(kicad_pcb
	(version 20241229)
	(generator "pcbnew")
	(generator_version "9.0")
	(general
		(thickness 1.294)
		(legacy_teardrops no)
	)
	(paper "A3")
	(title_block
		(title "Kintex 410T devboard")
		(date "2024-04-03")
		(rev "1.1.2")
	)
	(layers
		(0 "F.Cu" mixed)
		(4 "In1.Cu" power)
		(6 "In2.Cu" power)
		(8 "In3.Cu" mixed)
		(10 "In4.Cu" power)
		(12 "In5.Cu" mixed)
		(14 "In6.Cu" power)
		(16 "In7.Cu" mixed)
		(18 "In8.Cu" power)
		(2 "B.Cu" mixed)
		(9 "F.Adhes" user "F.Adhesive")
		(11 "B.Adhes" user "B.Adhesive")
		(13 "F.Paste" user)
		(15 "B.Paste" user)
		(5 "F.SilkS" user "F.Silkscreen")
		(7 "B.SilkS" user "B.Silkscreen")
		(1 "F.Mask" user)
		(3 "B.Mask" user)
		(17 "Dwgs.User" user "User.Drawings")
		(19 "Cmts.User" user "User.Comments")
		(21 "Eco1.User" user "User.Eco1")
		(23 "Eco2.User" user "User.Eco2")
		(25 "Edge.Cuts" user)
		(27 "Margin" user)
		(31 "F.CrtYd" user "F.Courtyard")
		(29 "B.CrtYd" user "B.Courtyard")
		(35 "F.Fab" user)
		(33 "B.Fab" user)
	)
	(setup
		(stackup
			(layer "F.SilkS"
				(type "Top Silk Screen")
			)
			(layer "F.Paste"
				(type "Top Solder Paste")
			)
			(layer "F.Mask"
				(type "Top Solder Mask")
				(color "Black")
				(thickness 0.01)
			)
			(layer "F.Cu"
				(type "copper")
				(thickness 0.035)
			)
			(layer "dielectric 1"
				(type "prepreg")
				(thickness 0.12)
				(material "PR2116")
				(epsilon_r 3.9)
				(loss_tangent 0.0022)
			)
			(layer "In1.Cu"
				(type "copper")
				(thickness 0.018)
			)
			(layer "dielectric 2"
				(type "core")
				(thickness 0.1)
				(material "IS400")
				(epsilon_r 3.9)
				(loss_tangent 0.022)
			)
			(layer "In2.Cu"
				(type "copper")
				(thickness 0.018)
			)
			(layer "dielectric 3"
				(type "prepreg")
				(thickness 0.07)
				(material "PR1080")
				(epsilon_r 3.14)
				(loss_tangent 0.0022) addsublayer
				(thickness 0.07)
				(material "PR1080")
				(epsilon_r 3.14)
				(loss_tangent 0.0022)
			)
			(layer "In3.Cu"
				(type "copper")
				(thickness 0.018)
			)
			(layer "dielectric 4"
				(type "core")
				(thickness 0.1)
				(material "IS400")
				(epsilon_r 3.9)
				(loss_tangent 0.022)
			)
			(layer "In4.Cu"
				(type "copper")
				(thickness 0.018)
			)
			(layer "dielectric 5"
				(type "core")
				(thickness 0.07)
				(material "PR1080")
				(epsilon_r 3.14)
				(loss_tangent 0.0022) addsublayer
				(thickness 0.07)
				(material "PR1080")
				(epsilon_r 3.14)
				(loss_tangent 0.0022)
			)
			(layer "In5.Cu"
				(type "copper")
				(thickness 0.018)
			)
			(layer "dielectric 6"
				(type "prepreg")
				(thickness 0.1)
				(material "IS400")
				(epsilon_r 3.9)
				(loss_tangent 0.022)
			)
			(layer "In6.Cu"
				(type "copper")
				(thickness 0.018)
			)
			(layer "dielectric 7"
				(type "core")
				(thickness 0.07)
				(material "PR1080")
				(epsilon_r 3.14)
				(loss_tangent 0.0022) addsublayer
				(thickness 0.07)
				(material "PR1080")
				(epsilon_r 3.14)
				(loss_tangent 0.0022)
			)
			(layer "In7.Cu"
				(type "copper")
				(thickness 0.018)
			)
			(layer "dielectric 8"
				(type "prepreg")
				(thickness 0.1)
				(material "IS400")
				(epsilon_r 3.9)
				(loss_tangent 0.022)
			)
			(layer "In8.Cu"
				(type "copper")
				(thickness 0.018)
			)
			(layer "dielectric 9"
				(type "prepreg")
				(thickness 0.12)
				(material "PR2116")
				(epsilon_r 3.9)
				(loss_tangent 0.0022)
			)
			(layer "B.Cu"
				(type "copper")
				(thickness 0.035)
			)
			(layer "B.Mask"
				(type "Bottom Solder Mask")
				(color "Black")
				(thickness 0.01)
			)
			(layer "B.Paste"
				(type "Bottom Solder Paste")
			)
			(layer "B.SilkS"
				(type "Bottom Silk Screen")
			)
			(copper_finish "None")
			(dielectric_constraints yes)
		)
		(pad_to_mask_clearance 0)
		(allow_soldermask_bridges_in_footprints no)
		(tenting front back)
		(aux_axis_origin 150 190)
		(pcbplotparams
			(layerselection 0x00000000_00000000_55555555_5755f5ff)
			(plot_on_all_layers_selection 0x00000000_00000000_00000000_00000000)
			(disableapertmacros no)
			(usegerberextensions no)
			(usegerberattributes yes)
			(usegerberadvancedattributes yes)
			(creategerberjobfile yes)
			(dashed_line_dash_ratio 12.000000)
			(dashed_line_gap_ratio 3.000000)
			(svgprecision 6)
			(plotframeref no)
			(mode 1)
			(useauxorigin no)
			(hpglpennumber 1)
			(hpglpenspeed 20)
			(hpglpendiameter 15.000000)
			(pdf_front_fp_property_popups yes)
			(pdf_back_fp_property_popups yes)
			(pdf_metadata yes)
			(pdf_single_document no)
			(dxfpolygonmode yes)
			(dxfimperialunits yes)
			(dxfusepcbnewfont yes)
			(psnegative no)
			(psa4output no)
			(plot_black_and_white yes)
			(sketchpadsonfab no)
			(plotpadnumbers no)
			(hidednponfab no)
			(sketchdnponfab yes)
			(crossoutdnponfab yes)
			(subtractmaskfromsilk no)
			(outputformat 1)
			(mirror no)
			(drillshape 1)
			(scaleselection 1)
			(outputdirectory "")
		)
	)
	(net 0 "")
	(net 1 "GND")
	(net 2 "VCC_USR_A")
	(net 3 "VCC_USR_B")
	(net 4 "/Power supply/DC_IN")
	(net 5 "/Power supply/PD_VBUS")
	(net 6 "+1V0_MGTAVCC")
	(net 7 "+0V675_VTT")
	(net 8 "+1V2_MGTAVTT")
	(net 9 "/FPGA Config/FPGA_CFG_DXN")
	(net 10 "/FPGA Config/FPGA_CFG_DXP")
	(net 11 "+0V675_VREF")
	(net 12 "Net-(J15A-TRDCT1{slash}2{slash}3{slash}4_1)")
	(net 13 "/USER_IO.BUTTON1")
	(net 14 "/DC-DC Converters/SEQ_EN")
	(net 15 "Net-(U41-OUT)")
	(net 16 "Net-(J23-SHIELD)")
	(net 17 "Net-(D1-C)")
	(net 18 "Net-(D9-A)")
	(net 19 "Net-(D11-A)")
	(net 20 "Net-(D13-A)")
	(net 21 "Net-(D19-C)")
	(net 22 "Net-(D20-C)")
	(net 23 "Net-(D21-C)")
	(net 24 "+3V3")
	(net 25 "+1V35")
	(net 26 "+1V8")
	(net 27 "Net-(D22-C)")
	(net 28 "unconnected-(J4-Pin_3-Pad3)")
	(net 29 "Net-(J4-Pin_4)")
	(net 30 "unconnected-(J7-Pin_3-Pad3)")
	(net 31 "unconnected-(J8-Pin_3-Pad3)")
	(net 32 "unconnected-(J13-SBU_{1}-PadA8)")
	(net 33 "unconnected-(J13-SBU_{2}-PadB8)")
	(net 34 "unconnected-(J14-SBU_{1}-PadA8)")
	(net 35 "unconnected-(J14-SBU_{2}-PadB8)")
	(net 36 "unconnected-(J15A-TRD3-_1-Pad5_1)")
	(net 37 "+3V3_AON")
	(net 38 "/FPGA Bank 14 & 15/SYSTEM_FLASH.DQ0")
	(net 39 "unconnected-(J15A-TRD3+_1-Pad6_1)")
	(net 40 "unconnected-(J15A-TRD4-_1-Pad7_1)")
	(net 41 "unconnected-(J15A-TRD4+_1-Pad8_1)")
	(net 42 "unconnected-(J16-CEC-Pad13)")
	(net 43 "/FPGA Bank 14 & 15/SYSTEM_FLASH.DQ1")
	(net 44 "unconnected-(J16-UTILITY{slash}HEAC+-Pad14)")
	(net 45 "/FPGA Bank 12 & 13/UART1.RX")
	(net 46 "/FPGA Bank 12 & 13/UART0.RX")
	(net 47 "unconnected-(J16-SCL-Pad15)")
	(net 48 "unconnected-(J16-SDA-Pad16)")
	(net 49 "unconnected-(J16-HPD{slash}HEAC--Pad19)")
	(net 50 "unconnected-(J18H-DP9_M2C_P-PadB04)")
	(net 51 "unconnected-(J18H-DP9_M2C_N-PadB05)")
	(net 52 "unconnected-(J18H-DP8_M2C_P-PadB08)")
	(net 53 "unconnected-(J18H-DP8_M2C_N-PadB09)")
	(net 54 "/FPGA Bank 12 & 13/UART1.TX")
	(net 55 "/FPGA Bank 12 & 13/UART0.TX")
	(net 56 "/FPGA Bank 14 & 15/SYSTEM_FLASH.CLK")
	(net 57 "unconnected-(J18H-DP9_C2M_P-PadB24)")
	(net 58 "unconnected-(J18H-DP9_C2M_N-PadB25)")
	(net 59 "12P0V")
	(net 60 "/FMC+ HSPC/GTX_TX0_C_P")
	(net 61 "/FMC+ HSPC/GTX116.TX3_P")
	(net 62 "/FMC+ HSPC/GTX_TX0_C_N")
	(net 63 "/FMC+ HSPC/GTX116.TX3_N")
	(net 64 "/FMC+ HSPC/GTX_TX1_C_P")
	(net 65 "/FMC+ HSPC/GTX116.TX2_P")
	(net 66 "unconnected-(J18H-DP8_C2M_P-PadB28)")
	(net 67 "/FMC+ HSPC/GTX_TX1_C_N")
	(net 68 "unconnected-(J18H-DP8_C2M_N-PadB29)")
	(net 69 "/FMC+ HSPC/GTX116.TX2_N")
	(net 70 "unconnected-(J18A-RES0-PadB40)")
	(net 71 "/FMC+ HSPC/GTX_TX2_C_P")
	(net 72 "unconnected-(J18C-LA06_P-PadC10)")
	(net 73 "/FMC+ HSPC/GTX116.TX1_P")
	(net 74 "/SPI Flash + SD Card/SD_CARD_~{CD}")
	(net 75 "/FPGA Bank 14 & 15/SYSTEM_FLASH.~{CS}")
	(net 76 "/FMC+ HSPC/GTX_TX2_C_N")
	(net 77 "unconnected-(J18C-LA06_N-PadC11)")
	(net 78 "/FMC+ HSPC/GTX116.TX1_N")
	(net 79 "/FMC+ HSPC/GTX_TX3_C_P")
	(net 80 "/FMC+ HSPC/GTX116.TX0_P")
	(net 81 "/FMC+ HSPC/GTX_TX3_C_N")
	(net 82 "/FMC+ HSPC/GTX116.TX0_N")
	(net 83 "/FMC+ HSPC/GTX_TX4_C_P")
	(net 84 "unconnected-(J18C-LA10_P-PadC14)")
	(net 85 "unconnected-(J18C-LA10_N-PadC15)")
	(net 86 "unconnected-(J18C-LA14_P-PadC18)")
	(net 87 "/FMC+ HSPC/GTX115.TX3_P")
	(net 88 "/FMC+ HSPC/GTX_TX4_C_N")
	(net 89 "/FMC+ HSPC/GTX115.TX3_N")
	(net 90 "unconnected-(J18C-LA14_N-PadC19)")
	(net 91 "unconnected-(J18C-LA18_P_CC-PadC22)")
	(net 92 "unconnected-(J18C-LA18_N_CC-PadC23)")
	(net 93 "unconnected-(J18C-LA27_P-PadC26)")
	(net 94 "unconnected-(J18C-LA27_N-PadC27)")
	(net 95 "unconnected-(J18B-GA0-PadC34)")
	(net 96 "/FMC+ HSPC/GTX_TX5_C_P")
	(net 97 "/FMC+ HSPC/GTX115.TX2_P")
	(net 98 "/FMC+ HSPC/GTX_TX5_C_N")
	(net 99 "Net-(J18B-PG_C2M)")
	(net 100 "unconnected-(J18C-LA01_N_CC-PadD09)")
	(net 101 "/FMC+ HSPC/GTX115.TX2_N")
	(net 102 "unconnected-(J18C-LA05_P-PadD11)")
	(net 103 "unconnected-(J18C-LA05_N-PadD12)")
	(net 104 "unconnected-(J18C-LA09_P-PadD14)")
	(net 105 "/FMC+ HSPC/GTX_TX6_C_P")
	(net 106 "unconnected-(J18C-LA09_N-PadD15)")
	(net 107 "/FMC+ HSPC/GTX115.TX1_P")
	(net 108 "unconnected-(J18C-LA13_P-PadD17)")
	(net 109 "/FMC+ HSPC/GTX_TX6_C_N")
	(net 110 "unconnected-(J18C-LA13_N-PadD18)")
	(net 111 "/Supervisior MCU/FAN_PWM")
	(net 112 "/Supervisior MCU/SAM_FPGA_CCLK")
	(net 113 "/FPGA Config/TEMP_~{ALERT}")
	(net 114 "unconnected-(J18C-LA17_P_CC-PadD20)")
	(net 115 "/FMC+ HSPC/GTX115.TX1_N")
	(net 116 "unconnected-(J18C-LA17_N_CC-PadD21)")
	(net 117 "unconnected-(J18C-LA23_P-PadD23)")
	(net 118 "unconnected-(J18C-LA23_N-PadD24)")
	(net 119 "/FMC+ HSPC/GTX_TX7_C_P")
	(net 120 "unconnected-(J18C-LA26_P-PadD26)")
	(net 121 "unconnected-(J18C-LA26_N-PadD27)")
	(net 122 "/FMC+ HSPC/GTX115.TX0_P")
	(net 123 "/FMC+ HSPC/GTX_TX7_C_N")
	(net 124 "/FMC+ HSPC/GTX115.TX0_N")
	(net 125 "unconnected-(J18A-3P3VAUX-PadD32)")
	(net 126 "unconnected-(J18B-GA1-PadD35)")
	(net 127 "unconnected-(J18D-HA01_P_CC-PadE02)")
	(net 128 "unconnected-(J18D-HA01_N_CC-PadE03)")
	(net 129 "unconnected-(J18D-HA05_P-PadE06)")
	(net 130 "unconnected-(J18D-HA05_N-PadE07)")
	(net 131 "unconnected-(J18D-HA09_P-PadE09)")
	(net 132 "unconnected-(J18D-HA09_N-PadE10)")
	(net 133 "unconnected-(J18D-HA13_P-PadE12)")
	(net 134 "unconnected-(J18D-HA13_N-PadE13)")
	(net 135 "unconnected-(J18D-HA16_P-PadE15)")
	(net 136 "unconnected-(J18D-HA16_N-PadE16)")
	(net 137 "unconnected-(J18D-HA20_P-PadE18)")
	(net 138 "unconnected-(J18D-HA20_N-PadE19)")
	(net 139 "unconnected-(J18E-HB03_P-PadE21)")
	(net 140 "unconnected-(J18E-HB03_N-PadE22)")
	(net 141 "unconnected-(J18E-HB05_P-PadE24)")
	(net 142 "unconnected-(J18E-HB05_N-PadE25)")
	(net 143 "/Power supply/VREG_1V2")
	(net 144 "unconnected-(J18E-HB09_P-PadE27)")
	(net 145 "unconnected-(J18E-HB09_N-PadE28)")
	(net 146 "unconnected-(J18E-HB13_P-PadE30)")
	(net 147 "unconnected-(J18E-HB13_N-PadE31)")
	(net 148 "unconnected-(J18E-HB19_P-PadE33)")
	(net 149 "unconnected-(J18E-HB19_N-PadE34)")
	(net 150 "unconnected-(J18E-HB21_P-PadE36)")
	(net 151 "unconnected-(J18E-HB21_N-PadE37)")
	(net 152 "unconnected-(J18A-VADJ-PadE39)")
	(net 153 "Net-(J18B-PG_M2C)")
	(net 154 "unconnected-(J18D-HA00_P_CC-PadF04)")
	(net 155 "unconnected-(J18D-HA00_N_CC-PadF05)")
	(net 156 "unconnected-(J18D-HA04_P-PadF07)")
	(net 157 "unconnected-(J18D-HA04_N-PadF08)")
	(net 158 "unconnected-(J18D-HA08_P-PadF10)")
	(net 159 "unconnected-(J18D-HA08_N-PadF11)")
	(net 160 "unconnected-(J18D-HA12_P-PadF13)")
	(net 161 "/FPGA Config/JTAG.TMS")
	(net 162 "unconnected-(J18D-HA12_N-PadF14)")
	(net 163 "unconnected-(J18D-HA15_P-PadF16)")
	(net 164 "unconnected-(J18D-HA15_N-PadF17)")
	(net 165 "/FPGA Config/JTAG.TCK")
	(net 166 "unconnected-(J18D-HA19_P-PadF19)")
	(net 167 "unconnected-(J18D-HA19_N-PadF20)")
	(net 168 "unconnected-(J18E-HB02_P-PadF22)")
	(net 169 "unconnected-(J18E-HB02_N-PadF23)")
	(net 170 "unconnected-(J18E-HB04_P-PadF25)")
	(net 171 "unconnected-(J18E-HB04_N-PadF26)")
	(net 172 "unconnected-(J18E-HB08_P-PadF28)")
	(net 173 "unconnected-(J18E-HB08_N-PadF29)")
	(net 174 "unconnected-(J18E-HB12_P-PadF31)")
	(net 175 "unconnected-(J18E-HB12_N-PadF32)")
	(net 176 "unconnected-(J18E-HB16_P-PadF34)")
	(net 177 "unconnected-(J18E-HB16_N-PadF35)")
	(net 178 "unconnected-(J18E-HB20_P-PadF37)")
	(net 179 "unconnected-(J18E-HB20_N-PadF38)")
	(net 180 "unconnected-(J18F-CLK1_M2C_P-PadG02)")
	(net 181 "unconnected-(J18F-CLK1_M2C_N-PadG03)")
	(net 182 "unconnected-(J18C-LA00_P_CC-PadG06)")
	(net 183 "unconnected-(J18C-LA00_N_CC-PadG07)")
	(net 184 "unconnected-(J18C-LA03_P-PadG09)")
	(net 185 "unconnected-(J18C-LA03_N-PadG10)")
	(net 186 "unconnected-(J18C-LA08_P-PadG12)")
	(net 187 "unconnected-(J18C-LA08_N-PadG13)")
	(net 188 "unconnected-(J18C-LA12_P-PadG15)")
	(net 189 "unconnected-(J18C-LA12_N-PadG16)")
	(net 190 "/FPGA Config/JTAG.TDO")
	(net 191 "unconnected-(J18C-LA31_N-PadG34)")
	(net 192 "unconnected-(J18C-LA33_P-PadG36)")
	(net 193 "unconnected-(J18C-LA33_N-PadG37)")
	(net 194 "Net-(J18A-VREF_A_M2C)")
	(net 195 "unconnected-(J18F-CLK0_M2C_P-PadH04)")
	(net 196 "unconnected-(J18F-CLK0_M2C_N-PadH05)")
	(net 197 "unconnected-(J18C-LA02_P-PadH07)")
	(net 198 "unconnected-(J18C-LA02_N-PadH08)")
	(net 199 "unconnected-(J18C-LA04_P-PadH10)")
	(net 200 "unconnected-(J18C-LA04_N-PadH11)")
	(net 201 "unconnected-(J18C-LA07_P-PadH13)")
	(net 202 "unconnected-(J18C-LA07_N-PadH14)")
	(net 203 "unconnected-(J18C-LA30_P-PadH34)")
	(net 204 "unconnected-(J18C-LA30_N-PadH35)")
	(net 205 "unconnected-(J18C-LA32_P-PadH37)")
	(net 206 "unconnected-(J18C-LA32_N-PadH38)")
	(net 207 "unconnected-(J18D-HA14_P-PadJ15)")
	(net 208 "unconnected-(J18D-HA14_N-PadJ16)")
	(net 209 "unconnected-(J18E-HB11_P-PadJ30)")
	(net 210 "unconnected-(J18E-HB11_N-PadJ31)")
	(net 211 "unconnected-(J18E-HB15_P-PadJ33)")
	(net 212 "unconnected-(J18E-HB15_N-PadJ34)")
	(net 213 "unconnected-(J18E-HB18_P-PadJ36)")
	(net 214 "unconnected-(J18E-HB18_N-PadJ37)")
	(net 215 "unconnected-(J18A-VIO_B_M2C-PadJ39)")
	(net 216 "Net-(J18A-VREF_B_M2C)")
	(net 217 "unconnected-(J18D-HA10_P-PadK13)")
	(net 218 "unconnected-(J18D-HA10_N-PadK14)")
	(net 219 "unconnected-(J18E-HB06_N_CC-PadK29)")
	(net 220 "/FPGA Config/JTAG.TDI")
	(net 221 "unconnected-(J18E-HB10_P-PadK31)")
	(net 222 "unconnected-(J18E-HB10_N-PadK32)")
	(net 223 "unconnected-(J18E-HB14_P-PadK34)")
	(net 224 "unconnected-(J18E-HB14_N-PadK35)")
	(net 225 "unconnected-(J18E-HB17_P_CC-PadK37)")
	(net 226 "unconnected-(J18E-HB17_N_CC-PadK38)")
	(net 227 "unconnected-(J18A-RES1-PadL01)")
	(net 228 "unconnected-(J18G-GBTCLK4_M2C_P-PadL04)")
	(net 229 "unconnected-(J18G-GBTCLK4_M2C_N-PadL05)")
	(net 230 "unconnected-(J18G-GBTCLK3_M2C_P-PadL08)")
	(net 231 "unconnected-(J18G-GBTCLK3_M2C_N-PadL09)")
	(net 232 "unconnected-(J18G-GBTCLK2_M2C_P-PadL12)")
	(net 233 "unconnected-(J18G-GBTCLK2_M2C_N-PadL13)")
	(net 234 "unconnected-(J18G-SYNC_C2M_P-PadL16)")
	(net 235 "unconnected-(J18G-SYNC_C2M_N-PadL17)")
	(net 236 "unconnected-(J18G-REFCLK_C2M_P-PadL20)")
	(net 237 "unconnected-(J18G-REFCLK_C2M_N-PadL21)")
	(net 238 "unconnected-(J18G-REFCLK_M2C_P-PadL24)")
	(net 239 "/FMC+ HSPC/FMC.IO21_P")
	(net 240 "unconnected-(J18G-REFCLK_M2C_N-PadL25)")
	(net 241 "/FMC+ HSPC/FMC.IO18_N")
	(net 242 "unconnected-(J18G-SYNC_M2C_P-PadL28)")
	(net 243 "unconnected-(J18G-SYNC_M2C_N-PadL29)")
	(net 244 "unconnected-(J18A-RES2-PadL32)")
	(net 245 "unconnected-(J18A-RES3-PadL33)")
	(net 246 "/FPGA Config/DONE")
	(net 247 "unconnected-(J18H-DP23_M2C_P-PadM02)")
	(net 248 "unconnected-(J18H-DP23_M2C_N-PadM03)")
	(net 249 "/FMC+ HSPC/GTX116.RX0_P")
	(net 250 "/Supervisior MCU/CFG_DONE")
	(net 251 "unconnected-(J18H-DP22_M2C_P-PadM06)")
	(net 252 "unconnected-(J18H-DP22_M2C_N-PadM07)")
	(net 253 "unconnected-(J18H-DP21_M2C_P-PadM10)")
	(net 254 "/FMC+ HSPC/FMC.IO18_P")
	(net 255 "unconnected-(J18H-DP21_M2C_N-PadM11)")
	(net 256 "unconnected-(J18H-DP20_M2C_P-PadM14)")
	(net 257 "/FPGA Config/INIT_B")
	(net 258 "unconnected-(J18H-DP20_M2C_N-PadM15)")
	(net 259 "unconnected-(J18H-DP14_C2M_P-PadM18)")
	(net 260 "/Supervisior MCU/FPGA_CFG_CS")
	(net 261 "unconnected-(J18H-DP14_C2M_N-PadM19)")
	(net 262 "unconnected-(J18H-DP15_C2M_P-PadM22)")
	(net 263 "unconnected-(J18H-DP15_C2M_N-PadM23)")
	(net 264 "unconnected-(J18H-DP16_C2M_P-PadM26)")
	(net 265 "/Supervisior MCU/PWR_ON")
	(net 266 "unconnected-(J18H-DP16_C2M_N-PadM27)")
	(net 267 "/Power supply/VREG_2V7")
	(net 268 "/FMC+ HSPC/FMC.IO16_N")
	(net 269 "unconnected-(J18H-DP17_C2M_P-PadM30)")
	(net 270 "unconnected-(J18H-DP17_C2M_N-PadM31)")
	(net 271 "unconnected-(J18H-DP18_C2M_P-PadM34)")
	(net 272 "unconnected-(J18H-DP18_C2M_N-PadM35)")
	(net 273 "unconnected-(J18H-DP19_C2M_P-PadM38)")
	(net 274 "unconnected-(J18H-DP19_C2M_N-PadM39)")
	(net 275 "unconnected-(J18H-DP23_C2M_P-PadY02)")
	(net 276 "/Supervisior MCU/SW_STATE")
	(net 277 "unconnected-(J18H-DP23_C2M_N-PadY03)")
	(net 278 "/FMC+ HSPC/FMC.IO16_P")
	(net 279 "/DC-DC Converters/PB_CTRL.~{PB_CTRL_CLR}")
	(net 280 "unconnected-(J18H-DP21_C2M_P-PadY06)")
	(net 281 "unconnected-(J18H-DP21_C2M_N-PadY07)")
	(net 282 "/FMC+ HSPC/GTX116.RX3_N")
	(net 283 "/FMC+ HSPC/GTX116.RX1_N")
	(net 284 "unconnected-(J18H-DP10_M2C_P-PadY10)")
	(net 285 "unconnected-(J18H-DP10_M2C_N-PadY11)")
	(net 286 "unconnected-(J18H-DP12_M2C_P-PadY14)")
	(net 287 "/FMC+ HSPC/GTX116.RX3_P")
	(net 288 "/FMC+ HSPC/GTX116.RX1_P")
	(net 289 "unconnected-(J18H-DP12_M2C_N-PadY15)")
	(net 290 "unconnected-(J18H-DP14_M2C_P-PadY18)")
	(net 291 "unconnected-(J18H-DP14_M2C_N-PadY19)")
	(net 292 "unconnected-(J18H-DP15_M2C_P-PadY22)")
	(net 293 "unconnected-(J18H-DP15_M2C_N-PadY23)")
	(net 294 "unconnected-(J18H-DP11_C2M_P-PadY26)")
	(net 295 "unconnected-(J18H-DP11_C2M_N-PadY27)")
	(net 296 "unconnected-(J18H-DP13_C2M_P-PadY30)")
	(net 297 "unconnected-(J18H-DP13_C2M_N-PadY31)")
	(net 298 "/FPGA Config/MODE2")
	(net 299 "/FPGA Config/MODE1")
	(net 300 "/FPGA Config/MODE0")
	(net 301 "/FPGA Config/PROGRAM_B")
	(net 302 "unconnected-(J18H-DP17_M2C_P-PadY34)")
	(net 303 "unconnected-(J18H-DP17_M2C_N-PadY35)")
	(net 304 "unconnected-(J18H-DP19_M2C_P-PadY38)")
	(net 305 "unconnected-(J18H-DP19_M2C_N-PadY39)")
	(net 306 "unconnected-(J18B-HSPC_PRSNT_M2C_L-PadZ01)")
	(net 307 "/FMC+ HSPC/GTX116.RX2_N")
	(net 308 "unconnected-(J18H-DP22_C2M_P-PadZ04)")
	(net 309 "unconnected-(J18H-DP22_C2M_N-PadZ05)")
	(net 310 "unconnected-(J18H-DP20_C2M_P-PadZ08)")
	(net 311 "unconnected-(J18H-DP20_C2M_N-PadZ09)")
	(net 312 "/FMC+ HSPC/GTX116.RX2_P")
	(net 313 "unconnected-(J18H-DP11_M2C_P-PadZ12)")
	(net 314 "unconnected-(J18H-DP11_M2C_N-PadZ13)")
	(net 315 "unconnected-(J18H-DP13_M2C_P-PadZ16)")
	(net 316 "unconnected-(J18H-DP13_M2C_N-PadZ17)")
	(net 317 "unconnected-(J18G-GBTCLK5_M2C_P-PadZ20)")
	(net 318 "unconnected-(J18G-GBTCLK5_M2C_N-PadZ21)")
	(net 319 "unconnected-(J18H-DP10_C2M_P-PadZ24)")
	(net 320 "unconnected-(J18H-DP10_C2M_N-PadZ25)")
	(net 321 "unconnected-(J18H-DP12_C2M_P-PadZ28)")
	(net 322 "unconnected-(J18H-DP12_C2M_N-PadZ29)")
	(net 323 "unconnected-(J18H-DP16_M2C_P-PadZ32)")
	(net 324 "unconnected-(J18H-DP16_M2C_N-PadZ33)")
	(net 325 "unconnected-(J18H-DP18_M2C_P-PadZ36)")
	(net 326 "unconnected-(J18H-DP18_M2C_N-PadZ37)")
	(net 327 "Net-(J23-DAT2)")
	(net 328 "Net-(J23-DAT3{slash}CD)")
	(net 329 "Net-(J23-CMD)")
	(net 330 "Net-(J23-CLK)")
	(net 331 "Net-(J23-DAT0)")
	(net 332 "Net-(J23-DAT1)")
	(net 333 "Net-(Q1-D)")
	(net 334 "/FMC+ HSPC/FMC.IO25")
	(net 335 "/FMC+ HSPC/FMC.IO20_N")
	(net 336 "Net-(Q2-D)")
	(net 337 "/FMC+ HSPC/FMC.IO20_P")
	(net 338 "Net-(Q5-G)")
	(net 339 "/FMC+ HSPC/FMC.IO11_N")
	(net 340 "/FMC+ HSPC/FMC.IO11_P")
	(net 341 "Net-(Q6-G)")
	(net 342 "Net-(Q7-G)")
	(net 343 "Net-(Q17-G)")
	(net 344 "Net-(Q18-D)")
	(net 345 "Net-(U3-STBY)")
	(net 346 "unconnected-(R20-R1.1-Pad1)")
	(net 347 "unconnected-(R20-R1.2-Pad8)")
	(net 348 "unconnected-(R22-R3.1-Pad3)")
	(net 349 "/FMC+ HSPC/FMC.IO24_N")
	(net 350 "/FMC+ HSPC/FMC.IO24_P")
	(net 351 "/FMC+ HSPC/FMC.IO14_N")
	(net 352 "/FMC+ HSPC/FMC.IO14_P")
	(net 353 "/FMC+ HSPC/FMC.IO12_N")
	(net 354 "/FMC+ HSPC/FMC.IO12_P")
	(net 355 "unconnected-(R24-R1.1-Pad1)")
	(net 356 "unconnected-(R24-R1.2-Pad8)")
	(net 357 "unconnected-(R25-R1.2-Pad8)")
	(net 358 "unconnected-(R28-R1.1-Pad1)")
	(net 359 "unconnected-(R28-R2.1-Pad2)")
	(net 360 "unconnected-(R28-R2.2-Pad7)")
	(net 361 "unconnected-(R28-R1.2-Pad8)")
	(net 362 "Net-(U6-VBUS_EN_SNK)")
	(net 363 "unconnected-(R61-R4.1-Pad4)")
	(net 364 "unconnected-(R61-R4.2-Pad5)")
	(net 365 "Net-(U8-TRIM)")
	(net 366 "unconnected-(R63-R2.1-Pad2)")
	(net 367 "unconnected-(R63-R2.2-Pad7)")
	(net 368 "Net-(U22-B1Y)")
	(net 369 "Net-(U22-B2Y)")
	(net 370 "Net-(U22-B3Y)")
	(net 371 "Net-(U22-B4)")
	(net 372 "Net-(U23-OE)")
	(net 373 "/FMC+ HSPC/FMC.IO0")
	(net 374 "Net-(U23-B1Y)")
	(net 375 "Net-(U23-B2Y)")
	(net 376 "Net-(U23-B3Y)")
	(net 377 "/FMC+ HSPC/FMC.IO9_N")
	(net 378 "Net-(U23-B4)")
	(net 379 "Net-(U24-OE)")
	(net 380 "FMC.SDA_3V3")
	(net 381 "/FMC+ HSPC/FMC.IO9_P")
	(net 382 "Net-(U30-ISET)")
	(net 383 "FMC.SCL_3V3")
	(net 384 "/FMC+ HSPC/FMC.IO7_N")
	(net 385 "Net-(U43-EN)")
	(net 386 "Net-(U43-FLG)")
	(net 387 "/FMC+ HSPC/FMC.IO7_P")
	(net 388 "/FMC+ HSPC/FMC.IO8_N")
	(net 389 "Net-(U43-ISET)")
	(net 390 "/FPGA Bank 33 & 34/SD_CARD.DAT2")
	(net 391 "/FPGA Bank 33 & 34/SD_CARD.DAT3")
	(net 392 "/FMC+ HSPC/FMC.IO8_P")
	(net 393 "/FPGA Bank 33 & 34/SD_CARD.CMD")
	(net 394 "/FPGA Bank 33 & 34/SD_CARD.CLK")
	(net 395 "/FPGA Bank 33 & 34/SD_CARD.DAT0")
	(net 396 "/FMC+ HSPC/FMC.IO10_N")
	(net 397 "/FPGA Bank 33 & 34/SD_CARD.DAT1")
	(net 398 "/FPGA Bank 14 & 15/SYSTEM_FLASH.DQ3")
	(net 399 "unconnected-(U1E-IO_L1N_T0_33-PadAB12)")
	(net 400 "/FMC+ HSPC/FMC.IO10_P")
	(net 401 "/FMC+ HSPC/FMC.IO6_N")
	(net 402 "/FPGA Bank 33 & 34/USR_FLASH_0.DQ3")
	(net 403 "/FPGA Bank 14 & 15/SYSTEM_FLASH.DQ2")
	(net 404 "/FPGA Bank 33 & 34/USR_FLASH_0.DQ2")
	(net 405 "/FMC+ HSPC/FMC.IO6_P")
	(net 406 "unconnected-(U1E-IO_L9P_T1_DQS_33-PadAC12)")
	(net 407 "/FPGA Bank 33 & 34/USR_FLASH_0.~{CS}")
	(net 408 "/FPGA Bank 33 & 34/USR_FLASH_0.CLK")
	(net 409 "/FMC+ HSPC/FMC.IO19_N")
	(net 410 "/FPGA Bank 33 & 34/USR_FLASH_0.DQ0")
	(net 411 "/FPGA Bank 33 & 34/USR_FLASH_0.DQ1")
	(net 412 "unconnected-(U1E-IO_L8P_T1_33-PadAD8)")
	(net 413 "/FMC+ HSPC/FMC.IO19_P")
	(net 414 "/FMC+ HSPC/FMC.IO1_N")
	(net 415 "unconnected-(U1E-IO_25_VRP_33-PadAD13)")
	(net 416 "/FPGA Bank 33 & 34/SD_CARD.~{CD}")
	(net 417 "/FPGA Bank 16 & 17/USR_FLASH_1.DQ3")
	(net 418 "/FMC+ HSPC/FMC.IO1_P")
	(net 419 "/FPGA Bank 16 & 17/USR_FLASH_1.DQ2")
	(net 420 "/FPGA Bank 16 & 17/USR_FLASH_1.~{CS}")
	(net 421 "unconnected-(U1E-IO_L8N_T1_33-PadAE8)")
	(net 422 "unconnected-(U1E-IO_L14P_T2_SRCC_33-PadAE10)")
	(net 423 "/FMC+ HSPC/FMC.IO13_N")
	(net 424 "/FMC+ HSPC/FMC.IO13_P")
	(net 425 "unconnected-(U1E-IO_L11P_T1_SRCC_33-PadAE11)")
	(net 426 "/FMC+ HSPC/FMC.IO17_N")
	(net 427 "/FPGA Bank 16 & 17/USR_FLASH_1.CLK")
	(net 428 "/FMC+ HSPC/FMC.IO17_P")
	(net 429 "/FPGA Bank 16 & 17/USR_FLASH_1.DQ0")
	(net 430 "/FPGA Bank 16 & 17/USR_FLASH_1.DQ1")
	(net 431 "/FPGA Config/JTAG.RST")
	(net 432 "/FPGA Bank 12 & 13/FAN_PWM_CTRL")
	(net 433 "/FPGA Bank 12 & 13/PMOD_A.IO7")
	(net 434 "/FPGA Bank 12 & 13/PMOD_A.IO8")
	(net 435 "unconnected-(U1E-IO_L14N_T2_SRCC_33-PadAF10)")
	(net 436 "unconnected-(U1E-IO_L23P_T3_33-PadAF12)")
	(net 437 "/FMC+ HSPC/FMC.IO21_N")
	(net 438 "/FPGA Bank 12 & 13/PMOD_A.IO9")
	(net 439 "/FPGA Bank 12 & 13/PMOD_A.IO10")
	(net 440 "/FMC+ HSPC/FMC.IO5_N")
	(net 441 "/FMC+ HSPC/FMC.IO5_P")
	(net 442 "/FPGA Bank 12 & 13/PMOD_B.IO7")
	(net 443 "unconnected-(U1E-IO_L16P_T2_33-PadAG9)")
	(net 444 "/FMC+ HSPC/FMC.IO23_N")
	(net 445 "/FMC+ HSPC/FMC.IO23_P")
	(net 446 "/FMC+ HSPC/FMC.IO3_N")
	(net 447 "unconnected-(U1E-IO_L13P_T2_MRCC_33-PadAG10)")
	(net 448 "unconnected-(U1E-IO_L23N_T3_33-PadAG12)")
	(net 449 "/FMC+ HSPC/FMC.IO3_P")
	(net 450 "/FMC+ HSPC/FMC.IO2_N")
	(net 451 "/FPGA Bank 12 & 13/PMOD_B.IO8")
	(net 452 "/FPGA Bank 12 & 13/PMOD_B.IO9")
	(net 453 "/FPGA Bank 12 & 13/PMOD_B.IO10")
	(net 454 "/FMC+ HSPC/GTX115.RX2_N")
	(net 455 "/FMC+ HSPC/FMC.IO2_P")
	(net 456 "/FPGA Bank 12 & 13/PMOD_A.IO1")
	(net 457 "/FPGA Bank 12 & 13/PMOD_A.IO2")
	(net 458 "/FPGA Bank 12 & 13/PMOD_A.IO3")
	(net 459 "/FMC+ HSPC/GTX115.RX2_P")
	(net 460 "/FMC+ HSPC/FMC.IO4_N")
	(net 461 "/FPGA Bank 12 & 13/PMOD_A.IO4")
	(net 462 "/FPGA Bank 12 & 13/PMOD_B.IO1")
	(net 463 "/FMC+ HSPC/GTX115.RX1_N")
	(net 464 "/FMC+ HSPC/FMC.IO4_P")
	(net 465 "unconnected-(U1E-IO_L16N_T2_33-PadAH9)")
	(net 466 "unconnected-(U1E-IO_L13N_T2_MRCC_33-PadAH10)")
	(net 467 "unconnected-(U1E-IO_L18P_T2_33-PadAH11)")
	(net 468 "/FMC+ HSPC/GTX115.RX1_P")
	(net 469 "unconnected-(U1E-IO_L21P_T3_DQS_33-PadAH14)")
	(net 470 "/FPGA Bank 12 & 13/PMOD_B.IO2")
	(net 471 "/FPGA Bank 12 & 13/PMOD_B.IO3")
	(net 472 "/FPGA Bank 12 & 13/PMOD_B.IO4")
	(net 473 "/FMC+ HSPC/GTX115.RX3_N")
	(net 474 "/FPGA Bank 12 & 13/CW_HEADER.RST")
	(net 475 "/FPGA Bank 12 & 13/CW_HEADER.MISO")
	(net 476 "/FPGA Bank 12 & 13/CW_HEADER.MOSI")
	(net 477 "/FPGA Bank 12 & 13/CW_HEADER.TSCK")
	(net 478 "/FMC+ HSPC/GTR_REFCLK1_R_N")
	(net 479 "/FMC+ HSPC/GTX115.RX3_P")
	(net 480 "/FPGA Bank 12 & 13/CW_HEADER.TPDIC")
	(net 481 "unconnected-(U1E-IO_L15P_T2_DQS_33-PadAJ9)")
	(net 482 "unconnected-(U1E-IO_L18N_T2_33-PadAJ11)")
	(net 483 "/FMC+ HSPC/GTX115.RX0_N")
	(net 484 "unconnected-(U1E-IO_L21N_T3_DQS_33-PadAJ14)")
	(net 485 "/FPGA Bank 12 & 13/CW_HEADER.TPDID")
	(net 486 "/FMC+ HSPC/GTX115.RX0_P")
	(net 487 "/FPGA Bank 12 & 13/CW_HEADER.HS1")
	(net 488 "/FPGA Bank 12 & 13/CW_HEADER.HS2")
	(net 489 "/FPGA Bank 12 & 13/CW_HEADER.IO1")
	(net 490 "/FMC+ HSPC/GTX116.RX0_N")
	(net 491 "/FPGA Bank 12 & 13/CW_HEADER.IO2")
	(net 492 "/FPGA Bank 12 & 13/CW_HEADER.IO3")
	(net 493 "/FPGA Bank 12 & 13/CW_HEADER.IO4")
	(net 494 "/FPGA supply/MGTRREF")
	(net 495 "/FPGA Bank 12 & 13/USB_HOST.INT")
	(net 496 "/FPGA Bank 12 & 13/USB_HOST.~{RESET}")
	(net 497 "/FPGA Bank 12 & 13/USB_USER.VDET")
	(net 498 "/FPGA Bank 12 & 13/USB_USER.~{OE}")
	(net 499 "/FMC+ HSPC/GTR_REFCLK1_R_P")
	(net 500 "/FPGA Bank 12 & 13/USB_USER.SUS")
	(net 501 "/FPGA Bank 18 & 32/ETH_RMII.~{RESET}")
	(net 502 "/FPGA Bank 18 & 32/ETH_RMII.MDIO")
	(net 503 "/FPGA Bank 16 & 17/GBE_RGMII.RXD3")
	(net 504 "/FPGA Bank 16 & 17/GBE_RGMII.RXD2")
	(net 505 "/FPGA Bank 16 & 17/GBE_RGMII.RXD1")
	(net 506 "/FPGA Bank 16 & 17/GBE_RGMII.RXD0")
	(net 507 "/FPGA Bank 16 & 17/GBE_RGMII.GTR_CLK")
	(net 508 "/FPGA Bank 16 & 17/GBE_RGMII.~{INT}")
	(net 509 "/FPGA Bank 16 & 17/GBE_RGMII.RX_DV")
	(net 510 "/FPGA Bank 16 & 17/GBE_RGMII.REFCLK")
	(net 511 "/FPGA Bank 18 & 32/ETH_RMII.TXEN")
	(net 512 "unconnected-(U1E-IO_L15N_T2_DQS_33-PadAK9)")
	(net 513 "/FPGA Bank 18 & 32/ETH_RMII.TXD0")
	(net 514 "/FMC+ HSPC/FMC.CLK_DIR")
	(net 515 "/FPGA Bank 18 & 32/ETH_RMII.TXD1")
	(net 516 "/FPGA Bank 18 & 32/ETH_RMII.REFCLK")
	(net 517 "/FPGA Bank 18 & 32/ETH_RMII.RX_DV")
	(net 518 "unconnected-(U1E-IO_L17N_T2_33-PadAK10)")
	(net 519 "/FPGA Bank 18 & 32/ETH_RMII.RXD0")
	(net 520 "/FPGA Bank 18 & 32/ETH_RMII.RXD1")
	(net 521 "/FPGA Bank 18 & 32/ETH_RMII.RXER")
	(net 522 "/FPGA Bank 16 & 17/GBE_RGMII.~{RESET}")
	(net 523 "/FPGA Bank 16 & 17/GBE_RGMII.MDIO")
	(net 524 "/FPGA Bank 16 & 17/HDMI.D2_P")
	(net 525 "/FPGA Bank 16 & 17/HDMI.D2_N")
	(net 526 "/FPGA Bank 16 & 17/HDMI.D1_P")
	(net 527 "/FPGA Bank 16 & 17/HDMI.D1_N")
	(net 528 "/FPGA Bank 16 & 17/HDMI.D0_P")
	(net 529 "/FPGA Bank 16 & 17/HDMI.D0_N")
	(net 530 "/FPGA Bank 16 & 17/HDMI.CLK_P")
	(net 531 "/DRAM + SRAM/DDR.A0")
	(net 532 "/DRAM + SRAM/DDR.A1")
	(net 533 "/DRAM + SRAM/DDR.A2")
	(net 534 "/DRAM + SRAM/DDR.A3")
	(net 535 "/DRAM + SRAM/DDR.A4")
	(net 536 "/DRAM + SRAM/DDR.A5")
	(net 537 "/DRAM + SRAM/DDR.A6")
	(net 538 "/DRAM + SRAM/DDR.A7")
	(net 539 "/DRAM + SRAM/DDR.A8")
	(net 540 "/DRAM + SRAM/DDR.A9")
	(net 541 "/DRAM + SRAM/DDR.A10")
	(net 542 "/DRAM + SRAM/DDR.A11")
	(net 543 "/DRAM + SRAM/DDR.A12")
	(net 544 "/DRAM + SRAM/DDR.A13")
	(net 545 "/DRAM + SRAM/DDR.A14")
	(net 546 "/DRAM + SRAM/DDR.A15")
	(net 547 "/DRAM + SRAM/DDR.BA0")
	(net 548 "/DRAM + SRAM/DDR.BA1")
	(net 549 "/DRAM + SRAM/DDR.BA2")
	(net 550 "/DRAM + SRAM/DDR.CKE")
	(net 551 "/DRAM + SRAM/DDR.CK_P")
	(net 552 "/DRAM + SRAM/DDR.CK_N")
	(net 553 "/DRAM + SRAM/DDR.ODT")
	(net 554 "/DRAM + SRAM/DDR.~{RESET}")
	(net 555 "/DRAM + SRAM/DDR_ZQ")
	(net 556 "/DRAM + SRAM/SRAM.~{CE}")
	(net 557 "/DRAM + SRAM/DDR.DM")
	(net 558 "/DRAM + SRAM/DDR.~{WE}")
	(net 559 "/DRAM + SRAM/DDR.~{CAS}")
	(net 560 "/DRAM + SRAM/DDR.~{RAS}")
	(net 561 "/DRAM + SRAM/DDR.~{CS}")
	(net 562 "/DRAM + SRAM/SRAM.CE2")
	(net 563 "/DRAM + SRAM/SRAM.~{WE}")
	(net 564 "/DRAM + SRAM/SRAM.~{OE}")
	(net 565 "/FPGA Bank 16 & 17/HDMI.CLK_N")
	(net 566 "/FPGA Bank 14 & 15/CFG_PUDC")
	(net 567 "/FPGA Bank 33 & 34/DDR_VRN")
	(net 568 "/FPGA Bank 33 & 34/DDR_VRP")
	(net 569 "/FPGA Bank 12 & 13/USB_HOST.VBUS_PEN")
	(net 570 "/FPGA Bank 12 & 13/USB_USER.VBUS_PEN")
	(net 571 "/FPGA Bank 12 & 13/~{PB_CTRL_CLR}")
	(net 572 "/FPGA Bank 12 & 13/~{PB_CTRL_INT}")
	(net 573 "unconnected-(U1G-MGTXTXN3_118-PadA3)")
	(net 574 "unconnected-(U1G-MGTXTXP3_118-PadA4)")
	(net 575 "unconnected-(U1G-MGTXRXN3_118-PadA7)")
	(net 576 "unconnected-(U1G-MGTXRXP3_118-PadA8)")
	(net 577 "/DC-DC Converters/PB_CTRL.~{PB_CTRL_INT}")
	(net 578 "/FPGA Bank 12 & 13/USB_HOST.CLK")
	(net 579 "/FPGA Bank 12 & 13/USB_HOST.MISO")
	(net 580 "/FPGA Bank 12 & 13/USB_HOST.GPX")
	(net 581 "unconnected-(U1C-IO_L21P_T3_DQS_17-PadA20)")
	(net 582 "unconnected-(U1C-IO_L21N_T3_DQS_17-PadA21)")
	(net 583 "/USB PHY/USB_HOST_VBUS_EN")
	(net 584 "/FPGA Bank 12 & 13/USB_USER.VP")
	(net 585 "unconnected-(U1D-IO_L23P_T3_32-PadAA17)")
	(net 586 "unconnected-(U1D-IO_25_VRP_32-PadAB14)")
	(net 587 "/FPGA Bank 12 & 13/USB_USER.RCV")
	(net 588 "unconnected-(U1D-IO_L18P_T2_32-PadAB17)")
	(net 589 "/FPGA Bank 18 & 32/ETH_RMII.MDC")
	(net 590 "unconnected-(U1D-IO_L17P_T2_32-PadAB19)")
	(net 591 "/FMC+ HSPC/GTX115.REFCLK1_P")
	(net 592 "/FMC+ HSPC/GTX115.REFCLK1_N")
	(net 593 "/FMC+ HSPC/GTR_REFCLK2_R_P")
	(net 594 "/FMC+ HSPC/GTX116.REFCLK0_P")
	(net 595 "/FMC+ HSPC/GTR_REFCLK2_R_N")
	(net 596 "/FMC+ HSPC/GTX116.REFCLK0_N")
	(net 597 "/FMC+ HSPC/GTR_REFCLK3_R_P")
	(net 598 "/FMC+ HSPC/GTX116.REFCLK1_P")
	(net 599 "/FMC+ HSPC/GTR_REFCLK3_R_N")
	(net 600 "/FMC+ HSPC/GTX116.REFCLK1_N")
	(net 601 "unconnected-(U1D-IO_L22P_T3_32-PadAC14)")
	(net 602 "unconnected-(U1D-IO_L21P_T3_DQS_32-PadAC16)")
	(net 603 "unconnected-(U1A-IO_L19P_T3_13-PadAC26)")
	(net 604 "unconnected-(U1A-IO_L12N_T1_MRCC_13-PadAC27)")
	(net 605 "unconnected-(U1D-IO_L14N_T2_SRCC_32-PadAD16)")
	(net 606 "unconnected-(U1D-IO_L14P_T2_SRCC_32-PadAD17)")
	(net 607 "unconnected-(U1D-IO_L10P_T1_32-PadAD19)")
	(net 608 "unconnected-(U1A-IO_L19N_T3_VREF_13-PadAD26)")
	(net 609 "unconnected-(U1D-IO_L19N_T3_VREF_32-PadAE14)")
	(net 610 "unconnected-(U1D-IO_L19P_T3_32-PadAE15)")
	(net 611 "unconnected-(U1D-IO_L6P_T0_32-PadAE16)")
	(net 612 "unconnected-(U1D-IO_L10N_T1_32-PadAE19)")
	(net 613 "unconnected-(U1A-IO_L9N_T1_DQS_13-PadAE29)")
	(net 614 "unconnected-(U1A-IO_L16P_T2_13-PadAE30)")
	(net 615 "unconnected-(U1D-IO_L4P_T0_32-PadAF15)")
	(net 616 "/FPGA Bank 12 & 13/USB_USER.SPD")
	(net 617 "unconnected-(U1D-IO_L12P_T1_MRCC_32-PadAF17)")
	(net 618 "unconnected-(U1A-IO_L16N_T2_13-PadAF30)")
	(net 619 "/FPGA Bank 12 & 13/USB_USER.SCON")
	(net 620 "unconnected-(U1D-IO_L12N_T1_MRCC_32-PadAG17)")
	(net 621 "unconnected-(U1D-IO_L11N_T1_SRCC_32-PadAG18)")
	(net 622 "+1V85_ADC")
	(net 623 "/Clocks/SYS.CLK_N")
	(net 624 "/Clocks/SYS.CLK_P")
	(net 625 "unconnected-(U1E-IO_L17P_T2_33-PadAK11)")
	(net 626 "unconnected-(U1D-IO_L8P_T1_32-PadAG19)")
	(net 627 "/FMC+ HSPC/GTR_REFCLK0_R_P")
	(net 628 "/FMC+ HSPC/GTX115.REFCLK0_P")
	(net 629 "/FMC+ HSPC/GTR_REFCLK0_R_N")
	(net 630 "/FMC+ HSPC/GTX115.REFCLK0_N")
	(net 631 "unconnected-(U1A-IO_L21N_T3_DQS_13-PadAG28)")
	(net 632 "unconnected-(U1A-IO_L13P_T2_MRCC_13-PadAG29)")
	(net 633 "unconnected-(U1A-IO_L18P_T2_13-PadAG30)")
	(net 634 "/FMC+ HSPC/FMC.IO22_N")
	(net 635 "unconnected-(U1E-IO_L14N_T2_SRCC_34-PadAH5)")
	(net 636 "unconnected-(U1E-IO_L14P_T2_SRCC_34-PadAH6)")
	(net 637 "/USB PHY/USB_HOST_VBUS_FLG")
	(net 638 "unconnected-(U1D-IO_L3P_T0_DQS_32-PadAH16)")
	(net 639 "/FPGA Bank 12 & 13/USB_USER.VPO")
	(net 640 "/Clocks/LVDS_XO_200M_ENA")
	(net 641 "/FMC+ HSPC/FMC.IO15_N")
	(net 642 "/FMC+ HSPC/FMC.IO22_P")
	(net 643 "/FMC+ HSPC/FMC.IO15_P")
	(net 644 "unconnected-(U1D-IO_L8N_T1_32-PadAH19)")
	(net 645 "unconnected-(U1A-IO_L22P_T3_13-PadAH26)")
	(net 646 "unconnected-(U1A-IO_L13N_T2_MRCC_13-PadAH29)")
	(net 647 "unconnected-(U1A-IO_L18N_T2_13-PadAH30)")
	(net 648 "unconnected-(U1E-IO_L17P_T2_34-PadAJ1)")
	(net 649 "VREFP")
	(net 650 "+1V0")
	(net 651 "unconnected-(U1E-IO_L18P_T2_34-PadAJ3)")
	(net 652 "unconnected-(U1E-IO_L13N_T2_MRCC_34-PadAJ4)")
	(net 653 "unconnected-(U1D-IO_L3N_T0_DQS_32-PadAJ16)")
	(net 654 "/DRAM + SRAM/DDR.DQ7")
	(net 655 "/DRAM + SRAM/DDR.DQ4")
	(net 656 "/DRAM + SRAM/DDR.DQS_P")
	(net 657 "/DRAM + SRAM/DDR.DQ3")
	(net 658 "/DRAM + SRAM/DDR.DQS_N")
	(net 659 "/DRAM + SRAM/DDR.DQ5")
	(net 660 "/DRAM + SRAM/DDR.DQ6")
	(net 661 "/DRAM + SRAM/DDR.DQ0")
	(net 662 "/DRAM + SRAM/DDR.DQ2")
	(net 663 "/DRAM + SRAM/DDR.DQ1")
	(net 664 "/DRAM + SRAM/SRAM.A5")
	(net 665 "/DRAM + SRAM/SRAM.A6")
	(net 666 "/DRAM + SRAM/SRAM.DQ3")
	(net 667 "/DRAM + SRAM/SRAM.A8")
	(net 668 "/DRAM + SRAM/SRAM.DQ6")
	(net 669 "/DRAM + SRAM/SRAM.DQ7")
	(net 670 "/DRAM + SRAM/SRAM.A9")
	(net 671 "/DRAM + SRAM/SRAM.A2")
	(net 672 "/DRAM + SRAM/SRAM.A3")
	(net 673 "/DRAM + SRAM/SRAM.A13")
	(net 674 "/DRAM + SRAM/SRAM.DQ5")
	(net 675 "/DRAM + SRAM/SRAM.A15")
	(net 676 "/DRAM + SRAM/SRAM.DQ4")
	(net 677 "/DRAM + SRAM/SRAM.A14")
	(net 678 "/DRAM + SRAM/SRAM.A11")
	(net 679 "/DRAM + SRAM/SRAM.A10")
	(net 680 "/DRAM + SRAM/SRAM.A0")
	(net 681 "/DRAM + SRAM/SRAM.A12")
	(net 682 "/DRAM + SRAM/SRAM.A4")
	(net 683 "/DRAM + SRAM/SRAM.DQ0")
	(net 684 "/DRAM + SRAM/SRAM.A7")
	(net 685 "/DRAM + SRAM/SRAM.A18")
	(net 686 "/DRAM + SRAM/SRAM.A1")
	(net 687 "/DRAM + SRAM/SRAM.DQ1")
	(net 688 "/DRAM + SRAM/SRAM.DQ2")
	(net 689 "/DRAM + SRAM/SRAM.A16")
	(net 690 "/DRAM + SRAM/SRAM.A17")
	(net 691 "/DRAM + SRAM/SRAM.A19")
	(net 692 "unconnected-(U1A-IO_L17N_T2_12-PadAK24)")
	(net 693 "/FPGA Bank 12 & 13/USB_USER.VMO")
	(net 694 "unconnected-(U1D-IO_L9P_T1_DQS_32-PadAJ18)")
	(net 695 "/FMC+ HSPC/FMC.~{PERST}")
	(net 696 "/FMC+ HSPC/FMC.PRSNT_M2C")
	(net 697 "/Power supply/VSS")
	(net 698 "/Power supply/VDD")
	(net 699 "GNDD")
	(net 700 "/Power supply/USB_PD_VBUS")
	(net 701 "/DC-DC Converters/PB_CTRL_OUT")
	(net 702 "VDC")
	(net 703 "+5V")
	(net 704 "/Power supply/USB_DBG_PD.VBUS")
	(net 705 "/USB PHY/USB_HOST_VBUS")
	(net 706 "/USB PHY/USB_HOST_XI")
	(net 707 "/USB PHY/FTDI_3V3")
	(net 708 "/USB PHY/USB_HOST_XO")
	(net 709 "/USB PHY/USB_HOST_VBCOMP")
	(net 710 "/USB PHY/FTDI_XI")
	(net 711 "/USB PHY/FTDI_VPLL")
	(net 712 "/USB PHY/FTDI_VCORE")
	(net 713 "/USB PHY/FTDI_XO")
	(net 714 "/USB PHY/FTDI_VPHY")
	(net 715 "/USB PHY/USB_USR_VBUS")
	(net 716 "/HDMI + Ethernet/ETH_XI")
	(net 717 "/HDMI + Ethernet/GBE_AVDDH")
	(net 718 "/HDMI + Ethernet/GBE_XI")
	(net 719 "/HDMI + Ethernet/ETH_XO")
	(net 720 "/HDMI + Ethernet/GBE_XO")
	(net 721 "/HDMI + Ethernet/ETH_3V3")
	(net 722 "/HDMI + Ethernet/ETH_VDDCR")
	(net 723 "/HDMI + Ethernet/ETH_CONN_SH")
	(net 724 "/HDMI + Ethernet/ETH1_P")
	(net 725 "/HDMI + Ethernet/ETH1_N")
	(net 726 "/HDMI + Ethernet/ETH2_P")
	(net 727 "+1V2")
	(net 728 "/HDMI + Ethernet/GBE_AVDDL{slash}PLL")
	(net 729 "/HDMI + Ethernet/ETH2_N")
	(net 730 "/HDMI + Ethernet/GBE_CONN_COMM")
	(net 731 "/DC-DC Converters/QDCDC1_VCC")
	(net 732 "/DC-DC Converters/QDCDC2_VCC")
	(net 733 "/DC-DC Converters/MGTAVCC_local")
	(net 734 "/DC-DC Converters/1V8_local")
	(net 735 "/DC-DC Converters/3V3_local")
	(net 736 "/DC-DC Converters/3V3_local_2")
	(net 737 "/DC-DC Converters/1V2_local")
	(net 738 "/DC-DC Converters/1V7_local")
	(net 739 "/DC-DC Converters/5V_local")
	(net 740 "/DC-DC Converters/1V35_local")
	(net 741 "/DC-DC Converters/1V0_VCC")
	(net 742 "/DC-DC Converters/1V85_VIN")
	(net 743 "/DC-DC Converters/1V7")
	(net 744 "/DC-DC Converters/VDDR_VRI")
	(net 745 "/DC-DC Converters/1V0_BS")
	(net 746 "/DC-DC Converters/1V0_SW")
	(net 747 "/DC-DC Converters/1V85_OUT")
	(net 748 "/DC-DC Converters/MGTAVTT_OUT")
	(net 749 "/DC-DC Converters/1V0_SS")
	(net 750 "/DC-DC Converters/VDDR_VTT")
	(net 751 "/DC-DC Converters/1V0_REG")
	(net 752 "/Clocks/PLL_XI")
	(net 753 "/Clocks/PLL_XO")
	(net 754 "Net-(D2-C)")
	(net 755 "Net-(D12-A)")
	(net 756 "Net-(D4-Pad1)")
	(net 757 "Net-(D4-Pad2)")
	(net 758 "/HDMI + Ethernet/POE_GBE.VC1")
	(net 759 "/HDMI + Ethernet/POE_GBE.VC2")
	(net 760 "/HDMI + Ethernet/POE_GBE.VC3")
	(net 761 "/HDMI + Ethernet/POE_GBE.VC4")
	(net 762 "Net-(D6-Pad1)")
	(net 763 "Net-(D6-Pad2)")
	(net 764 "/HDMI + Ethernet/POE_ETH.VC1")
	(net 765 "/HDMI + Ethernet/POE_ETH.VC2")
	(net 766 "/HDMI + Ethernet/POE_ETH.VC3")
	(net 767 "/HDMI + Ethernet/POE_ETH.VC4")
	(net 768 "Net-(D23-C)")
	(net 769 "/Power supply/PD_PWR_OK2")
	(net 770 "Net-(D24-C)")
	(net 771 "/Power supply/PD_PWR_OK3")
	(net 772 "Net-(D18-C)")
	(net 773 "Net-(D24-A)")
	(net 774 "unconnected-(U1D-IO_L7P_T1_32-PadAJ19)")
	(net 775 "Net-(D18-A)")
	(net 776 "unconnected-(U1A-IO_L24P_T3_13-PadAJ26)")
	(net 777 "Net-(D19-A)")
	(net 778 "unconnected-(U1A-IO_L20P_T3_13-PadAJ27)")
	(net 779 "Net-(D20-A)")
	(net 780 "unconnected-(U1C-IO_L1P_T0_16-PadB23)")
	(net 781 "Net-(D21-A)")
	(net 782 "unconnected-(U1C-IO_L17P_T2_16-PadB30)")
	(net 783 "Net-(D22-A)")
	(net 784 "unconnected-(U1E-IO_L17N_T2_34-PadAK1)")
	(net 785 "Net-(D23-A)")
	(net 786 "unconnected-(U1E-IO_L18N_T2_34-PadAK3)")
	(net 787 "Net-(D25-C)")
	(net 788 "unconnected-(U1D-IO_L1N_T0_32-PadAK15)")
	(net 789 "Net-(D25-A)")
	(net 790 "Net-(D26-A)")
	(net 791 "Net-(D27-A)")
	(net 792 "Net-(D28-A)")
	(net 793 "Net-(D29-A)")
	(net 794 "/HDMI + Ethernet/HDMI_CONN_5V")
	(net 795 "/HDMI + Ethernet/HDMI_5V")
	(net 796 "unconnected-(U1D-IO_L1P_T0_32-PadAK16)")
	(net 797 "/DC-DC Converters/PB_CTRL_OE")
	(net 798 "/Power supply/POE_ACTIVE")
	(net 799 "FTDI_DIS")
	(net 800 "unconnected-(U1J-VCCBATT_0-PadC10)")
	(net 801 "/User GPIO + LED + button + DIP switch/FAN_PWM_PIN")
	(net 802 "/User GPIO + LED + button + DIP switch/PMOD_A_10")
	(net 803 "/User GPIO + LED + button + DIP switch/PMOD_A_4")
	(net 804 "/User GPIO + LED + button + DIP switch/PMOD_A_9")
	(net 805 "/User GPIO + LED + button + DIP switch/PMOD_A_3")
	(net 806 "/User GPIO + LED + button + DIP switch/PMOD_A_8")
	(net 807 "/User GPIO + LED + button + DIP switch/PMOD_A_2")
	(net 808 "/User GPIO + LED + button + DIP switch/PMOD_A_7")
	(net 809 "/User GPIO + LED + button + DIP switch/PMOD_A_1")
	(net 810 "/User GPIO + LED + button + DIP switch/PMOD_B_10")
	(net 811 "/User GPIO + LED + button + DIP switch/PMOD_B_4")
	(net 812 "/User GPIO + LED + button + DIP switch/PMOD_B_9")
	(net 813 "/User GPIO + LED + button + DIP switch/PMOD_B_3")
	(net 814 "/User GPIO + LED + button + DIP switch/PMOD_B_8")
	(net 815 "/User GPIO + LED + button + DIP switch/PMOD_B_2")
	(net 816 "/User GPIO + LED + button + DIP switch/PMOD_B_7")
	(net 817 "/User GPIO + LED + button + DIP switch/PMOD_B_1")
	(net 818 "unconnected-(U1D-IO_L9N_T1_DQS_32-PadAK18)")
	(net 819 "unconnected-(U1D-IO_L7N_T1_32-PadAK19)")
	(net 820 "unconnected-(J10-Pad1)")
	(net 821 "unconnected-(J10-Pad3)")
	(net 822 "/User GPIO + LED + button + DIP switch/CW_20PIN_HS1")
	(net 823 "/User GPIO + LED + button + DIP switch/CW_20PIN_RST")
	(net 824 "/User GPIO + LED + button + DIP switch/CW_20PIN_HS2")
	(net 825 "/User GPIO + LED + button + DIP switch/CW_20PIN_MISO")
	(net 826 "/User GPIO + LED + button + DIP switch/CW_20PIN_MOSI")
	(net 827 "/User GPIO + LED + button + DIP switch/CW_20PIN_IO1")
	(net 828 "/User GPIO + LED + button + DIP switch/CW_20PIN_TSCK")
	(net 829 "/User GPIO + LED + button + DIP switch/CW_20PIN_IO2")
	(net 830 "/User GPIO + LED + button + DIP switch/CW_20PIN_TPDIC")
	(net 831 "/User GPIO + LED + button + DIP switch/CW_20PIN_IO3")
	(net 832 "/User GPIO + LED + button + DIP switch/CW_20PIN_TPDID")
	(net 833 "unconnected-(J10-Pad18)")
	(net 834 "unconnected-(J10-Pad20)")
	(net 835 "/USB PHY/USB_HOST_CONN_D-")
	(net 836 "/USB PHY/USB_HOST_CONN_D+")
	(net 837 "/Power supply/USB_DBG_PD.CC1")
	(net 838 "/USB PHY/USB_DBG_CONN_D+")
	(net 839 "/USB PHY/USB_DBG_CONN_D-")
	(net 840 "/Power supply/USB_DBG_PD.CC2")
	(net 841 "/USB PHY/USB_USR_CC1")
	(net 842 "/USB PHY/USB_USR_CONN_D+")
	(net 843 "/USB PHY/USB_USR_CONN_D-")
	(net 844 "/USB PHY/USB_USR_CC2")
	(net 845 "/HDMI + Ethernet/ETH_LED_LINK+")
	(net 846 "/HDMI + Ethernet/ETH_LED_SPD-")
	(net 847 "/HDMI + Ethernet/ETH_LED_LINK-")
	(net 848 "/HDMI + Ethernet/ETH_LED_SPD+")
	(net 849 "/HDMI + Ethernet/GBE_LED_LINK+")
	(net 850 "/HDMI + Ethernet/GBE_LED_SPD-")
	(net 851 "/HDMI + Ethernet/GBE_LED_LINK-")
	(net 852 "/HDMI + Ethernet/GBE_LED_SPD+")
	(net 853 "/HDMI + Ethernet/GBE4_N")
	(net 854 "/HDMI + Ethernet/GBE4_P")
	(net 855 "/HDMI + Ethernet/GBE3_N")
	(net 856 "/HDMI + Ethernet/GBE3_P")
	(net 857 "/HDMI + Ethernet/GBE2_N")
	(net 858 "/HDMI + Ethernet/GBE2_P")
	(net 859 "/HDMI + Ethernet/GBE1_N")
	(net 860 "/HDMI + Ethernet/GBE1_P")
	(net 861 "/HDMI + Ethernet/HDMI_CONN_CLK_P")
	(net 862 "/HDMI + Ethernet/HDMI_CONN_D0_N")
	(net 863 "/HDMI + Ethernet/HDMI_CONN_D0_P")
	(net 864 "/HDMI + Ethernet/HDMI_CONN_D1_N")
	(net 865 "/HDMI + Ethernet/HDMI_CONN_D1_P")
	(net 866 "/HDMI + Ethernet/HDMI_CONN_D2_N")
	(net 867 "/HDMI + Ethernet/HDMI_CONN_D2_P")
	(net 868 "/HDMI + Ethernet/HDMI_CONN_CLK_N")
	(net 869 "Net-(NT1-Pad1)")
	(net 870 "VREFN")
	(net 871 "unconnected-(U1A-IO_L15P_T2_DQS_13-PadAK29)")
	(net 872 "/Power supply/SINK_EN")
	(net 873 "unconnected-(U1G-MGTXTXN2_118-PadB1)")
	(net 874 "unconnected-(U1G-MGTXTXP2_118-PadB2)")
	(net 875 "unconnected-(U1C-IO_L2N_T0_16-PadD23)")
	(net 876 "/User GPIO + LED + button + DIP switch/FAN_PWM_CTRL_AON")
	(net 877 "unconnected-(U1C-IO_L4N_T0_16-PadD24)")
	(net 878 "/USB PHY/~{BDBUS3}")
	(net 879 "unconnected-(U1C-IO_L11P_T1_SRCC_16-PadD26)")
	(net 880 "/Power supply/VBUS_DIS")
	(net 881 "/Power supply/AMPS_CTL")
	(net 882 "/Power supply/REF")
	(net 883 "/Power supply/MPS_DUTY")
	(net 884 "unconnected-(U1C-IO_L16P_T2_16-PadD29)")
	(net 885 "/Power supply/CLSA")
	(net 886 "/Power supply/CLSB")
	(net 887 "/Power supply/DEN")
	(net 888 "/Power supply/PDBUS_DISCH")
	(net 889 "/Power supply/PG")
	(net 890 "unconnected-(U1G-MGTXRXN2_118-PadB5)")
	(net 891 "unconnected-(R62-Pad2)")
	(net 892 "unconnected-(U1G-MGTXRXP2_118-PadB6)")
	(net 893 "/FPGA Bank 12 & 13/USB_HOST.~{CS}")
	(net 894 "/SPI Flash + SD Card/SYSTEM_FLASH_~{CS}")
	(net 895 "/SPI Flash + SD Card/SYSTEM_FLASH_CLK")
	(net 896 "/SPI Flash + SD Card/SYSTEM_FLASH_DQ0")
	(net 897 "/SPI Flash + SD Card/SYSTEM_FLASH_DQ1")
	(net 898 "/SPI Flash + SD Card/SYSTEM_FLASH_DQ2")
	(net 899 "/SPI Flash + SD Card/SYSTEM_FLASH_DQ3")
	(net 900 "/SPI Flash + SD Card/USR_FLASH_0_~{CS}")
	(net 901 "/SPI Flash + SD Card/USR_FLASH_0_CLK")
	(net 902 "/SPI Flash + SD Card/USR_FLASH_0_DQ0")
	(net 903 "/SPI Flash + SD Card/USR_FLASH_0_DQ1")
	(net 904 "/SPI Flash + SD Card/USR_FLASH_0_DQ2")
	(net 905 "/SPI Flash + SD Card/USR_FLASH_0_DQ3")
	(net 906 "/SPI Flash + SD Card/USR_FLASH_1_~{CS}")
	(net 907 "/SPI Flash + SD Card/USR_FLASH_1_CLK")
	(net 908 "/SPI Flash + SD Card/USR_FLASH_1_DQ0")
	(net 909 "/SPI Flash + SD Card/USR_FLASH_1_DQ1")
	(net 910 "/SPI Flash + SD Card/USR_FLASH_1_DQ2")
	(net 911 "/SPI Flash + SD Card/USR_FLASH_1_DQ3")
	(net 912 "/USB PHY/LED_TX0")
	(net 913 "/USB PHY/LED_RX0")
	(net 914 "/USB PHY/LED_TX1")
	(net 915 "/USB PHY/LED_RX1")
	(net 916 "/USB PHY/USB_HOST_D-")
	(net 917 "/USB PHY/USB_HOST_D+")
	(net 918 "/USB PHY/FTDI_PWREN")
	(net 919 "/USB PHY/FTDI_RST")
	(net 920 "/USB PHY/FTDI_REF")
	(net 921 "/USB PHY/FTDI_UART0_TX")
	(net 922 "/USB PHY/FTDI_UART0_RX")
	(net 923 "/USB PHY/FTDI_UART1_TX")
	(net 924 "/USB PHY/FTDI_UART1_RX")
	(net 925 "/USB PHY/BDBUS3")
	(net 926 "/USB PHY/USB_USR_VPU")
	(net 927 "/USB PHY/USB_USR_D-")
	(net 928 "/USB PHY/USB_USR_D+")
	(net 929 "unconnected-(U1G-MGTXTXN1_118-PadC3)")
	(net 930 "unconnected-(U1G-MGTXTXP1_118-PadC4)")
	(net 931 "unconnected-(U1G-MGTREFCLK0N_118-PadC7)")
	(net 932 "unconnected-(U1G-MGTREFCLK0P_118-PadC8)")
	(net 933 "unconnected-(U1C-IO_L2P_T0_16-PadE23)")
	(net 934 "/USB PHY/SPI_EN")
	(net 935 "unconnected-(U1C-IO_L4P_T0_16-PadE24)")
	(net 936 "unconnected-(U1C-IO_L3N_T0_DQS_16-PadE25)")
	(net 937 "unconnected-(U1C-IO_L5N_T0_16-PadE26)")
	(net 938 "/FPGA Bank 12 & 13/USB_HOST.MOSI")
	(net 939 "/FPGA Bank 16 & 17/GBE_RGMII.TXD0")
	(net 940 "/USB PHY/I2C_EN")
	(net 941 "/USB PHY/FTDI_SCL")
	(net 942 "/USB PHY/FTDI_SDA_IN")
	(net 943 "Net-(R191-Pad1)")
	(net 944 "/HDMI + Ethernet/ETH_PHY_RX_DV")
	(net 945 "/HDMI + Ethernet/ETH_PHY_RXD1")
	(net 946 "/HDMI + Ethernet/ETH_PHY_RXDO")
	(net 947 "/HDMI + Ethernet/ETH_PHY_RXER")
	(net 948 "/HDMI + Ethernet/ETH_PHY_TXEN")
	(net 949 "/HDMI + Ethernet/ETH_PHY_TXDO")
	(net 950 "/HDMI + Ethernet/ETH_PHY_TXD1")
	(net 951 "/HDMI + Ethernet/ETH_PHY_REFCLK")
	(net 952 "/HDMI + Ethernet/ETH_ISET")
	(net 953 "/HDMI + Ethernet/GBE_ISET")
	(net 954 "/DC-DC Converters/QDCDC2_GPIO")
	(net 955 "/Supervisior MCU/FPGA_COPI")
	(net 956 "/DC-DC Converters/POE_DC")
	(net 957 "/DC-DC Converters/FB6")
	(net 958 "/DC-DC Converters/FB5")
	(net 959 "/DC-DC Converters/FB1")
	(net 960 "/DC-DC Converters/FB2")
	(net 961 "/DC-DC Converters/ON{slash}OFF")
	(net 962 "/DC-DC Converters/FB3")
	(net 963 "/DC-DC Converters/FB4")
	(net 964 "/DC-DC Converters/FB7")
	(net 965 "/DC-DC Converters/FB8")
	(net 966 "/DC-DC Converters/EN1")
	(net 967 "/DC-DC Converters/EN2")
	(net 968 "/DC-DC Converters/EN3")
	(net 969 "/DC-DC Converters/MGTAVTT_ILIM")
	(net 970 "/DC-DC Converters/1V0_FB")
	(net 971 "/Clocks/PLL_Y0")
	(net 972 "/Clocks/PLL_Y1")
	(net 973 "/Clocks/PLL_Y4")
	(net 974 "/DC-DC Converters/~{PB_CTRL_IN}")
	(net 975 "/Supervisior MCU/FPGA_CIPO")
	(net 976 "unconnected-(U1G-MGTXTXN0_118-PadD1)")
	(net 977 "unconnected-(U1G-MGTXTXP0_118-PadD2)")
	(net 978 "unconnected-(U1G-MGTXRXN1_118-PadD5)")
	(net 979 "unconnected-(U1C-IO_0_16-PadF23)")
	(net 980 "unconnected-(U1C-IO_L3P_T0_DQS_16-PadF25)")
	(net 981 "unconnected-(U1C-IO_L5P_T0_16-PadF26)")
	(net 982 "unconnected-(U1G-MGTXRXP1_118-PadD6)")
	(net 983 "/Power supply/PD_CTRL.RESET")
	(net 984 "unconnected-(U1C-IO_L10P_T1_17-PadD22)")
	(net 985 "unconnected-(U1G-MGTXRXN0_118-PadE3)")
	(net 986 "unconnected-(U1G-MGTXRXP0_118-PadE4)")
	(net 987 "unconnected-(U1G-MGTREFCLK1N_118-PadE7)")
	(net 988 "unconnected-(U1C-IO_L6P_T0_16-PadG23)")
	(net 989 "unconnected-(U1C-IO_L6N_T0_VREF_16-PadG24)")
	(net 990 "unconnected-(U1C-IO_25_16-PadG25)")
	(net 991 "unconnected-(U1G-MGTREFCLK1P_118-PadE8)")
	(net 992 "unconnected-(U1C-IO_L14P_T2_SRCC_17-PadE19)")
	(net 993 "/FPGA Bank 16 & 17/GBE_RGMII.TXD3")
	(net 994 "unconnected-(U1G-MGTXTXN3_117-PadF1)")
	(net 995 "unconnected-(U1G-MGTXTXP3_117-PadF2)")
	(net 996 "/USB PHY/FTDI_EECLK")
	(net 997 "/USB PHY/FTDI_EECS")
	(net 998 "/USB PHY/FTDI_EEDAT")
	(net 999 "unconnected-(U1G-MGTXRXN3_117-PadF5)")
	(net 1000 "unconnected-(U1G-MGTXRXP3_117-PadF6)")
	(net 1001 "/FPGA Bank 16 & 17/GBE_RGMII.MDC")
	(net 1002 "/FPGA Bank 16 & 17/GBE_RGMII.TXD2")
	(net 1003 "unconnected-(U1C-IO_L9N_T1_DQS_17-PadF22)")
	(net 1004 "unconnected-(U1G-MGTXRXN2_117-PadG3)")
	(net 1005 "unconnected-(U1G-MGTXRXP2_117-PadG4)")
	(net 1006 "unconnected-(U1G-MGTREFCLK0N_117-PadG7)")
	(net 1007 "unconnected-(U1G-MGTREFCLK0P_117-PadG8)")
	(net 1008 "/FPGA Bank 16 & 17/GBE_RGMII.TX_EN")
	(net 1009 "unconnected-(U1C-IO_L9P_T1_DQS_17-PadG22)")
	(net 1010 "unconnected-(U1G-MGTXTXN2_117-PadH1)")
	(net 1011 "unconnected-(U1G-MGTXTXP2_117-PadH2)")
	(net 1012 "unconnected-(U1G-MGTXRXN1_117-PadH5)")
	(net 1013 "unconnected-(U1G-MGTXRXP1_117-PadH6)")
	(net 1014 "unconnected-(U1C-IO_L3N_T0_DQS_17-PadH17)")
	(net 1015 "/USB PHY/FTDI_JTAG_TCK")
	(net 1016 "/USB PHY/FTDI_JTAG_TDI")
	(net 1017 "/USB PHY/FTDI_JTAG_TDO")
	(net 1018 "/USB PHY/FTDI_JTAG_TMS")
	(net 1019 "/FPGA Bank 16 & 17/GBE_RGMII.GTX_CLK")
	(net 1020 "/USB PHY/FTDI_JTAG_RST")
	(net 1021 "/FPGA Bank 16 & 17/GBE_RGMII.TXD1")
	(net 1022 "unconnected-(U1C-IO_L7N_T1_17-PadH22)")
	(net 1023 "/USB PHY/BDBUS0")
	(net 1024 "/USB PHY/BDBUS1")
	(net 1025 "/USB PHY/BDBUS2")
	(net 1026 "unconnected-(U1G-MGTXTXN1_117-PadJ3)")
	(net 1027 "unconnected-(U1G-MGTXTXP1_117-PadJ4)")
	(net 1028 "unconnected-(U1G-MGTREFCLK1N_117-PadJ7)")
	(net 1029 "unconnected-(U1G-MGTREFCLK1P_117-PadJ8)")
	(net 1030 "unconnected-(U1C-IO_L3P_T0_DQS_17-PadJ17)")
	(net 1031 "unconnected-(U1C-IO_L1N_T0_17-PadJ18)")
	(net 1032 "unconnected-(U1B-IO_L5P_T0_AD2P_15-PadJ21)")
	(net 1033 "unconnected-(U1B-IO_L1P_T0_AD0P_15-PadJ23)")
	(net 1034 "unconnected-(U1B-IO_L1N_T0_AD0N_15-PadJ24)")
	(net 1035 "unconnected-(U1G-MGTXTXN0_117-PadK1)")
	(net 1036 "unconnected-(U1G-MGTXTXP0_117-PadK2)")
	(net 1037 "unconnected-(U1G-MGTXRXN0_117-PadK5)")
	(net 1038 "unconnected-(U1G-MGTXRXP0_117-PadK6)")
	(net 1039 "unconnected-(U1C-IO_L1P_T0_17-PadK18)")
	(net 1040 "unconnected-(U1C-IO_L6P_T0_17-PadK19)")
	(net 1041 "unconnected-(U1C-IO_L6N_T0_VREF_17-PadK20)")
	(net 1042 "unconnected-(U1B-IO_L3P_T0_DQS_AD1P_15-PadK23)")
	(net 1043 "unconnected-(U1B-IO_L3N_T0_DQS_AD1N_15-PadK24)")
	(net 1044 "unconnected-(U1B-IO_L12N_T1_MRCC_AD5N_15-PadK25)")
	(net 1045 "unconnected-(U1B-IO_L23P_T3_A03_D19_14-PadU24)")
	(net 1046 "unconnected-(U1B-IO_L15N_T2_DQS_DOUT_CSO_B_14-PadU30)")
	(net 1047 "/USB PHY/FTDI_SDA_OUT")
	(net 1048 "unconnected-(U1B-IO_L22N_T3_A04_D20_14-PadV22)")
	(net 1049 "unconnected-(U1B-IO_25_14-PadW19)")
	(net 1050 "unconnected-(U1B-IO_L13N_T2_MRCC_15-PadK29)")
	(net 1051 "unconnected-(U1I-CFGBVS_0-PadL10)")
	(net 1052 "/DC-DC Converters/SW2")
	(net 1053 "/DC-DC Converters/PB_CTRL.VDDR_EN")
	(net 1054 "/Supervisior MCU/CFG_PROGRAMB")
	(net 1055 "/DC-DC Converters/VDDR_PGOOD")
	(net 1056 "unconnected-(U1C-IO_L5P_T0_17-PadL17)")
	(net 1057 "unconnected-(U1C-IO_L5N_T0_17-PadL18)")
	(net 1058 "unconnected-(U3-NC-Pad1)")
	(net 1059 "unconnected-(U3-NC-Pad5)")
	(net 1060 "/Supervisior MCU/CFG_INITB")
	(net 1061 "/Supervisior MCU/USB_A0")
	(net 1062 "/Supervisior MCU/USB_A1")
	(net 1063 "/Supervisior MCU/USB_A2")
	(net 1064 "/Supervisior MCU/USB_A3")
	(net 1065 "/Supervisior MCU/USB_A4")
	(net 1066 "/Supervisior MCU/USB_A5")
	(net 1067 "/Supervisior MCU/USB_A6")
	(net 1068 "/Supervisior MCU/USB_A7")
	(net 1069 "/Supervisior MCU/USB_A8")
	(net 1070 "/Supervisior MCU/USB_A9")
	(net 1071 "/Supervisior MCU/USB_A10")
	(net 1072 "/Supervisior MCU/USB_A11")
	(net 1073 "/Supervisior MCU/USB_A12")
	(net 1074 "/Supervisior MCU/USB_A13")
	(net 1075 "/Supervisior MCU/USB_A14")
	(net 1076 "/Supervisior MCU/USB_A15")
	(net 1077 "/Supervisior MCU/USB_A16")
	(net 1078 "/Supervisior MCU/USB_A17")
	(net 1079 "/Supervisior MCU/USB_A18")
	(net 1080 "/Supervisior MCU/USB_A19")
	(net 1081 "/Supervisior MCU/TXD1")
	(net 1082 "/Supervisior MCU/TXD0")
	(net 1083 "/Supervisior MCU/RXD1")
	(net 1084 "/Supervisior MCU/RXD0")
	(net 1085 "/Supervisior MCU/PGOOD_VCCINT")
	(net 1086 "/Supervisior MCU/PGOOD_3V3")
	(net 1087 "/Supervisior MCU/PGOOD_1V8")
	(net 1088 "/Supervisior MCU/PGOOD_1V2")
	(net 1089 "/Supervisior MCU/USB_SPI_SCK")
	(net 1090 "/Supervisior MCU/USB_SPI_COPI")
	(net 1091 "/Supervisior MCU/USB_SPI_CIPO")
	(net 1092 "/Supervisior MCU/USB_CLK1_SPARE")
	(net 1093 "/Supervisior MCU/USB_ALE")
	(net 1094 "/Supervisior MCU/USB_RD")
	(net 1095 "/Supervisior MCU/USB_CE")
	(net 1096 "/Supervisior MCU/USB_SPI_CS")
	(net 1097 "/Supervisior MCU/USB_D2")
	(net 1098 "/Supervisior MCU/USB_D1")
	(net 1099 "/Supervisior MCU/USB_D0")
	(net 1100 "/Supervisior MCU/USB_WR")
	(net 1101 "/Supervisior MCU/SDA0")
	(net 1102 "/Supervisior MCU/SCL0")
	(net 1103 "/Supervisior MCU/FPGA_M0")
	(net 1104 "/Supervisior MCU/FPGA_M1")
	(net 1105 "/Supervisior MCU/FPGA_M2")
	(net 1106 "/Supervisior MCU/TEMP_ALERT_N")
	(net 1107 "/Supervisior MCU/USB_C_PD_RST")
	(net 1108 "/Supervisior MCU/PWR_RST")
	(net 1109 "/Supervisior MCU/USB_D3")
	(net 1110 "/Supervisior MCU/USB_D4")
	(net 1111 "/Supervisior MCU/USB_D5")
	(net 1112 "/Supervisior MCU/USB_D6")
	(net 1113 "/Supervisior MCU/USB_D7")
	(net 1114 "/Supervisior MCU/USB_SPARE0")
	(net 1115 "/Supervisior MCU/USB_SPARE1")
	(net 1116 "/Supervisior MCU/USB_SPARE2")
	(net 1117 "/Supervisior MCU/USB_SPARE3")
	(net 1118 "/Supervisior MCU/USB_CLK0")
	(net 1119 "unconnected-(U3-NC-Pad9)")
	(net 1120 "unconnected-(U3-NC-Pad13)")
	(net 1121 "unconnected-(U3-NC-Pad16)")
	(net 1122 "unconnected-(U4-NC-PadA1)")
	(net 1123 "unconnected-(U4-NC-PadB1)")
	(net 1124 "unconnected-(U4-NC-PadB2)")
	(net 1125 "unconnected-(U4-NC-PadB6)")
	(net 1126 "unconnected-(U4-NC-PadC2)")
	(net 1127 "unconnected-(U4-NC-PadC5)")
	(net 1128 "unconnected-(U4-NC-PadE3)")
	(net 1129 "unconnected-(U4-NC-PadF2)")
	(net 1130 "unconnected-(U4-NC-PadF5)")
	(net 1131 "unconnected-(U4-NC-PadG1)")
	(net 1132 "unconnected-(U4-NC-PadG2)")
	(net 1133 "unconnected-(U4-NC-PadG6)")
	(net 1134 "unconnected-(U5-NC-PadA3)")
	(net 1135 "unconnected-(U5-NF{slash}TDQS#-PadA7)")
	(net 1136 "unconnected-(U5-NC-PadF1)")
	(net 1137 "unconnected-(U5-NC-PadF9)")
	(net 1138 "unconnected-(U5-NC-PadH1)")
	(net 1139 "unconnected-(U5-NC-PadH9)")
	(net 1140 "unconnected-(U6-NC-Pad3)")
	(net 1141 "unconnected-(U6-ATTACH-Pad11)")
	(net 1142 "unconnected-(U6-GPIO-Pad15)")
	(net 1143 "/DC-DC Converters/SW1")
	(net 1144 "unconnected-(U16-Pad5)")
	(net 1145 "/User GPIO + LED + button + DIP switch/CW_20PIN_IO4")
	(net 1146 "unconnected-(U6-A_B_SIDE-Pad17)")
	(net 1147 "unconnected-(U6-~{ALERT}-Pad19)")
	(net 1148 "unconnected-(U7-~{AUTCLS}-Pad10)")
	(net 1149 "unconnected-(U7-NC-Pad14)")
	(net 1150 "unconnected-(U7-NC-Pad15)")
	(net 1151 "unconnected-(U7-IRSHDL_EN-Pad16)")
	(net 1152 "unconnected-(U7-TPL-Pad17)")
	(net 1153 "unconnected-(U7-TPH-Pad18)")
	(net 1154 "unconnected-(U7-~{BT}-Pad19)")
	(net 1155 "unconnected-(U7-NC-Pad20)")
	(net 1156 "unconnected-(U9-STAT-Pad4)")
	(net 1157 "unconnected-(U10-STAT-Pad4)")
	(net 1158 "unconnected-(U11-STAT-Pad4)")
	(net 1159 "unconnected-(U15-NC-Pad4)")
	(net 1160 "unconnected-(U18-QB-Pad1)")
	(net 1161 "unconnected-(U18-QC-Pad2)")
	(net 1162 "unconnected-(U18-QD-Pad3)")
	(net 1163 "unconnected-(U18-QH'-Pad9)")
	(net 1164 "unconnected-(U18-QA-Pad15)")
	(net 1165 "unconnected-(U18-EP-Pad17)")
	(net 1166 "unconnected-(U19-GPIN7-Pad1)")
	(net 1167 "unconnected-(U19-GPOUT0-Pad4)")
	(net 1168 "unconnected-(U19-GPOUT1-Pad5)")
	(net 1169 "unconnected-(U19-GPOUT2-Pad6)")
	(net 1170 "unconnected-(U19-GPOUT3-Pad7)")
	(net 1171 "unconnected-(U19-GPOUT4-Pad8)")
	(net 1172 "unconnected-(U19-GPOUT5-Pad9)")
	(net 1173 "unconnected-(U19-GPOUT6-Pad10)")
	(net 1174 "unconnected-(U19-GPOUT7-Pad11)")
	(net 1175 "unconnected-(U19-GPIN0-Pad26)")
	(net 1176 "unconnected-(U19-GPIN1-Pad27)")
	(net 1177 "unconnected-(U19-GPIN2-Pad28)")
	(net 1178 "unconnected-(U19-GPIN3-Pad29)")
	(net 1179 "unconnected-(U19-GPIN4-Pad30)")
	(net 1180 "unconnected-(U19-GPIN5-Pad31)")
	(net 1181 "unconnected-(U19-GPIN6-Pad32)")
	(net 1182 "unconnected-(U20-ADBUS4-Pad17)")
	(net 1183 "unconnected-(U20-ADBUS6-Pad19)")
	(net 1184 "unconnected-(U20-ADBUS7-Pad20)")
	(net 1185 "unconnected-(U20-BDBUS6-Pad28)")
	(net 1186 "unconnected-(U20-BDBUS7-Pad29)")
	(net 1187 "unconnected-(U20-~{SUSPEND}-Pad30)")
	(net 1188 "unconnected-(U20-CDBUS2-Pad34)")
	(net 1189 "unconnected-(U20-CDBUS3-Pad35)")
	(net 1190 "unconnected-(U20-CDBUS4-Pad37)")
	(net 1191 "/DC-DC Converters/+0V675_EN")
	(net 1192 "Net-(F1-Pad1)")
	(net 1193 "unconnected-(U1B-IO_L2P_T0_AD8P_15-PadL22)")
	(net 1194 "unconnected-(U1B-IO_L2N_T0_AD8N_15-PadL23)")
	(net 1195 "unconnected-(D33-Pad2)")
	(net 1196 "unconnected-(U20-CDBUS5-Pad38)")
	(net 1197 "unconnected-(U20-CDBUS6-Pad39)")
	(net 1198 "unconnected-(U20-CDBUS7-Pad40)")
	(net 1199 "unconnected-(U20-DDBUS2-Pad47)")
	(net 1200 "unconnected-(U20-DDBUS3-Pad48)")
	(net 1201 "unconnected-(U20-DDBUS4-Pad49)")
	(net 1202 "unconnected-(U20-DDBUS5-Pad51)")
	(net 1203 "unconnected-(U20-DDBUS6-Pad52)")
	(net 1204 "unconnected-(U20-DDBUS7-Pad53)")
	(net 1205 "Net-(D38-Pad1)")
	(net 1206 "unconnected-(U22-NC-Pad6)")
	(net 1207 "unconnected-(U22-NC-Pad9)")
	(net 1208 "unconnected-(U23-NC-Pad6)")
	(net 1209 "unconnected-(SW3-Pad1)")
	(net 1210 "unconnected-(SW3-Pad2)")
	(net 1211 "unconnected-(SW3-Pad15)")
	(net 1212 "unconnected-(SW3-Pad16)")
	(net 1213 "/DC-DC Converters/SENSE_5V_N")
	(net 1214 "/DC-DC Converters/SENSE_5V_P")
	(net 1215 "/DC-DC Converters/SENSE_1V35_N")
	(net 1216 "/DC-DC Converters/SENSE_1V35_P")
	(net 1217 "/DC-DC Converters/SENSE_3V3_1_N")
	(net 1218 "/DC-DC Converters/SENSE_3V3_2_N")
	(net 1219 "/DC-DC Converters/SENSE_3V3_1_P")
	(net 1220 "/DC-DC Converters/SENSE_3V3_2_P")
	(net 1221 "/DC-DC Converters/SENSE_1V0_P")
	(net 1222 "/DC-DC Converters/SENSE_1V0_N")
	(net 1223 "/DC-DC Converters/SENSE_1V8_N")
	(net 1224 "/DC-DC Converters/SENSE_1V8_P")
	(net 1225 "/DC-DC Converters/SENSE_1V2_N")
	(net 1226 "/DC-DC Converters/SENSE_1V2_P")
	(net 1227 "Net-(C198-Pad2)")
	(net 1228 "/USER_IO.BUTTON0")
	(net 1229 "unconnected-(U23-NC-Pad9)")
	(net 1230 "Net-(C364-Pad1)")
	(net 1231 "Net-(C366-Pad2)")
	(net 1232 "/USER_IO.BUTTON3")
	(net 1233 "/USER_IO.BUTTON2")
	(net 1234 "/USER_IO.A1")
	(net 1235 "/USER_IO.A3")
	(net 1236 "/USER_IO.A5")
	(net 1237 "/USER_IO.A7")
	(net 1238 "/USER_IO.A9")
	(net 1239 "/USER_IO.A11")
	(net 1240 "/USER_IO.A12")
	(net 1241 "/USER_IO.A13")
	(net 1242 "/USER_IO.A14")
	(net 1243 "/USER_IO.A15")
	(net 1244 "/PLL.CLK0")
	(net 1245 "/USER_IO.A16")
	(net 1246 "/USER_IO.A17")
	(net 1247 "/USER_IO.A18")
	(net 1248 "/USER_IO.A21")
	(net 1249 "/USER_IO.A23")
	(net 1250 "/USER_IO.A24")
	(net 1251 "/USER_IO.A25")
	(net 1252 "/USER_IO.A26")
	(net 1253 "/USER_IO.A27")
	(net 1254 "/USER_IO.A28")
	(net 1255 "/USER_IO.A29")
	(net 1256 "/USER_IO.A30")
	(net 1257 "/USER_IO.A31")
	(net 1258 "/USER_IO.A32")
	(net 1259 "/USER_IO.A33")
	(net 1260 "/USER_IO.A35")
	(net 1261 "/USER_IO.A36")
	(net 1262 "/USER_IO.A37")
	(net 1263 "/USER_IO.A38")
	(net 1264 "/USER_IO.A39")
	(net 1265 "/USER_IO.A40")
	(net 1266 "/USER_IO.B1")
	(net 1267 "/USER_IO.B3")
	(net 1268 "/USER_IO.B5")
	(net 1269 "/USER_IO.B6")
	(net 1270 "/USER_IO.B7")
	(net 1271 "/USER_IO.B8")
	(net 1272 "/USER_IO.B9")
	(net 1273 "/USER_IO.B10")
	(net 1274 "/USER_IO.B11")
	(net 1275 "/USER_IO.B12")
	(net 1276 "/USER_IO.B14")
	(net 1277 "/USER_IO.B15")
	(net 1278 "/USER_IO.B16")
	(net 1279 "/USER_IO.B17")
	(net 1280 "/USER_IO.B18")
	(net 1281 "/USER_IO.B19")
	(net 1282 "/USER_IO.B21")
	(net 1283 "/USER_IO.B23")
	(net 1284 "/USER_IO.B24")
	(net 1285 "/USER_IO.B25")
	(net 1286 "/USER_IO.B26")
	(net 1287 "/USER_IO.B27")
	(net 1288 "/USER_IO.B28")
	(net 1289 "/USER_IO.B29")
	(net 1290 "/USER_IO.B30")
	(net 1291 "/USER_IO.B31")
	(net 1292 "/USER_IO.B32")
	(net 1293 "/USER_IO.B33")
	(net 1294 "/USB_SPI.MISO")
	(net 1295 "/USB_SPI.MOSI")
	(net 1296 "/USB_SPI.SCK")
	(net 1297 "/USB_SPI.~{CS}")
	(net 1298 "unconnected-(U1B-IO_L24P_T3_RS1_15-PadM22)")
	(net 1299 "/USER_IO.LED_GREEN0")
	(net 1300 "/USER_IO.LED_GREEN1")
	(net 1301 "/USER_IO.LED_GREEN2")
	(net 1302 "/USER_IO.LED_GREEN3")
	(net 1303 "/USER_IO.LED_GREEN4")
	(net 1304 "/USER_IO.LED_GREEN5")
	(net 1305 "/USER_IO.LED_RED")
	(net 1306 "unconnected-(U24-NC-Pad6)")
	(net 1307 "/USER_IO.LED_BLUE")
	(net 1308 "/USER_IO.DIP_SW3")
	(net 1309 "/USER_IO.DIP_SW2")
	(net 1310 "/USER_IO.DIP_SW1")
	(net 1311 "/USER_IO.DIP_SW0")
	(net 1312 "/SUP_MCU.FPGA_M0")
	(net 1313 "/SUP_MCU.FPGA_M1")
	(net 1314 "/SUP_MCU.FPGA_M2")
	(net 1315 "/SUP_MCU.DONE")
	(net 1316 "/SUP_MCU.INITB")
	(net 1317 "/SUP_MCU.PROGRAMB")
	(net 1318 "/USER_IO.DIP_SW7")
	(net 1319 "/SUP_MCU.MISO")
	(net 1320 "/USER_IO.DIP_SW6")
	(net 1321 "/SUP_MCU.MOSI")
	(net 1322 "/USER_IO.DIP_SW5")
	(net 1323 "/SUP_MCU.SCLK0")
	(net 1324 "/USER_IO.DIP_SW4")
	(net 1325 "/SUP_MCU.~{SCS}")
	(net 1326 "/SUP_MCU.FPGA_MISO")
	(net 1327 "/SUP_MCU.FPGA_MOSI")
	(net 1328 "/SUP_MCU.TX1")
	(net 1329 "/SUP_MCU.TX0")
	(net 1330 "/SUP_MCU.RX1")
	(net 1331 "/SUP_MCU.RX0")
	(net 1332 "/SUP_MCU.CCLK")
	(net 1333 "unconnected-(U1B-IO_L23P_T3_FOE_B_15-PadM24)")
	(net 1334 "/SUP_MCU.CFG_CS")
	(net 1335 "/SUP_MCU.TEMP_ALERT_N")
	(net 1336 "/I2C.SDA")
	(net 1337 "/SUP_MCU.SDA")
	(net 1338 "/I2C.SCL")
	(net 1339 "/SUP_MCU.SCL")
	(net 1340 "/SUP_MCU.SW_STATE")
	(net 1341 "unconnected-(U1B-IO_L23N_T3_FWE_B_15-PadM25)")
	(net 1342 "unconnected-(U1B-IO_L19N_T3_A21_VREF_15-PadN20)")
	(net 1343 "unconnected-(U1B-IO_L20P_T3_A20_15-PadN21)")
	(net 1344 "unconnected-(U1B-IO_L20N_T3_A19_15-PadN22)")
	(net 1345 "unconnected-(U1B-IO_L21N_T3_DQS_A18_15-PadN24)")
	(net 1346 "unconnected-(U1B-IO_L18P_T2_A24_15-PadN25)")
	(net 1347 "unconnected-(U1B-IO_25_15-PadP19)")
	(net 1348 "unconnected-(U1B-IO_L21P_T3_DQS_15-PadP23)")
	(net 1349 "/SUP_MCU.PD_RST")
	(net 1350 "/SUP_MCU.FAN_PWM")
	(net 1351 "/SUP_MCU.A0")
	(net 1352 "/SUP_MCU.A13")
	(net 1353 "/SUP_MCU.A1")
	(net 1354 "/SUP_MCU.A7")
	(net 1355 "/SUP_MCU.A16")
	(net 1356 "/SUP_MCU.A18")
	(net 1357 "unconnected-(U24-NC-Pad9)")
	(net 1358 "/SUP_MCU.A2")
	(net 1359 "/SUP_MCU.A5")
	(net 1360 "/SUP_MCU.A3")
	(net 1361 "/SUP_MCU.A4")
	(net 1362 "/SUP_MCU.A6")
	(net 1363 "/SUP_MCU.A17")
	(net 1364 "/SUP_MCU.A15")
	(net 1365 "/SUP_MCU.CLKO")
	(net 1366 "/SUP_MCU.A14")
	(net 1367 "/SUP_MCU.A19")
	(net 1368 "unconnected-(U24-B2Y-Pad12)")
	(net 1369 "/SUP_MCU.A10")
	(net 1370 "/SUP_MCU.A11")
	(net 1371 "/SUP_MCU.A12")
	(net 1372 "/SUP_MCU.D0")
	(net 1373 "/SUP_MCU.D3")
	(net 1374 "/SUP_MCU.D6")
	(net 1375 "/SUP_MCU.D7")
	(net 1376 "/SUP_MCU.CE")
	(net 1377 "/SUP_MCU.SPARE0")
	(net 1378 "/SUP_MCU.A8")
	(net 1379 "/SUP_MCU.D2")
	(net 1380 "/SUP_MCU.D5")
	(net 1381 "/SUP_MCU.D4")
	(net 1382 "/SUP_MCU.D1")
	(net 1383 "/SUP_MCU.SPARE1")
	(net 1384 "/SUP_MCU.SPARE2")
	(net 1385 "/SUP_MCU.SPARE3")
	(net 1386 "/SUP_MCU.SCLK1")
	(net 1387 "/SUP_MCU.PG_3V3")
	(net 1388 "/SUP_MCU.WR")
	(net 1389 "/SUP_MCU.PG_VCCINT")
	(net 1390 "/SUP_MCU.RD")
	(net 1391 "/SUP_MCU.A9")
	(net 1392 "/SUP_MCU.ALE")
	(net 1393 "/I2C.QDCDC2_SCL")
	(net 1394 "/I2C.QDCDC1_SCL")
	(net 1395 "unconnected-(U1I-VP_0-PadR15)")
	(net 1396 "unconnected-(U1I-VN_0-PadT14)")
	(net 1397 "/FPGA Bank 12 & 13/USB_USER.VM")
	(net 1398 "unconnected-(U1D-IO_L24N_T3_32-PadY15)")
	(net 1399 "unconnected-(U1D-IO_L24P_T3_32-PadY16)")
	(net 1400 "unconnected-(U1D-IO_L15N_T2_DQS_32-PadY18)")
	(net 1401 "unconnected-(U1A-IO_0_13-PadY25)")
	(net 1402 "/PLL.CLK2")
	(net 1403 "/PLL.CLK1")
	(net 1404 "unconnected-(U27-LDO_O-Pad43)")
	(net 1405 "unconnected-(U31-SW2-Pad11)")
	(net 1406 "unconnected-(U31-SW1-Pad12)")
	(net 1407 "unconnected-(U42-S1{slash}A1-Pad2)")
	(net 1408 "unconnected-(U42-Y2-Pad15)")
	(net 1409 "unconnected-(U42-Y3-Pad16)")
	(net 1410 "unconnected-(U42-Y5-Pad20)")
	(net 1411 "unconnected-(U44-NC-Pad4)")
	(net 1412 "unconnected-(Y6-NC-Pad2)")
	(net 1413 "/SUP_MCU.PG_1V2")
	(footprint "antmicro-footprints:C_0402_1005Metric"
		(layer "F.Cu")
		(at 195.803752 91.5615)
		(descr "Capacitor SMD 0402")
		(tags "capacitor SMD 0402")
		(property "Reference" "C286"
			(at -1.628752 -0.4365 0)
			(layer "F.SilkS")
			(effects
				(font
					(size 0.7 0.7)
					(thickness 0.15)
				)
				(justify left bottom)
			)
		)
		(property "Value" "C_100n_0402"
			(at 0 1.169 0)
			(layer "F.Fab")
			(effects
				(font
					(size 0.7 0.7)
					(thickness 0.15)
				)
				(justify left bottom)
			)
		)
		(property "Description" "SMD Multilayer Ceramic Capacitor, 0.1 µF, 50 V, 0402 [1005 Metric], ± 10%, X5R, GRM Series"
			(at 0 0 0)
			(layer "F.Fab")
			(hide yes)
			(effects
				(font
					(size 1.27 1.27)
					(thickness 0.15)
				)
			)
		)
		(property "Author" "Antmicro"
			(at 0 0 0)
			(layer "F.Fab")
			(hide yes)
			(effects
				(font
					(size 1 1)
					(thickness 0.15)
				)
			)
		)
		(property "Dielectric" "X5R"
			(at 0 0 0)
			(layer "F.Fab")
			(hide yes)
			(effects
				(font
					(size 1 1)
					(thickness 0.15)
				)
			)
		)
		(property "License" "Apache-2.0"
			(at 0 0 0)
			(layer "F.Fab")
			(hide yes)
			(effects
				(font
					(size 1 1)
					(thickness 0.15)
				)
			)
		)
		(property "MPN" "GRM155R61H104KE14D"
			(at 0 0 0)
			(layer "F.Fab")
			(hide yes)
			(effects
				(font
					(size 1 1)
					(thickness 0.15)
				)
			)
		)
		(property "Manufacturer" "Murata"
			(at 0 0 0)
			(layer "F.Fab")
			(hide yes)
			(effects
				(font
					(size 1 1)
					(thickness 0.15)
				)
			)
		)
		(property "Val" "100n"
			(at 0 0 0)
			(layer "F.Fab")
			(hide yes)
			(effects
				(font
					(size 1 1)
					(thickness 0.15)
				)
			)
		)
		(property "Voltage" "50V"
			(at 0 0 0)
			(layer "F.Fab")
			(hide yes)
			(effects
				(font
					(size 1 1)
					(thickness 0.15)
				)
			)
		)
		(sheetname "HDMI + Ethernet")
		(sheetfile "hdmi-ethernet.kicad_sch")
		(attr smd)
		(fp_rect
			(start -0.925 -0.47)
			(end 0.925 0.47)
			(stroke
				(width 0.05)
				(type default)
			)
			(fill no)
			(layer "F.CrtYd")
		)
		(fp_line
			(start -0.494 -0.25)
			(end 0.504 -0.25)
			(stroke
				(width 0.15)
				(type solid)
			)
			(layer "F.Fab")
		)
		(fp_line
			(start -0.494 0.248)
			(end -0.494 -0.25)
			(stroke
				(width 0.15)
				(type solid)
			)
			(layer "F.Fab")
		)
		(fp_line
			(start 0.504 -0.25)
			(end 0.504 0.248)
			(stroke
				(width 0.15)
				(type solid)
			)
			(layer "F.Fab")
		)
		(fp_line
			(start 0.504 0.248)
			(end -0.494 0.248)
			(stroke
				(width 0.15)
				(type solid)
			)
			(layer "F.Fab")
		)
		(pad "1" smd roundrect
			(at -0.48 0)
			(size 0.59 0.64)
			(layers "F.Cu" "F.Mask" "F.Paste")
			(roundrect_rratio 0.25)
			(net 1 "GND")
			(pintype "passive")
		)
		(pad "2" smd roundrect
			(at 0.48 0)
			(size 0.59 0.64)
			(layers "F.Cu" "F.Mask" "F.Paste")
			(roundrect_rratio 0.25)
			(net 727 "+1V2")
			(pintype "passive")
		)
	)
	(footprint "antmicro-footprints:C_0402_1005Metric"
		(layer "F.Cu")
		(at 228.25 151.9 180)
		(descr "Capacitor SMD 0402")
		(tags "capacitor SMD 0402")
		(property "Reference" "C258"
			(at -1.85 -1.25 0)
			(layer "F.SilkS")
			(effects
				(font
					(size 0.7 0.7)
					(thickness 0.15)
				)
				(justify right bottom)
			)
		)
		(property "Value" "C_22p_0402"
			(at 0 1.4 0)
			(layer "F.Fab")
			(effects
				(font
					(size 0.7 0.7)
					(thickness 0.15)
				)
				(justify right bottom)
			)
		)
		(property "Description" "SMD Multilayer Ceramic Capacitor, 22 pF, 50 V, 0402 [1005 Metric], ± 5%, C0G / NP0, CC Series"
			(at 0 0 180)
			(layer "F.Fab")
			(hide yes)
			(effects
				(font
					(size 1.27 1.27)
					(thickness 0.15)
				)
			)
		)
		(property "Author" "Antmicro"
			(at 456.5 303.8 0)
			(layer "F.Fab")
			(hide yes)
			(effects
				(font
					(size 1 1)
					(thickness 0.15)
				)
			)
		)
		(property "Dielectric" ""
			(at 456.5 303.8 0)
			(layer "F.Fab")
			(hide yes)
			(effects
				(font
					(size 1 1)
					(thickness 0.15)
				)
			)
		)
		(property "License" "Apache-2.0"
			(at 456.5 303.8 0)
			(layer "F.Fab")
			(hide yes)
			(effects
				(font
					(size 1 1)
					(thickness 0.15)
				)
			)
		)
		(property "MPN" "CC0402JRNPO9BN220"
			(at 456.5 303.8 0)
			(layer "F.Fab")
			(hide yes)
			(effects
				(font
					(size 1 1)
					(thickness 0.15)
				)
			)
		)
		(property "Manufacturer" "YAGEO"
			(at 456.5 303.8 0)
			(layer "F.Fab")
			(hide yes)
			(effects
				(font
					(size 1 1)
					(thickness 0.15)
				)
			)
		)
		(property "Val" "22p"
			(at 456.5 303.8 0)
			(layer "F.Fab")
			(hide yes)
			(effects
				(font
					(size 1 1)
					(thickness 0.15)
				)
			)
		)
		(property "Voltage" ""
			(at 456.5 303.8 0)
			(layer "F.Fab")
			(hide yes)
			(effects
				(font
					(size 1 1)
					(thickness 0.15)
				)
			)
		)
		(sheetname "HDMI + Ethernet")
		(sheetfile "hdmi-ethernet.kicad_sch")
		(attr smd)
		(fp_rect
			(start -0.925 -0.47)
			(end 0.925 0.47)
			(stroke
				(width 0.05)
				(type default)
			)
			(fill no)
			(layer "F.CrtYd")
		)
		(fp_line
			(start 0.504 0.248)
			(end -0.494 0.248)
			(stroke
				(width 0.15)
				(type solid)
			)
			(layer "F.Fab")
		)
		(fp_line
			(start 0.504 -0.25)
			(end 0.504 0.248)
			(stroke
				(width 0.15)
				(type solid)
			)
			(layer "F.Fab")
		)
		(fp_line
			(start -0.494 0.248)
			(end -0.494 -0.25)
			(stroke
				(width 0.15)
				(type solid)
			)
			(layer "F.Fab")
		)
		(fp_line
			(start -0.494 -0.25)
			(end 0.504 -0.25)
			(stroke
				(width 0.15)
				(type solid)
			)
			(layer "F.Fab")
		)
		(pad "1" smd roundrect
			(at -0.48 0 180)
			(size 0.59 0.64)
			(layers "F.Cu" "F.Mask" "F.Paste")
			(roundrect_rratio 0.25)
			(net 1 "GND")
			(pintype "passive")
		)
		(pad "2" smd roundrect
			(at 0.48 0 180)
			(size 0.59 0.64)
			(layers "F.Cu" "F.Mask" "F.Paste")
			(roundrect_rratio 0.25)
			(net 719 "/HDMI + Ethernet/ETH_XO")
			(pintype "passive")
		)
	)
	(footprint "antmicro-footprints:LED_0603_1608Metric_G"
		(layer "F.Cu")
		(at 207.99 74.97 90)
		(descr "LED SMD 0603 Green")
		(tags "LED SMD 0603 Green")
		(property "Reference" "D1"
			(at -2.23 0.76 0)
			(layer "F.SilkS")
			(effects
				(font
					(size 0.7 0.7)
					(thickness 0.15)
				)
				(justify right bottom)
			)
		)
		(property "Value" "LED_G_0603_KP-1608CGCK"
			(at 0 1.6 90)
			(layer "F.Fab")
			(effects
				(font
					(size 0.7 0.7)
					(thickness 0.15)
				)
				(justify left bottom)
			)
		)
		(property "Description" "LED, Green, SMD, 0603, 20 mA, 2.1 V, 570 nm"
			(at 0 0 90)
			(layer "F.Fab")
			(hide yes)
			(effects
				(font
					(size 1.27 1.27)
					(thickness 0.15)
				)
			)
		)
		(property "Author" "Antmicro"
			(at 282.96 -133.02 0)
			(layer "F.Fab")
			(hide yes)
			(effects
				(font
					(size 1 1)
					(thickness 0.15)
				)
			)
		)
		(property "Color" "Green"
			(at 282.96 -133.02 0)
			(layer "F.Fab")
			(hide yes)
			(effects
				(font
					(size 1 1)
					(thickness 0.15)
				)
			)
		)
		(property "License" "Apache-2.0"
			(at 282.96 -133.02 0)
			(layer "F.Fab")
			(hide yes)
			(effects
				(font
					(size 1 1)
					(thickness 0.15)
				)
			)
		)
		(property "MPN" "KP-1608CGCK"
			(at 282.96 -133.02 0)
			(layer "F.Fab")
			(hide yes)
			(effects
				(font
					(size 1 1)
					(thickness 0.15)
				)
			)
		)
		(property "Manufacturer" "Kingbright"
			(at 282.96 -133.02 0)
			(layer "F.Fab")
			(hide yes)
			(effects
				(font
					(size 1 1)
					(thickness 0.15)
				)
			)
		)
		(sheetname "FPGA Config")
		(sheetfile "fpga-config.kicad_sch")
		(attr smd)
		(fp_line
			(start 0.22 -0.35)
			(end -0.22 -0.35)
			(stroke
				(width 0.15)
				(type solid)
			)
			(layer "F.SilkS")
		)
		(fp_line
			(start -1.18 -0.319)
			(end -1.18 0.321)
			(stroke
				(width 0.15)
				(type solid)
			)
			(layer "F.SilkS")
		)
		(fp_line
			(start 0.105328 0.001008)
			(end 0.24 0.001)
			(stroke
				(width 0.1)
				(type solid)
			)
			(layer "F.SilkS")
		)
		(fp_line
			(start -0.094672 0.001008)
			(end 0.105328 -0.198992)
			(stroke
				(width 0.1)
				(type solid)
			)
			(layer "F.SilkS")
		)
		(fp_line
			(start -0.094672 0.001008)
			(end -0.24 0.001008)
			(stroke
				(width 0.1)
				(type solid)
			)
			(layer "F.SilkS")
		)
		(fp_line
			(start 0.105328 0.201008)
			(end 0.105328 -0.198992)
			(stroke
				(width 0.1)
				(type solid)
			)
			(layer "F.SilkS")
		)
		(fp_line
			(start 0.105328 0.201008)
			(end -0.094672 0.001008)
			(stroke
				(width 0.1)
				(type solid)
			)
			(layer "F.SilkS")
		)
		(fp_line
			(start -0.094672 0.201008)
			(end -0.094672 -0.198992)
			(stroke
				(width 0.1)
				(type solid)
			)
			(layer "F.SilkS")
		)
		(fp_line
			(start 0.22 0.35)
			(end -0.22 0.35)
			(stroke
				(width 0.15)
				(type solid)
			)
			(layer "F.SilkS")
		)
		(fp_rect
			(start 1.25 0.65)
			(end -1.25 -0.65)
			(stroke
				(width 0.05)
				(type solid)
			)
			(fill no)
			(layer "F.CrtYd")
		)
		(fp_line
			(start 0.201 -0.202)
			(end -0.101 0)
			(stroke
				(width 0.15)
				(type solid)
			)
			(layer "F.Fab")
		)
		(fp_line
			(start -0.199 -0.202)
			(end -0.199 0.1)
			(stroke
				(width 0.15)
				(type solid)
			)
			(layer "F.Fab")
		)
		(fp_line
			(start 0.599 0)
			(end 0.201 0)
			(stroke
				(width 0.15)
				(type solid)
			)
			(layer "F.Fab")
		)
		(fp_line
			(start 0.201 0)
			(end 0.201 -0.202)
			(stroke
				(width 0.15)
				(type solid)
			)
			(layer "F.Fab")
		)
		(fp_line
			(start -0.101 0)
			(end 0.201 0.2)
			(stroke
				(width 0.15)
				(type solid)
			)
			(layer "F.Fab")
		)
		(fp_line
			(start -0.199 0)
			(end -0.597 0)
			(stroke
				(width 0.15)
				(type solid)
			)
			(layer "F.Fab")
		)
		(fp_line
			(start 0.201 0.2)
			(end 0.201 0)
			(stroke
				(width 0.15)
				(type solid)
			)
			(layer "F.Fab")
		)
		(fp_line
			(start -0.199 0.2)
			(end -0.199 0.1)
			(stroke
				(width 0.15)
				(type solid)
			)
			(layer "F.Fab")
		)
		(fp_rect
			(start 0.848 0.4)
			(end -0.85 -0.402)
			(stroke
				(width 0.15)
				(type solid)
			)
			(fill no)
			(layer "F.Fab")
		)
		(pad "1" smd roundrect
			(at -0.7 0 270)
			(size 0.8 1)
			(layers "F.Cu" "F.Mask" "F.Paste")
			(roundrect_rratio 0.2)
			(net 17 "Net-(D1-C)")
			(pinfunction "C")
			(pintype "passive")
		)
		(pad "2" smd roundrect
			(at 0.7 0 270)
			(size 0.8 1)
			(layers "F.Cu" "F.Mask" "F.Paste")
			(roundrect_rratio 0.2)
			(net 24 "+3V3")
			(pinfunction "A")
			(pintype "passive")
		)
	)
	(footprint "antmicro-footprints:R_0402_1005Metric"
		(layer "F.Cu")
		(at 224.4 154 90)
		(descr "Resistor SMD 0402")
		(tags "resistor SMD 0402")
		(property "Reference" "R244"
			(at -1.6 1.2 90)
			(layer "F.SilkS")
			(effects
				(font
					(size 0.7 0.7)
					(thickness 0.15)
				)
				(justify left bottom)
			)
		)
		(property "Value" "R_12k_0402"
			(at 0 1.4 90)
			(layer "F.Fab")
			(effects
				(font
					(size 0.7 0.7)
					(thickness 0.15)
				)
				(justify left bottom)
			)
		)
		(property "Description" "SMD Chip Resistor, 12 kohm, ± 1%, 62.5 mW, 0402 [1005 Metric], Thick Film, General Purpose"
			(at 0 0 90)
			(layer "F.Fab")
			(hide yes)
			(effects
				(font
					(size 1.27 1.27)
					(thickness 0.15)
				)
			)
		)
		(property "Author" "Antmicro"
			(at 378.4 -70.4 0)
			(layer "F.Fab")
			(hide yes)
			(effects
				(font
					(size 1 1)
					(thickness 0.15)
				)
			)
		)
		(property "License" "Apache-2.0"
			(at 378.4 -70.4 0)
			(layer "F.Fab")
			(hide yes)
			(effects
				(font
					(size 1 1)
					(thickness 0.15)
				)
			)
		)
		(property "MPN" "CR0402-FX-1202GLF"
			(at 378.4 -70.4 0)
			(layer "F.Fab")
			(hide yes)
			(effects
				(font
					(size 1 1)
					(thickness 0.15)
				)
			)
		)
		(property "Manufacturer" "Bourns"
			(at 378.4 -70.4 0)
			(layer "F.Fab")
			(hide yes)
			(effects
				(font
					(size 1 1)
					(thickness 0.15)
				)
			)
		)
		(property "Tolerance" "1%"
			(at 378.4 -70.4 0)
			(layer "F.Fab")
			(hide yes)
			(effects
				(font
					(size 1 1)
					(thickness 0.15)
				)
			)
		)
		(property "Val" "12k"
			(at 378.4 -70.4 0)
			(layer "F.Fab")
			(hide yes)
			(effects
				(font
					(size 1 1)
					(thickness 0.15)
				)
			)
		)
		(sheetname "HDMI + Ethernet")
		(sheetfile "hdmi-ethernet.kicad_sch")
		(attr smd)
		(fp_rect
			(start -0.925 -0.47)
			(end 0.925 0.47)
			(stroke
				(width 0.05)
				(type default)
			)
			(fill no)
			(layer "F.CrtYd")
		)
		(fp_rect
			(start -0.5 -0.25)
			(end 0.5 0.25)
			(stroke
				(width 0.15)
				(type solid)
			)
			(fill no)
			(layer "F.Fab")
		)
		(pad "1" smd roundrect
			(at -0.48 0 90)
			(size 0.59 0.64)
			(layers "F.Cu" "F.Mask" "F.Paste")
			(roundrect_rratio 0.25)
			(net 1 "GND")
			(pintype "passive")
		)
		(pad "2" smd roundrect
			(at 0.48 0 90)
			(size 0.59 0.64)
			(layers "F.Cu" "F.Mask" "F.Paste")
			(roundrect_rratio 0.25)
			(net 952 "/HDMI + Ethernet/ETH_ISET")
			(pintype "passive")
		)
	)
	(footprint "antmicro-footprints:R_0402_1005Metric"
		(layer "F.Cu")
		(at 228.517121 158 90)
		(descr "Resistor SMD 0402")
		(tags "resistor SMD 0402")
		(property "Reference" "R50"
			(at 2.175 0.382879 90)
			(layer "F.SilkS")
			(effects
				(font
					(size 0.7 0.7)
					(thickness 0.15)
				)
				(justify left bottom)
			)
		)
		(property "Value" "R_100k_0402"
			(at 0 1.4 90)
			(layer "F.Fab")
			(effects
				(font
					(size 0.7 0.7)
					(thickness 0.15)
				)
				(justify left bottom)
			)
		)
		(property "Description" "SMD Chip Resistor, 100 kohm, ± 1%, 62.5 mW, 0402 [1005 Metric], Thick Film, General Purpose"
			(at 0 0 90)
			(layer "F.Fab")
			(hide yes)
			(effects
				(font
					(size 1.27 1.27)
					(thickness 0.15)
				)
			)
		)
		(property "Author" "Antmicro"
			(at 386.517121 -70.517121 0)
			(layer "F.Fab")
			(hide yes)
			(effects
				(font
					(size 1 1)
					(thickness 0.15)
				)
			)
		)
		(property "License" "Apache-2.0"
			(at 386.517121 -70.517121 0)
			(layer "F.Fab")
			(hide yes)
			(effects
				(font
					(size 1 1)
					(thickness 0.15)
				)
			)
		)
		(property "MPN" "CR0402-FX-1003GLF"
			(at 386.517121 -70.517121 0)
			(layer "F.Fab")
			(hide yes)
			(effects
				(font
					(size 1 1)
					(thickness 0.15)
				)
			)
		)
		(property "Manufacturer" "Bourns"
			(at 386.517121 -70.517121 0)
			(layer "F.Fab")
			(hide yes)
			(effects
				(font
					(size 1 1)
					(thickness 0.15)
				)
			)
		)
		(property "Tolerance" "1%"
			(at 386.517121 -70.517121 0)
			(layer "F.Fab")
			(hide yes)
			(effects
				(font
					(size 1 1)
					(thickness 0.15)
				)
			)
		)
		(property "Val" "100k"
			(at 386.517121 -70.517121 0)
			(layer "F.Fab")
			(hide yes)
			(effects
				(font
					(size 1 1)
					(thickness 0.15)
				)
			)
		)
		(sheetname "Power supply")
		(sheetfile "power-supply.kicad_sch")
		(attr smd)
		(fp_rect
			(start -0.925 -0.47)
			(end 0.925 0.47)
			(stroke
				(width 0.05)
				(type default)
			)
			(fill no)
			(layer "F.CrtYd")
		)
		(fp_rect
			(start -0.5 -0.25)
			(end 0.5 0.25)
			(stroke
				(width 0.15)
				(type solid)
			)
			(fill no)
			(layer "F.Fab")
		)
		(pad "1" smd roundrect
			(at -0.48 0 90)
			(size 0.59 0.64)
			(layers "F.Cu" "F.Mask" "F.Paste")
			(roundrect_rratio 0.25)
			(net 872 "/Power supply/SINK_EN")
			(pintype "passive")
		)
		(pad "2" smd roundrect
			(at 0.48 0 90)
			(size 0.59 0.64)
			(layers "F.Cu" "F.Mask" "F.Paste")
			(roundrect_rratio 0.25)
			(net 5 "/Power supply/PD_VBUS")
			(pintype "passive")
		)
	)
	(footprint "antmicro-footprints:Vishay_PowerPAK_1212-8_Single"
		(layer "F.Cu")
		(at 190.225 187.699)
		(descr "PowerPAK 1212-8 Single")
		(tags "Vishay PowerPAK 1212-8 Single")
		(property "Reference" "Q5"
			(at 2.925 1.851 90)
			(layer "F.SilkS")
			(effects
				(font
					(size 0.7 0.7)
					(thickness 0.15)
				)
				(justify left bottom)
			)
		)
		(property "Value" "SI7613DN-T1-GE3"
			(at -8 2.7 0)
			(layer "F.Fab")
			(effects
				(font
					(size 0.7 0.7)
					(thickness 0.15)
				)
				(justify left bottom)
			)
		)
		(property "Description" "Power MOSFET, P Channel, 20 V, 35 A, 0.0072 ohm, PowerPAK 1212, Surface Mount"
			(at 0 0 0)
			(layer "F.Fab")
			(hide yes)
			(effects
				(font
					(size 1.27 1.27)
					(thickness 0.15)
				)
			)
		)
		(property "Author" "Antmicro"
			(at 0 0 0)
			(layer "F.Fab")
			(hide yes)
			(effects
				(font
					(size 1 1)
					(thickness 0.15)
				)
			)
		)
		(property "License" "Apache-2.0"
			(at 0 0 0)
			(layer "F.Fab")
			(hide yes)
			(effects
				(font
					(size 1 1)
					(thickness 0.15)
				)
			)
		)
		(property "MPN" "SI7613DN-T1-GE3"
			(at 0 0 0)
			(layer "F.Fab")
			(hide yes)
			(effects
				(font
					(size 1 1)
					(thickness 0.15)
				)
			)
		)
		(property "Manufacturer" "Vishay"
			(at 0 0 0)
			(layer "F.Fab")
			(hide yes)
			(effects
				(font
					(size 1 1)
					(thickness 0.15)
				)
			)
		)
		(sheetname "Power supply")
		(sheetfile "power-supply.kicad_sch")
		(attr smd)
		(fp_line
			(start -1.651 -1.651)
			(end -1.651 -1.317)
			(stroke
				(width 0.15)
				(type solid)
			)
			(layer "F.SilkS")
		)
		(fp_line
			(start -1.651 -1.651)
			(end 1.648 -1.651)
			(stroke
				(width 0.15)
				(type solid)
			)
			(layer "F.SilkS")
		)
		(fp_line
			(start -1.635 1.3)
			(end -1.635 1.634)
			(stroke
				(width 0.15)
				(type solid)
			)
			(layer "F.SilkS")
		)
		(fp_line
			(start -1.635 1.634)
			(end 1.634 1.634)
			(stroke
				(width 0.15)
				(type solid)
			)
			(layer "F.SilkS")
		)
		(fp_line
			(start 1.634 1.3)
			(end 1.634 1.634)
			(stroke
				(width 0.15)
				(type solid)
			)
			(layer "F.SilkS")
		)
		(fp_line
			(start 1.648 -1.651)
			(end 1.648 -1.317)
			(stroke
				(width 0.15)
				(type solid)
			)
			(layer "F.SilkS")
		)
		(fp_circle
			(center -1.9 -1.4)
			(end -1.85 -1.4)
			(stroke
				(width 0.15)
				(type solid)
			)
			(fill yes)
			(layer "F.SilkS")
		)
		(fp_rect
			(start -2 -1.8)
			(end 2 1.798)
			(stroke
				(width 0.05)
				(type solid)
			)
			(fill no)
			(layer "F.CrtYd")
		)
		(fp_line
			(start -1.6425 -1.4175)
			(end -1.4175 -1.6425)
			(stroke
				(width 0.15)
				(type solid)
			)
			(layer "F.Fab")
		)
		(fp_rect
			(start -1.651 -1.651)
			(end 1.648 1.648)
			(stroke
				(width 0.15)
				(type solid)
			)
			(fill no)
			(layer "F.Fab")
		)
		(pad "1" smd rect
			(at -1.436 -0.99)
			(size 0.99 0.405)
			(layers "F.Cu" "F.Mask" "F.Paste")
			(net 702 "VDC")
			(pinfunction "S")
			(pintype "passive")
		)
		(pad "2" smd rect
			(at -1.436 -0.332)
			(size 0.99 0.405)
			(layers "F.Cu" "F.Mask" "F.Paste")
			(net 702 "VDC")
			(pinfunction "S")
			(pintype "passive")
		)
		(pad "3" smd rect
			(at -1.436 0.33)
			(size 0.99 0.405)
			(layers "F.Cu" "F.Mask" "F.Paste")
			(net 702 "VDC")
			(pinfunction "S")
			(pintype "passive")
		)
		(pad "4" smd rect
			(at -1.436 0.988)
			(size 0.99 0.405)
			(layers "F.Cu" "F.Mask" "F.Paste")
			(net 338 "Net-(Q5-G)")
			(pinfunction "G")
			(pintype "passive")
		)
		(pad "5" smd custom
			(at 0.557 0)
			(size 1.725 2.235)
			(layers "F.Cu" "F.Mask" "F.Paste")
			(net 4 "/Power supply/DC_IN")
			(pinfunction "D")
			(pintype "passive")
			(zone_connect 2)
			(options
				(clearance outline)
				(anchor rect)
			)
			(primitives
				(gr_poly
					(pts
						(xy 0.8625 0.1275) (xy 0.8625 -0.1275) (xy 1.3725 -0.1275) (xy 1.3725 -0.5325) (xy 0.8625 -0.5325)
						(xy 0.8625 -0.7875) (xy 1.3725 -0.7875) (xy 1.3725 -1.195) (xy 0.6125 -1.195) (xy 0.6125 1.195)
						(xy 1.3725 1.195) (xy 1.3725 0.7875) (xy 0.8625 0.7875) (xy 0.8625 0.5325) (xy 1.3725 0.5325)
						(xy 1.3725 0.1275)
					)
					(width 0)
					(fill yes)
				)
			)
		)
	)
	(footprint "antmicro-footprints:C_0402_1005Metric"
		(layer "F.Cu")
		(at 154.2 157 180)
		(descr "Capacitor SMD 0402")
		(tags "capacitor SMD 0402")
		(property "Reference" "C399"
			(at -0.95 -1.4 0)
			(layer "F.SilkS")
			(effects
				(font
					(size 0.7 0.7)
					(thickness 0.15)
				)
				(justify right bottom)
			)
		)
		(property "Value" "C_100n_0402"
			(at 0 1.4 0)
			(layer "F.Fab")
			(effects
				(font
					(size 0.7 0.7)
					(thickness 0.15)
				)
				(justify right bottom)
			)
		)
		(property "Description" "SMD Multilayer Ceramic Capacitor, 0.1 µF, 50 V, 0402 [1005 Metric], ± 10%, X5R, GRM Series"
			(at 0 0 180)
			(layer "F.Fab")
			(hide yes)
			(effects
				(font
					(size 1.27 1.27)
					(thickness 0.15)
				)
			)
		)
		(property "Author" "Antmicro"
			(at 308.4 314 0)
			(layer "F.Fab")
			(hide yes)
			(effects
				(font
					(size 1 1)
					(thickness 0.15)
				)
			)
		)
		(property "Dielectric" "X5R"
			(at 308.4 314 0)
			(layer "F.Fab")
			(hide yes)
			(effects
				(font
					(size 1 1)
					(thickness 0.15)
				)
			)
		)
		(property "License" "Apache-2.0"
			(at 308.4 314 0)
			(layer "F.Fab")
			(hide yes)
			(effects
				(font
					(size 1 1)
					(thickness 0.15)
				)
			)
		)
		(property "MPN" "GRM155R61H104KE14D"
			(at 308.4 314 0)
			(layer "F.Fab")
			(hide yes)
			(effects
				(font
					(size 1 1)
					(thickness 0.15)
				)
			)
		)
		(property "Manufacturer" "Murata"
			(at 308.4 314 0)
			(layer "F.Fab")
			(hide yes)
			(effects
				(font
					(size 1 1)
					(thickness 0.15)
				)
			)
		)
		(property "Val" "100n"
			(at 308.4 314 0)
			(layer "F.Fab")
			(hide yes)
			(effects
				(font
					(size 1 1)
					(thickness 0.15)
				)
			)
		)
		(property "Voltage" "50V"
			(at 308.4 314 0)
			(layer "F.Fab")
			(hide yes)
			(effects
				(font
					(size 1 1)
					(thickness 0.15)
				)
			)
		)
		(sheetname "DC-DC Converters")
		(sheetfile "dc-dc.kicad_sch")
		(attr smd)
		(fp_rect
			(start -0.925 -0.47)
			(end 0.925 0.47)
			(stroke
				(width 0.05)
				(type default)
			)
			(fill no)
			(layer "F.CrtYd")
		)
		(fp_line
			(start 0.504 0.248)
			(end -0.494 0.248)
			(stroke
				(width 0.15)
				(type solid)
			)
			(layer "F.Fab")
		)
		(fp_line
			(start 0.504 -0.25)
			(end 0.504 0.248)
			(stroke
				(width 0.15)
				(type solid)
			)
			(layer "F.Fab")
		)
		(fp_line
			(start -0.494 0.248)
			(end -0.494 -0.25)
			(stroke
				(width 0.15)
				(type solid)
			)
			(layer "F.Fab")
		)
		(fp_line
			(start -0.494 -0.25)
			(end 0.504 -0.25)
			(stroke
				(width 0.15)
				(type solid)
			)
			(layer "F.Fab")
		)
		(pad "1" smd roundrect
			(at -0.48 0 180)
			(size 0.59 0.64)
			(layers "F.Cu" "F.Mask" "F.Paste")
			(roundrect_rratio 0.25)
			(net 1 "GND")
			(pintype "passive")
		)
		(pad "2" smd roundrect
			(at 0.48 0 180)
			(size 0.59 0.64)
			(layers "F.Cu" "F.Mask" "F.Paste")
			(roundrect_rratio 0.25)
			(net 24 "+3V3")
			(pintype "passive")
		)
	)
	(footprint "antmicro-footprints:R_0402_1005Metric"
		(layer "F.Cu")
		(at 228.517121 159.7)
		(descr "Resistor SMD 0402")
		(tags "resistor SMD 0402")
		(property "Reference" "R56"
			(at -1.067121 1.2 0)
			(layer "F.SilkS")
			(effects
				(font
					(size 0.7 0.7)
					(thickness 0.15)
				)
				(justify left bottom)
			)
		)
		(property "Value" "R_1k_0402"
			(at 0 1.4 0)
			(layer "F.Fab")
			(effects
				(font
					(size 0.7 0.7)
					(thickness 0.15)
				)
				(justify left bottom)
			)
		)
		(property "Description" "SMD Chip Resistor, 1 kohm, ± 1%, 63 mW, 0402 [1005 Metric], Thick Film, General Purpose"
			(at 0 0 0)
			(layer "F.Fab")
			(hide yes)
			(effects
				(font
					(size 1.27 1.27)
					(thickness 0.15)
				)
			)
		)
		(property "Author" "Antmicro"
			(at 0 0 0)
			(layer "F.Fab")
			(hide yes)
			(effects
				(font
					(size 1 1)
					(thickness 0.15)
				)
			)
		)
		(property "License" "Apache-2.0"
			(at 0 0 0)
			(layer "F.Fab")
			(hide yes)
			(effects
				(font
					(size 1 1)
					(thickness 0.15)
				)
			)
		)
		(property "MPN" "CR0402-FX-1001GLF"
			(at 0 0 0)
			(layer "F.Fab")
			(hide yes)
			(effects
				(font
					(size 1 1)
					(thickness 0.15)
				)
			)
		)
		(property "Manufacturer" "Bourns"
			(at 0 0 0)
			(layer "F.Fab")
			(hide yes)
			(effects
				(font
					(size 1 1)
					(thickness 0.15)
				)
			)
		)
		(property "Tolerance" "1%"
			(at 0 0 0)
			(layer "F.Fab")
			(hide yes)
			(effects
				(font
					(size 1 1)
					(thickness 0.15)
				)
			)
		)
		(property "Val" "1k"
			(at 0 0 0)
			(layer "F.Fab")
			(hide yes)
			(effects
				(font
					(size 1 1)
					(thickness 0.15)
				)
			)
		)
		(sheetname "Power supply")
		(sheetfile "power-supply.kicad_sch")
		(attr smd)
		(fp_rect
			(start -0.925 -0.47)
			(end 0.925 0.47)
			(stroke
				(width 0.05)
				(type default)
			)
			(fill no)
			(layer "F.CrtYd")
		)
		(fp_rect
			(start -0.5 -0.25)
			(end 0.5 0.25)
			(stroke
				(width 0.15)
				(type solid)
			)
			(fill no)
			(layer "F.Fab")
		)
		(pad "1" smd roundrect
			(at -0.48 0)
			(size 0.59 0.64)
			(layers "F.Cu" "F.Mask" "F.Paste")
			(roundrect_rratio 0.25)
			(net 700 "/Power supply/USB_PD_VBUS")
			(pintype "passive")
		)
		(pad "2" smd roundrect
			(at 0.48 0)
			(size 0.59 0.64)
			(layers "F.Cu" "F.Mask" "F.Paste")
			(roundrect_rratio 0.25)
			(net 888 "/Power supply/PDBUS_DISCH")
			(pintype "passive")
		)
	)
	(footprint "antmicro-footprints:R_0402_1005Metric"
		(layer "F.Cu")
		(at 259.6 128.5 180)
		(descr "Resistor SMD 0402")
		(tags "resistor SMD 0402")
		(property "Reference" "R361"
			(at 1.05 5.8 180)
			(layer "F.SilkS")
			(effects
				(font
					(size 0.7 0.7)
					(thickness 0.15)
				)
				(justify left bottom)
			)
		)
		(property "Value" "R_5k1_0402"
			(at 0 1.4 180)
			(layer "F.Fab")
			(effects
				(font
					(size 0.7 0.7)
					(thickness 0.15)
				)
				(justify left bottom)
			)
		)
		(property "Description" "SMD Chip Resistor, 5.1 kohm, ± 1%, 63 mW, 0402 [1005 Metric], Thick Film, General Purpose"
			(at 0 0 180)
			(layer "F.Fab")
			(hide yes)
			(effects
				(font
					(size 1.27 1.27)
					(thickness 0.15)
				)
			)
		)
		(property "Author" "Antmicro"
			(at 519.2 257 0)
			(layer "F.Fab")
			(hide yes)
			(effects
				(font
					(size 1 1)
					(thickness 0.15)
				)
			)
		)
		(property "License" "Apache-2.0"
			(at 519.2 257 0)
			(layer "F.Fab")
			(hide yes)
			(effects
				(font
					(size 1 1)
					(thickness 0.15)
				)
			)
		)
		(property "MPN" "CR0402-FX-5101GLF"
			(at 519.2 257 0)
			(layer "F.Fab")
			(hide yes)
			(effects
				(font
					(size 1 1)
					(thickness 0.15)
				)
			)
		)
		(property "Manufacturer" "Bourns"
			(at 519.2 257 0)
			(layer "F.Fab")
			(hide yes)
			(effects
				(font
					(size 1 1)
					(thickness 0.15)
				)
			)
		)
		(property "Tolerance" "1%"
			(at 519.2 257 0)
			(layer "F.Fab")
			(hide yes)
			(effects
				(font
					(size 1 1)
					(thickness 0.15)
				)
			)
		)
		(property "Val" "5k1"
			(at 519.2 257 0)
			(layer "F.Fab")
			(hide yes)
			(effects
				(font
					(size 1 1)
					(thickness 0.15)
				)
			)
		)
		(sheetname "USB PHY")
		(sheetfile "usb-phy.kicad_sch")
		(attr smd)
		(fp_rect
			(start -0.925 -0.47)
			(end 0.925 0.47)
			(stroke
				(width 0.05)
				(type default)
			)
			(fill no)
			(layer "F.CrtYd")
		)
		(fp_rect
			(start -0.5 -0.25)
			(end 0.5 0.25)
			(stroke
				(width 0.15)
				(type solid)
			)
			(fill no)
			(layer "F.Fab")
		)
		(pad "1" smd roundrect
			(at -0.48 0 180)
			(size 0.59 0.64)
			(layers "F.Cu" "F.Mask" "F.Paste")
			(roundrect_rratio 0.25)
			(net 841 "/USB PHY/USB_USR_CC1")
			(pintype "passive")
		)
		(pad "2" smd roundrect
			(at 0.48 0 180)
			(size 0.59 0.64)
			(layers "F.Cu" "F.Mask" "F.Paste")
			(roundrect_rratio 0.25)
			(net 1 "GND")
			(pintype "passive")
		)
	)
	(footprint "antmicro-footprints:R_0402_1005Metric"
		(layer "F.Cu")
		(at 159.7 147.9 180)
		(descr "Resistor SMD 0402")
		(tags "resistor SMD 0402")
		(property "Reference" "R329"
			(at 0.9 -1.25 180)
			(layer "F.SilkS")
			(effects
				(font
					(size 0.7 0.7)
					(thickness 0.15)
				)
				(justify left bottom)
			)
		)
		(property "Value" "R_0R_0402"
			(at 0 1.4 180)
			(layer "F.Fab")
			(effects
				(font
					(size 0.7 0.7)
					(thickness 0.15)
				)
				(justify left bottom)
			)
		)
		(property "Description" "SMD Chip Resistor, Jumper, 0 ohm, 100 mW, 0402 [1005 Metric], Thick Film, General Purpose"
			(at 0 0 180)
			(layer "F.Fab")
			(hide yes)
			(effects
				(font
					(size 1.27 1.27)
					(thickness 0.15)
				)
			)
		)
		(property "Author" "Antmicro"
			(at 319.4 295.8 0)
			(layer "F.Fab")
			(hide yes)
			(effects
				(font
					(size 1 1)
					(thickness 0.15)
				)
			)
		)
		(property "Current" "1A"
			(at 319.4 295.8 0)
			(layer "F.Fab")
			(hide yes)
			(effects
				(font
					(size 1 1)
					(thickness 0.15)
				)
			)
		)
		(property "License" "Apache-2.0"
			(at 319.4 295.8 0)
			(layer "F.Fab")
			(hide yes)
			(effects
				(font
					(size 1 1)
					(thickness 0.15)
				)
			)
		)
		(property "MPN" "ERJ2GE0R00X"
			(at 319.4 295.8 0)
			(layer "F.Fab")
			(hide yes)
			(effects
				(font
					(size 1 1)
					(thickness 0.15)
				)
			)
		)
		(property "Manufacturer" "Panasonic"
			(at 319.4 295.8 0)
			(layer "F.Fab")
			(hide yes)
			(effects
				(font
					(size 1 1)
					(thickness 0.15)
				)
			)
		)
		(property "Tolerance" ""
			(at 319.4 295.8 0)
			(layer "F.Fab")
			(hide yes)
			(effects
				(font
					(size 1 1)
					(thickness 0.15)
				)
			)
		)
		(property "Val" "0R"
			(at 319.4 295.8 0)
			(layer "F.Fab")
			(hide yes)
			(effects
				(font
					(size 1 1)
					(thickness 0.15)
				)
			)
		)
		(sheetname "DC-DC Converters")
		(sheetfile "dc-dc.kicad_sch")
		(attr smd)
		(fp_rect
			(start -0.925 -0.47)
			(end 0.925 0.47)
			(stroke
				(width 0.05)
				(type default)
			)
			(fill no)
			(layer "F.CrtYd")
		)
		(fp_rect
			(start -0.5 -0.25)
			(end 0.5 0.25)
			(stroke
				(width 0.15)
				(type solid)
			)
			(fill no)
			(layer "F.Fab")
		)
		(pad "1" smd roundrect
			(at -0.48 0 180)
			(size 0.59 0.64)
			(layers "F.Cu" "F.Mask" "F.Paste")
			(roundrect_rratio 0.25)
			(net 869 "Net-(NT1-Pad1)")
			(pintype "passive")
		)
		(pad "2" smd roundrect
			(at 0.48 0 180)
			(size 0.59 0.64)
			(layers "F.Cu" "F.Mask" "F.Paste")
			(roundrect_rratio 0.25)
			(net 15 "Net-(U41-OUT)")
			(pintype "passive")
		)
	)
	(footprint "antmicro-footprints:C_0402_1005Metric"
		(layer "F.Cu")
		(at 235.925 116.525 180)
		(descr "Capacitor SMD 0402")
		(tags "capacitor SMD 0402")
		(property "Reference" "C209"
			(at -3.575 -0.325 180)
			(layer "F.SilkS")
			(effects
				(font
					(size 0.7 0.7)
					(thickness 0.15)
				)
				(justify right bottom)
			)
		)
		(property "Value" "C_100n_0402"
			(at 0 1.4 0)
			(layer "F.Fab")
			(effects
				(font
					(size 0.7 0.7)
					(thickness 0.15)
				)
				(justify right bottom)
			)
		)
		(property "Description" "SMD Multilayer Ceramic Capacitor, 0.1 µF, 50 V, 0402 [1005 Metric], ± 10%, X5R, GRM Series"
			(at 0 0 180)
			(layer "F.Fab")
			(hide yes)
			(effects
				(font
					(size 1.27 1.27)
					(thickness 0.15)
				)
			)
		)
		(property "Author" "Antmicro"
			(at 471.85 233.05 0)
			(layer "F.Fab")
			(hide yes)
			(effects
				(font
					(size 1 1)
					(thickness 0.15)
				)
			)
		)
		(property "Dielectric" "X5R"
			(at 471.85 233.05 0)
			(layer "F.Fab")
			(hide yes)
			(effects
				(font
					(size 1 1)
					(thickness 0.15)
				)
			)
		)
		(property "License" "Apache-2.0"
			(at 471.85 233.05 0)
			(layer "F.Fab")
			(hide yes)
			(effects
				(font
					(size 1 1)
					(thickness 0.15)
				)
			)
		)
		(property "MPN" "GRM155R61H104KE14D"
			(at 471.85 233.05 0)
			(layer "F.Fab")
			(hide yes)
			(effects
				(font
					(size 1 1)
					(thickness 0.15)
				)
			)
		)
		(property "Manufacturer" "Murata"
			(at 471.85 233.05 0)
			(layer "F.Fab")
			(hide yes)
			(effects
				(font
					(size 1 1)
					(thickness 0.15)
				)
			)
		)
		(property "Val" "100n"
			(at 471.85 233.05 0)
			(layer "F.Fab")
			(hide yes)
			(effects
				(font
					(size 1 1)
					(thickness 0.15)
				)
			)
		)
		(property "Voltage" "50V"
			(at 471.85 233.05 0)
			(layer "F.Fab")
			(hide yes)
			(effects
				(font
					(size 1 1)
					(thickness 0.15)
				)
			)
		)
		(sheetname "SPI Flash + SD Card")
		(sheetfile "spi-flash.kicad_sch")
		(attr smd)
		(fp_rect
			(start -0.925 -0.47)
			(end 0.925 0.47)
			(stroke
				(width 0.05)
				(type default)
			)
			(fill no)
			(layer "F.CrtYd")
		)
		(fp_line
			(start 0.504 0.248)
			(end -0.494 0.248)
			(stroke
				(width 0.15)
				(type solid)
			)
			(layer "F.Fab")
		)
		(fp_line
			(start 0.504 -0.25)
			(end 0.504 0.248)
			(stroke
				(width 0.15)
				(type solid)
			)
			(layer "F.Fab")
		)
		(fp_line
			(start -0.494 0.248)
			(end -0.494 -0.25)
			(stroke
				(width 0.15)
				(type solid)
			)
			(layer "F.Fab")
		)
		(fp_line
			(start -0.494 -0.25)
			(end 0.504 -0.25)
			(stroke
				(width 0.15)
				(type solid)
			)
			(layer "F.Fab")
		)
		(pad "1" smd roundrect
			(at -0.48 0 180)
			(size 0.59 0.64)
			(layers "F.Cu" "F.Mask" "F.Paste")
			(roundrect_rratio 0.25)
			(net 1 "GND")
			(pintype "passive")
		)
		(pad "2" smd roundrect
			(at 0.48 0 180)
			(size 0.59 0.64)
			(layers "F.Cu" "F.Mask" "F.Paste")
			(roundrect_rratio 0.25)
			(net 24 "+3V3")
			(pintype "passive")
		)
	)
	(footprint "antmicro-footprints:C_0402_1005Metric"
		(layer "F.Cu")
		(at 204.1625 98.9615 90)
		(descr "Capacitor SMD 0402")
		(tags "capacitor SMD 0402")
		(property "Reference" "C265"
			(at -9.0385 6.5375 90)
			(layer "F.SilkS")
			(effects
				(font
					(size 0.7 0.7)
					(thickness 0.15)
				)
				(justify left bottom)
			)
		)
		(property "Value" "C_100n_0402"
			(at 0 1.169 90)
			(layer "F.Fab")
			(effects
				(font
					(size 0.7 0.7)
					(thickness 0.15)
				)
				(justify left bottom)
			)
		)
		(property "Description" "SMD Multilayer Ceramic Capacitor, 0.1 µF, 50 V, 0402 [1005 Metric], ± 10%, X5R, GRM Series"
			(at 0 0 90)
			(layer "F.Fab")
			(hide yes)
			(effects
				(font
					(size 1.27 1.27)
					(thickness 0.15)
				)
			)
		)
		(property "Author" "Antmicro"
			(at 303.124 -105.201 0)
			(layer "F.Fab")
			(hide yes)
			(effects
				(font
					(size 1 1)
					(thickness 0.15)
				)
			)
		)
		(property "Dielectric" "X5R"
			(at 303.124 -105.201 0)
			(layer "F.Fab")
			(hide yes)
			(effects
				(font
					(size 1 1)
					(thickness 0.15)
				)
			)
		)
		(property "License" "Apache-2.0"
			(at 303.124 -105.201 0)
			(layer "F.Fab")
			(hide yes)
			(effects
				(font
					(size 1 1)
					(thickness 0.15)
				)
			)
		)
		(property "MPN" "GRM155R61H104KE14D"
			(at 303.124 -105.201 0)
			(layer "F.Fab")
			(hide yes)
			(effects
				(font
					(size 1 1)
					(thickness 0.15)
				)
			)
		)
		(property "Manufacturer" "Murata"
			(at 303.124 -105.201 0)
			(layer "F.Fab")
			(hide yes)
			(effects
				(font
					(size 1 1)
					(thickness 0.15)
				)
			)
		)
		(property "Val" "100n"
			(at 303.124 -105.201 0)
			(layer "F.Fab")
			(hide yes)
			(effects
				(font
					(size 1 1)
					(thickness 0.15)
				)
			)
		)
		(property "Voltage" "50V"
			(at 303.124 -105.201 0)
			(layer "F.Fab")
			(hide yes)
			(effects
				(font
					(size 1 1)
					(thickness 0.15)
				)
			)
		)
		(sheetname "HDMI + Ethernet")
		(sheetfile "hdmi-ethernet.kicad_sch")
		(attr smd)
		(fp_rect
			(start -0.925 -0.47)
			(end 0.925 0.47)
			(stroke
				(width 0.05)
				(type default)
			)
			(fill no)
			(layer "F.CrtYd")
		)
		(fp_line
			(start 0.504 -0.25)
			(end 0.504 0.248)
			(stroke
				(width 0.15)
				(type solid)
			)
			(layer "F.Fab")
		)
		(fp_line
			(start -0.494 -0.25)
			(end 0.504 -0.25)
			(stroke
				(width 0.15)
				(type solid)
			)
			(layer "F.Fab")
		)
		(fp_line
			(start 0.504 0.248)
			(end -0.494 0.248)
			(stroke
				(width 0.15)
				(type solid)
			)
			(layer "F.Fab")
		)
		(fp_line
			(start -0.494 0.248)
			(end -0.494 -0.25)
			(stroke
				(width 0.15)
				(type solid)
			)
			(layer "F.Fab")
		)
		(pad "1" smd roundrect
			(at -0.48 0 90)
			(size 0.59 0.64)
			(layers "F.Cu" "F.Mask" "F.Paste")
			(roundrect_rratio 0.25)
			(net 1 "GND")
			(pintype "passive")
		)
		(pad "2" smd roundrect
			(at 0.48 0 90)
			(size 0.59 0.64)
			(layers "F.Cu" "F.Mask" "F.Paste")
			(roundrect_rratio 0.25)
			(net 717 "/HDMI + Ethernet/GBE_AVDDH")
			(pintype "passive")
		)
	)
	(footprint "antmicro-footprints:Conn_Socket_Samtec_ERF5_2x20_ERF5-020-05.0-L-DV-K-TR"
		(locked yes)
		(layer "F.Cu")
		(at 249.9 148.1)
		(property "Reference" "J22"
			(at 5.11 3.59 0)
			(layer "F.SilkS")
			(effects
				(font
					(size 0.7 0.7)
					(thickness 0.15)
				)
				(justify left bottom)
			)
		)
		(property "Value" "Socket_Samtec_ERF5_2x20_ERF5-020-05.0-L-DV-K-TR"
			(at 0 3.9 0)
			(layer "F.Fab")
			(effects
				(font
					(size 0.7 0.7)
					(thickness 0.15)
				)
				(justify left bottom)
			)
		)
		(property "Description" "Board to Board & Mezzanine Connectors 0.50 mm Edge Rate Rugged High Speed Socket"
			(at 0 0 0)
			(layer "F.Fab")
			(hide yes)
			(effects
				(font
					(size 1.27 1.27)
					(thickness 0.15)
				)
			)
		)
		(property "Author" "Antmicro"
			(at 0 0 0)
			(layer "F.Fab")
			(hide yes)
			(effects
				(font
					(size 1 1)
					(thickness 0.15)
				)
			)
		)
		(property "License" "Apache-2.0"
			(at 0 0 0)
			(layer "F.Fab")
			(hide yes)
			(effects
				(font
					(size 1 1)
					(thickness 0.15)
				)
			)
		)
		(property "MPN" "ERF5-020-05.0-L-DV-K-TR"
			(at 0 0 0)
			(layer "F.Fab")
			(hide yes)
			(effects
				(font
					(size 1 1)
					(thickness 0.15)
				)
			)
		)
		(property "Manufacturer" "Samtec"
			(at 0 0 0)
			(layer "F.Fab")
			(hide yes)
			(effects
				(font
					(size 1 1)
					(thickness 0.15)
				)
			)
		)
		(property "Pitch" "0.5 mm"
			(at 0 0 0)
			(layer "F.Fab")
			(hide yes)
			(effects
				(font
					(size 1 1)
					(thickness 0.15)
				)
			)
		)
		(sheetname "Supervisior MCU")
		(sheetfile "supervisor-mcu.kicad_sch")
		(attr smd)
		(fp_line
			(start -8.4 -2.475)
			(end -5.349 -2.475)
			(stroke
				(width 0.15)
				(type solid)
			)
			(layer "F.SilkS")
		)
		(fp_line
			(start -8.4 2.476)
			(end -8.4 -2.475)
			(stroke
				(width 0.15)
				(type solid)
			)
			(layer "F.SilkS")
		)
		(fp_line
			(start -5.349 2.476)
			(end -8.4 2.476)
			(stroke
				(width 0.15)
				(type solid)
			)
			(layer "F.SilkS")
		)
		(fp_line
			(start 5.351 -2.475)
			(end 8.401 -2.475)
			(stroke
				(width 0.15)
				(type solid)
			)
			(layer "F.SilkS")
		)
		(fp_line
			(start 8.401 -2.475)
			(end 8.401 2.476)
			(stroke
				(width 0.15)
				(type solid)
			)
			(layer "F.SilkS")
		)
		(fp_line
			(start 8.401 2.476)
			(end 5.351 2.476)
			(stroke
				(width 0.15)
				(type solid)
			)
			(layer "F.SilkS")
		)
		(fp_circle
			(center -5.2 2.9)
			(end -5.25 2.9)
			(stroke
				(width 0.15)
				(type solid)
			)
			(fill no)
			(layer "F.SilkS")
		)
		(fp_poly
			(pts
				(xy -4.623 -1.225) (xy -4.876 -1.225) (xy -4.876 -2.725) (xy -4.623 -2.725)
			)
			(stroke
				(width 0.01)
				(type solid)
			)
			(fill yes)
			(layer "F.Paste")
		)
		(fp_poly
			(pts
				(xy -4.623 2.726) (xy -4.876 2.726) (xy -4.876 1.226) (xy -4.623 1.226)
			)
			(stroke
				(width 0.01)
				(type solid)
			)
			(fill yes)
			(layer "F.Paste")
		)
		(fp_poly
			(pts
				(xy -4.123 -1.225) (xy -4.376 -1.225) (xy -4.376 -2.725) (xy -4.123 -2.725)
			)
			(stroke
				(width 0.01)
				(type solid)
			)
			(fill yes)
			(layer "F.Paste")
		)
		(fp_poly
			(pts
				(xy -4.123 2.726) (xy -4.376 2.726) (xy -4.376 1.226) (xy -4.123 1.226)
			)
			(stroke
				(width 0.01)
				(type solid)
			)
			(fill yes)
			(layer "F.Paste")
		)
		(fp_poly
			(pts
				(xy -3.623 -1.225) (xy -3.875 -1.225) (xy -3.875 -2.725) (xy -3.623 -2.725)
			)
			(stroke
				(width 0.01)
				(type solid)
			)
			(fill yes)
			(layer "F.Paste")
		)
		(fp_poly
			(pts
				(xy -3.623 2.726) (xy -3.875 2.726) (xy -3.875 1.226) (xy -3.623 1.226)
			)
			(stroke
				(width 0.01)
				(type solid)
			)
			(fill yes)
			(layer "F.Paste")
		)
		(fp_poly
			(pts
				(xy -3.123 -1.225) (xy -3.375 -1.225) (xy -3.375 -2.725) (xy -3.123 -2.725)
			)
			(stroke
				(width 0.01)
				(type solid)
			)
			(fill yes)
			(layer "F.Paste")
		)
		(fp_poly
			(pts
				(xy -3.123 2.726) (xy -3.375 2.726) (xy -3.375 1.226) (xy -3.123 1.226)
			)
			(stroke
				(width 0.01)
				(type solid)
			)
			(fill yes)
			(layer "F.Paste")
		)
		(fp_poly
			(pts
				(xy -2.623 -1.225) (xy -2.875 -1.225) (xy -2.875 -2.725) (xy -2.623 -2.725)
			)
			(stroke
				(width 0.01)
				(type solid)
			)
			(fill yes)
			(layer "F.Paste")
		)
		(fp_poly
			(pts
				(xy -2.623 2.726) (xy -2.875 2.726) (xy -2.875 1.226) (xy -2.623 1.226)
			)
			(stroke
				(width 0.01)
				(type solid)
			)
			(fill yes)
			(layer "F.Paste")
		)
		(fp_poly
			(pts
				(xy -2.123 -1.225) (xy -2.375 -1.225) (xy -2.375 -2.725) (xy -2.123 -2.725)
			)
			(stroke
				(width 0.01)
				(type solid)
			)
			(fill yes)
			(layer "F.Paste")
		)
		(fp_poly
			(pts
				(xy -2.123 2.726) (xy -2.375 2.726) (xy -2.375 1.226) (xy -2.123 1.226)
			)
			(stroke
				(width 0.01)
				(type solid)
			)
			(fill yes)
			(layer "F.Paste")
		)
		(fp_poly
			(pts
				(xy -1.622 -1.225) (xy -1.876 -1.225) (xy -1.876 -2.725) (xy -1.622 -2.725)
			)
			(stroke
				(width 0.01)
				(type solid)
			)
			(fill yes)
			(layer "F.Paste")
		)
		(fp_poly
			(pts
				(xy -1.622 2.726) (xy -1.876 2.726) (xy -1.876 1.226) (xy -1.622 1.226)
			)
			(stroke
				(width 0.01)
				(type solid)
			)
			(fill yes)
			(layer "F.Paste")
		)
		(fp_poly
			(pts
				(xy -1.122 -1.225) (xy -1.376 -1.225) (xy -1.376 -2.725) (xy -1.122 -2.725)
			)
			(stroke
				(width 0.01)
				(type solid)
			)
			(fill yes)
			(layer "F.Paste")
		)
		(fp_poly
			(pts
				(xy -1.122 2.726) (xy -1.376 2.726) (xy -1.376 1.226) (xy -1.122 1.226)
			)
			(stroke
				(width 0.01)
				(type solid)
			)
			(fill yes)
			(layer "F.Paste")
		)
		(fp_poly
			(pts
				(xy -0.621 -1.225) (xy -0.875 -1.225) (xy -0.875 -2.725) (xy -0.621 -2.725)
			)
			(stroke
				(width 0.01)
				(type solid)
			)
			(fill yes)
			(layer "F.Paste")
		)
		(fp_poly
			(pts
				(xy -0.621 2.726) (xy -0.875 2.726) (xy -0.875 1.226) (xy -0.621 1.226)
			)
			(stroke
				(width 0.01)
				(type solid)
			)
			(fill yes)
			(layer "F.Paste")
		)
		(fp_poly
			(pts
				(xy -0.121 -1.225) (xy -0.375 -1.225) (xy -0.375 -2.725) (xy -0.121 -2.725)
			)
			(stroke
				(width 0.01)
				(type solid)
			)
			(fill yes)
			(layer "F.Paste")
		)
		(fp_poly
			(pts
				(xy -0.121 2.726) (xy -0.375 2.726) (xy -0.375 1.226) (xy -0.121 1.226)
			)
			(stroke
				(width 0.01)
				(type solid)
			)
			(fill yes)
			(layer "F.Paste")
		)
		(fp_poly
			(pts
				(xy 0.377 -1.225) (xy 0.123 -1.225) (xy 0.123 -2.725) (xy 0.377 -2.725)
			)
			(stroke
				(width 0.01)
				(type solid)
			)
			(fill yes)
			(layer "F.Paste")
		)
		(fp_poly
			(pts
				(xy 0.377 2.726) (xy 0.123 2.726) (xy 0.123 1.226) (xy 0.377 1.226)
			)
			(stroke
				(width 0.01)
				(type solid)
			)
			(fill yes)
			(layer "F.Paste")
		)
		(fp_poly
			(pts
				(xy 0.877 -1.225) (xy 0.623 -1.225) (xy 0.623 -2.725) (xy 0.877 -2.725)
			)
			(stroke
				(width 0.01)
				(type solid)
			)
			(fill yes)
			(layer "F.Paste")
		)
		(fp_poly
			(pts
				(xy 0.877 2.726) (xy 0.623 2.726) (xy 0.623 1.226) (xy 0.877 1.226)
			)
			(stroke
				(width 0.01)
				(type solid)
			)
			(fill yes)
			(layer "F.Paste")
		)
		(fp_poly
			(pts
				(xy 1.377 -1.225) (xy 1.123 -1.225) (xy 1.123 -2.725) (xy 1.377 -2.725)
			)
			(stroke
				(width 0.01)
				(type solid)
			)
			(fill yes)
			(layer "F.Paste")
		)
		(fp_poly
			(pts
				(xy 1.377 2.726) (xy 1.123 2.726) (xy 1.123 1.226) (xy 1.377 1.226)
			)
			(stroke
				(width 0.01)
				(type solid)
			)
			(fill yes)
			(layer "F.Paste")
		)
		(fp_poly
			(pts
				(xy 1.877 -1.225) (xy 1.623 -1.225) (xy 1.623 -2.725) (xy 1.877 -2.725)
			)
			(stroke
				(width 0.01)
				(type solid)
			)
			(fill yes)
			(layer "F.Paste")
		)
		(fp_poly
			(pts
				(xy 1.877 2.726) (xy 1.623 2.726) (xy 1.623 1.226) (xy 1.877 1.226)
			)
			(stroke
				(width 0.01)
				(type solid)
			)
			(fill yes)
			(layer "F.Paste")
		)
		(fp_poly
			(pts
				(xy 2.378 -1.225) (xy 2.125 -1.225) (xy 2.125 -2.725) (xy 2.378 -2.725)
			)
			(stroke
				(width 0.01)
				(type solid)
			)
			(fill yes)
			(layer "F.Paste")
		)
		(fp_poly
			(pts
				(xy 2.378 2.726) (xy 2.125 2.726) (xy 2.125 1.226) (xy 2.378 1.226)
			)
			(stroke
				(width 0.01)
				(type solid)
			)
			(fill yes)
			(layer "F.Paste")
		)
		(fp_poly
			(pts
				(xy 2.878 -1.225) (xy 2.625 -1.225) (xy 2.625 -2.725) (xy 2.878 -2.725)
			)
			(stroke
				(width 0.01)
				(type solid)
			)
			(fill yes)
			(layer "F.Paste")
		)
		(fp_poly
			(pts
				(xy 2.878 2.726) (xy 2.625 2.726) (xy 2.625 1.226) (xy 2.878 1.226)
			)
			(stroke
				(width 0.01)
				(type solid)
			)
			(fill yes)
			(layer "F.Paste")
		)
		(fp_poly
			(pts
				(xy 3.378 -1.225) (xy 3.125 -1.225) (xy 3.125 -2.725) (xy 3.378 -2.725)
			)
			(stroke
				(width 0.01)
				(type solid)
			)
			(fill yes)
			(layer "F.Paste")
		)
		(fp_poly
			(pts
				(xy 3.378 2.726) (xy 3.125 2.726) (xy 3.125 1.226) (xy 3.378 1.226)
			)
			(stroke
				(width 0.01)
				(type solid)
			)
			(fill yes)
			(layer "F.Paste")
		)
		(fp_poly
			(pts
				(xy 3.878 -1.225) (xy 3.625 -1.225) (xy 3.625 -2.725) (xy 3.878 -2.725)
			)
			(stroke
				(width 0.01)
				(type solid)
			)
			(fill yes)
			(layer "F.Paste")
		)
		(fp_poly
			(pts
				(xy 3.878 2.726) (xy 3.625 2.726) (xy 3.625 1.226) (xy 3.878 1.226)
			)
			(stroke
				(width 0.01)
				(type solid)
			)
			(fill yes)
			(layer "F.Paste")
		)
		(fp_poly
			(pts
				(xy 4.377 -1.225) (xy 4.124 -1.225) (xy 4.124 -2.725) (xy 4.377 -2.725)
			)
			(stroke
				(width 0.01)
				(type solid)
			)
			(fill yes)
			(layer "F.Paste")
		)
		(fp_poly
			(pts
				(xy 4.377 2.726) (xy 4.124 2.726) (xy 4.124 1.226) (xy 4.377 1.226)
			)
			(stroke
				(width 0.01)
				(type solid)
			)
			(fill yes)
			(layer "F.Paste")
		)
		(fp_poly
			(pts
				(xy 4.877 -1.225) (xy 4.624 -1.225) (xy 4.624 -2.725) (xy 4.877 -2.725)
			)
			(stroke
				(width 0.01)
				(type solid)
			)
			(fill yes)
			(layer "F.Paste")
		)
		(fp_poly
			(pts
				(xy 4.877 2.726) (xy 4.624 2.726) (xy 4.624 1.226) (xy 4.877 1.226)
			)
			(stroke
				(width 0.01)
				(type solid)
			)
			(fill yes)
			(layer "F.Paste")
		)
		(fp_rect
			(start 8.651 2.926)
			(end -8.65 -2.925)
			(stroke
				(width 0.05)
				(type solid)
			)
			(fill no)
			(layer "F.CrtYd")
		)
		(fp_line
			(start -8.39 1.35)
			(end -7.27 2.47)
			(stroke
				(width 0.15)
				(type solid)
			)
			(layer "F.Fab")
		)
		(fp_rect
			(start 8.401 2.476)
			(end -8.4 -2.475)
			(stroke
				(width 0.15)
				(type solid)
			)
			(fill no)
			(layer "F.Fab")
		)
		(pad "" np_thru_hole circle
			(at -6.9 1.401 180)
			(size 1.45 1.45)
			(drill 1.45)
			(layers "*.Cu" "*.Mask")
		)
		(pad "" np_thru_hole circle
			(at 6.901 1.401 180)
			(size 1.45 1.45)
			(drill 1.45)
			(layers "*.Cu" "*.Mask")
		)
		(pad "1" smd rect
			(at -4.748 1.976 270)
			(size 1.5 0.3)
			(layers "F.Cu" "F.Mask")
			(net 1 "GND")
			(pintype "passive")
		)
		(pad "2" smd rect
			(at -4.748 -1.975 270)
			(size 1.5 0.3)
			(layers "F.Cu" "F.Mask")
			(net 1098 "/Supervisior MCU/USB_D1")
			(pintype "passive")
		)
		(pad "3" smd rect
			(at -4.248 1.976 270)
			(size 1.5 0.3)
			(layers "F.Cu" "F.Mask")
			(net 1 "GND")
			(pintype "passive")
		)
		(pad "4" smd rect
			(at -4.248 -1.975 270)
			(size 1.5 0.3)
			(layers "F.Cu" "F.Mask")
			(net 1110 "/Supervisior MCU/USB_D4")
			(pintype "passive")
		)
		(pad "5" smd rect
			(at -3.749 1.976 270)
			(size 1.5 0.3)
			(layers "F.Cu" "F.Mask")
			(net 1099 "/Supervisior MCU/USB_D0")
			(pintype "passive")
		)
		(pad "6" smd rect
			(at -3.749 -1.975 270)
			(size 1.5 0.3)
			(layers "F.Cu" "F.Mask")
			(net 1111 "/Supervisior MCU/USB_D5")
			(pintype "passive")
		)
		(pad "7" smd rect
			(at -3.249 1.976 270)
			(size 1.5 0.3)
			(layers "F.Cu" "F.Mask")
			(net 1109 "/Supervisior MCU/USB_D3")
			(pintype "passive")
		)
		(pad "8" smd rect
			(at -3.249 -1.975 270)
			(size 1.5 0.3)
			(layers "F.Cu" "F.Mask")
			(net 1102 "/Supervisior MCU/SCL0")
			(pintype "passive")
		)
		(pad "9" smd rect
			(at -2.749 1.976 270)
			(size 1.5 0.3)
			(layers "F.Cu" "F.Mask")
			(net 1112 "/Supervisior MCU/USB_D6")
			(pintype "passive")
		)
		(pad "10" smd rect
			(at -2.749 -1.975 270)
			(size 1.5 0.3)
			(layers "F.Cu" "F.Mask")
			(net 1106 "/Supervisior MCU/TEMP_ALERT_N")
			(pintype "passive")
		)
		(pad "11" smd rect
			(at -2.249 1.976 270)
			(size 1.5 0.3)
			(layers "F.Cu" "F.Mask")
			(net 1113 "/Supervisior MCU/USB_D7")
			(pintype "passive")
		)
		(pad "12" smd rect
			(at -2.249 -1.975 270)
			(size 1.5 0.3)
			(layers "F.Cu" "F.Mask")
			(net 1103 "/Supervisior MCU/FPGA_M0")
			(pintype "passive")
		)
		(pad "13" smd rect
			(at -1.749 1.976 270)
			(size 1.5 0.3)
			(layers "F.Cu" "F.Mask")
			(net 1095 "/Supervisior MCU/USB_CE")
			(pintype "passive")
		)
		(pad "14" smd rect
			(at -1.749 -1.975 270)
			(size 1.5 0.3)
			(layers "F.Cu" "F.Mask")
			(net 1116 "/Supervisior MCU/USB_SPARE2")
			(pintype "passive")
		)
		(pad "15" smd rect
			(at -1.249 1.976 270)
			(size 1.5 0.3)
			(layers "F.Cu" "F.Mask")
			(net 1060 "/Supervisior MCU/CFG_INITB")
			(pintype "passive")
		)
		(pad "16" smd rect
			(at -1.249 -1.975 270)
			(size 1.5 0.3)
			(layers "F.Cu" "F.Mask")
			(net 1115 "/Supervisior MCU/USB_SPARE1")
			(pintype "passive")
		)
		(pad "17" smd rect
			(at -0.748 1.976 270)
			(size 1.5 0.3)
			(layers "F.Cu" "F.Mask")
			(net 250 "/Supervisior MCU/CFG_DONE")
			(pintype "passive")
		)
		(pad "18" smd rect
			(at -0.748 -1.975 270)
			(size 1.5 0.3)
			(layers "F.Cu" "F.Mask")
			(net 1104 "/Supervisior MCU/FPGA_M1")
			(pintype "passive")
		)
		(pad "19" smd rect
			(at -0.248 1.976 270)
			(size 1.5 0.3)
			(layers "F.Cu" "F.Mask")
			(net 1054 "/Supervisior MCU/CFG_PROGRAMB")
			(pintype "passive")
		)
		(pad "20" smd rect
			(at -0.248 -1.975 270)
			(size 1.5 0.3)
			(layers "F.Cu" "F.Mask")
			(net 260 "/Supervisior MCU/FPGA_CFG_CS")
			(pintype "passive")
		)
		(pad "21" smd rect
			(at 0.25 1.976 270)
			(size 1.5 0.3)
			(layers "F.Cu" "F.Mask")
			(net 975 "/Supervisior MCU/FPGA_CIPO")
			(pintype "passive")
		)
		(pad "22" smd rect
			(at 0.25 -1.975 270)
			(size 1.5 0.3)
			(layers "F.Cu" "F.Mask")
			(net 1092 "/Supervisior MCU/USB_CLK1_SPARE")
			(pintype "passive")
		)
		(pad "23" smd rect
			(at 0.75 1.976 270)
			(size 1.5 0.3)
			(layers "F.Cu" "F.Mask")
			(net 1114 "/Supervisior MCU/USB_SPARE0")
			(pintype "passive")
		)
		(pad "24" smd rect
			(at 0.75 -1.975 270)
			(size 1.5 0.3)
			(layers "F.Cu" "F.Mask")
			(net 1117 "/Supervisior MCU/USB_SPARE3")
			(pintype "passive")
		)
		(pad "25" smd rect
			(at 1.25 1.976 270)
			(size 1.5 0.3)
			(layers "F.Cu" "F.Mask")
			(net 1088 "/Supervisior MCU/PGOOD_1V2")
			(pintype "passive")
		)
		(pad "26" smd rect
			(at 1.25 -1.975 270)
			(size 1.5 0.3)
			(layers "F.Cu" "F.Mask")
			(net 1085 "/Supervisior MCU/PGOOD_VCCINT")
			(pintype "passive")
		)
		(pad "27" smd rect
			(at 1.75 1.976 270)
			(size 1.5 0.3)
			(layers "F.Cu" "F.Mask")
			(net 1105 "/Supervisior MCU/FPGA_M2")
			(pintype "passive")
		)
		(pad "28" smd rect
			(at 1.75 -1.975 270)
			(size 1.5 0.3)
			(layers "F.Cu" "F.Mask")
			(net 1107 "/Supervisior MCU/USB_C_PD_RST")
			(pintype "passive")
		)
		(pad "29" smd rect
			(at 2.25 1.976 270)
			(size 1.5 0.3)
			(layers "F.Cu" "F.Mask")
			(net 1069 "/Supervisior MCU/USB_A8")
			(pintype "passive")
		)
		(pad "30" smd rect
			(at 2.25 -1.975 270)
			(size 1.5 0.3)
			(layers "F.Cu" "F.Mask")
			(net 955 "/Supervisior MCU/FPGA_COPI")
			(pintype "passive")
		)
		(pad "31" smd rect
			(at 2.75 1.976 270)
			(size 1.5 0.3)
			(layers "F.Cu" "F.Mask")
			(net 1090 "/Supervisior MCU/USB_SPI_COPI")
			(pintype "passive")
		)
		(pad "32" smd rect
			(at 2.75 -1.975 270)
			(size 1.5 0.3)
			(layers "F.Cu" "F.Mask")
			(net 1100 "/Supervisior MCU/USB_WR")
			(pintype "passive")
		)
		(pad "33" smd rect
			(at 3.25 1.976 270)
			(size 1.5 0.3)
			(layers "F.Cu" "F.Mask")
			(net 1091 "/Supervisior MCU/USB_SPI_CIPO")
			(pintype "passive")
		)
		(pad "34" smd rect
			(at 3.25 -1.975 270)
			(size 1.5 0.3)
			(layers "F.Cu" "F.Mask")
			(net 1093 "/Supervisior MCU/USB_ALE")
			(pintype "passive")
		)
		(pad "35" smd rect
			(at 3.75 1.976 270)
			(size 1.5 0.3)
			(layers "F.Cu" "F.Mask")
			(net 1096 "/Supervisior MCU/USB_SPI_CS")
			(pintype "passive")
		)
		(pad "36" smd rect
			(at 3.75 -1.975 270)
			(size 1.5 0.3)
			(layers "F.Cu" "F.Mask")
			(net 1086 "/Supervisior MCU/PGOOD_3V3")
			(pintype "passive")
		)
		(pad "37" smd rect
			(at 4.25 1.976 270)
			(size 1.5 0.3)
			(layers "F.Cu" "F.Mask")
			(net 1089 "/Supervisior MCU/USB_SPI_SCK")
			(pintype "passive")
		)
		(pad "38" smd rect
			(at 4.25 -1.975 270)
			(size 1.5 0.3)
			(layers "F.Cu" "F.Mask")
			(net 1070 "/Supervisior MCU/USB_A9")
			(pintype "passive")
		)
		(pad "39" smd rect
			(at 4.75 1.976 270)
			(size 1.5 0.3)
			(layers "F.Cu" "F.Mask")
			(net 1097 "/Supervisior MCU/USB_D2")
			(pintype "passive")
		)
		(pad "40" smd rect
			(at 4.75 -1.975 270)
			(size 1.5 0.3)
			(layers "F.Cu" "F.Mask")
			(net 1094 "/Supervisior MCU/USB_RD")
			(pintype "passive")
		)
	)
	(footprint "antmicro-footprints:Resonator_SMD_Abracon_ABM8G_3.2x2.5mm"
		(layer "F.Cu")
		(at 204.853752 102.8365 180)
		(property "Reference" "Y4"
			(at -5.346248 -8.0635 0)
			(layer "F.SilkS")
			(effects
				(font
					(size 0.7 0.7)
					(thickness 0.15)
				)
				(justify left bottom)
			)
		)
		(property "Value" "Resonator_25MHz_ABM8G"
			(at -1.75 2.548 180)
			(layer "F.Fab")
			(effects
				(font
					(size 0.7 0.7)
					(thickness 0.15)
				)
				(justify left bottom)
			)
		)
		(property "Description" "Crystal, 25 MHz, SMD, 3.2mm x 2.5mm, 30 ppm, 18 pF, 20 ppm, ABM8G"
			(at 0 0 180)
			(layer "F.Fab")
			(hide yes)
			(effects
				(font
					(size 1.27 1.27)
					(thickness 0.15)
				)
			)
		)
		(property "Author" "Antmicro"
			(at 409.707504 205.673 0)
			(layer "F.Fab")
			(hide yes)
			(effects
				(font
					(size 1 1)
					(thickness 0.15)
				)
			)
		)
		(property "License" "Apache-2.0"
			(at 409.707504 205.673 0)
			(layer "F.Fab")
			(hide yes)
			(effects
				(font
					(size 1 1)
					(thickness 0.15)
				)
			)
		)
		(property "MPN" "ABM8G-25.000MHZ-18-D2Y-T3"
			(at 409.707504 205.673 0)
			(layer "F.Fab")
			(hide yes)
			(effects
				(font
					(size 1 1)
					(thickness 0.15)
				)
			)
		)
		(property "Manufacturer" "Abracon"
			(at 409.707504 205.673 0)
			(layer "F.Fab")
			(hide yes)
			(effects
				(font
					(size 1 1)
					(thickness 0.15)
				)
			)
		)
		(property "Val" "25 MHz"
			(at 409.707504 205.673 0)
			(layer "F.Fab")
			(hide yes)
			(effects
				(font
					(size 1 1)
					(thickness 0.15)
				)
			)
		)
		(sheetname "HDMI + Ethernet")
		(sheetfile "hdmi-ethernet.kicad_sch")
		(attr smd)
		(fp_line
			(start 1.6 0.3)
			(end 1.6 -0.2)
			(stroke
				(width 0.15)
				(type solid)
			)
			(layer "F.SilkS")
		)
		(fp_line
			(start -0.35 1.25)
			(end 0.45 1.25)
			(stroke
				(width 0.15)
				(type solid)
			)
			(layer "F.SilkS")
		)
		(fp_line
			(start -0.35 -1.25)
			(end 0.45 -1.25)
			(stroke
				(width 0.15)
				(type solid)
			)
			(layer "F.SilkS")
		)
		(fp_line
			(start -1.6 0.3)
			(end -1.6 -0.2)
			(stroke
				(width 0.15)
				(type solid)
			)
			(layer "F.SilkS")
		)
		(fp_circle
			(center -1.75 1.5)
			(end -1.7 1.5)
			(stroke
				(width 0.15)
				(type solid)
			)
			(fill no)
			(layer "F.SilkS")
		)
		(fp_rect
			(start -1.907 -1.55)
			(end 2.006 1.649)
			(stroke
				(width 0.05)
				(type solid)
			)
			(fill no)
			(layer "F.CrtYd")
		)
		(pad "1" smd roundrect
			(at -1.101 0.949 180)
			(size 1.3 1.1)
			(layers "F.Cu" "F.Mask" "F.Paste")
			(roundrect_rratio 0)
			(chamfer_ratio 0.2)
			(chamfer bottom_left)
			(net 718 "/HDMI + Ethernet/GBE_XI")
			(pintype "passive")
		)
		(pad "2" smd rect
			(at 1.199 0.949 180)
			(size 1.3 1.1)
			(layers "F.Cu" "F.Mask" "F.Paste")
			(net 1 "GND")
			(pinfunction "SH")
			(pintype "passive")
		)
		(pad "3" smd rect
			(at 1.199 -0.85 180)
			(size 1.3 1.1)
			(layers "F.Cu" "F.Mask" "F.Paste")
			(net 720 "/HDMI + Ethernet/GBE_XO")
			(pintype "passive")
		)
		(pad "4" smd rect
			(at -1.101 -0.85 180)
			(size 1.3 1.1)
			(layers "F.Cu" "F.Mask" "F.Paste")
			(net 1 "GND")
			(pinfunction "SH")
			(pintype "passive")
		)
	)
	(footprint "antmicro-footprints:R_0603_1608Metric"
		(layer "F.Cu")
		(at 151.4 141 -90)
		(descr "Resistor SMD 0603")
		(tags "resistor SMD 0603")
		(property "Reference" "R326"
			(at 2.39 -1.44 270)
			(layer "F.SilkS")
			(effects
				(font
					(size 0.7 0.7)
					(thickness 0.15)
				)
				(justify left bottom)
			)
		)
		(property "Value" "R_0R_22.4A_0603"
			(at 0 1.6 270)
			(layer "F.Fab")
			(effects
				(font
					(size 0.7 0.7)
					(thickness 0.15)
				)
				(justify left bottom)
			)
		)
		(property "Description" "SMD Chip Resistor"
			(at 0 0 270)
			(layer "F.Fab")
			(hide yes)
			(effects
				(font
					(size 1.27 1.27)
					(thickness 0.15)
				)
			)
		)
		(property "Author" "Antmicro"
			(at 10.4 292.4 0)
			(layer "F.Fab")
			(hide yes)
			(effects
				(font
					(size 1 1)
					(thickness 0.15)
				)
			)
		)
		(property "License" "Apache-2.0"
			(at 10.4 292.4 0)
			(layer "F.Fab")
			(hide yes)
			(effects
				(font
					(size 1 1)
					(thickness 0.15)
				)
			)
		)
		(property "MPN" "PMR03EZPJ000"
			(at 10.4 292.4 0)
			(layer "F.Fab")
			(hide yes)
			(effects
				(font
					(size 1 1)
					(thickness 0.15)
				)
			)
		)
		(property "Manufacturer" "ROHM Semiconductor"
			(at 10.4 292.4 0)
			(layer "F.Fab")
			(hide yes)
			(effects
				(font
					(size 1 1)
					(thickness 0.15)
				)
			)
		)
		(property "Max. Curr." "22.4A"
			(at 10.4 292.4 0)
			(layer "F.Fab")
			(hide yes)
			(effects
				(font
					(size 1 1)
					(thickness 0.15)
				)
			)
		)
		(property "Tolerance" "template_tolerance"
			(at 10.4 292.4 0)
			(layer "F.Fab")
			(hide yes)
			(effects
				(font
					(size 1 1)
					(thickness 0.15)
				)
			)
		)
		(property "Val" "0R"
			(at 10.4 292.4 0)
			(layer "F.Fab")
			(hide yes)
			(effects
				(font
					(size 1 1)
					(thickness 0.15)
				)
			)
		)
		(sheetname "DC-DC Converters")
		(sheetfile "dc-dc.kicad_sch")
		(attr smd)
		(fp_line
			(start -0.15 0.4)
			(end 0.15 0.4)
			(stroke
				(width 0.15)
				(type solid)
			)
			(layer "F.SilkS")
		)
		(fp_line
			(start -0.15 -0.4)
			(end 0.15 -0.4)
			(stroke
				(width 0.15)
				(type solid)
			)
			(layer "F.SilkS")
		)
		(fp_rect
			(start -1.25 -0.65)
			(end 1.25 0.65)
			(stroke
				(width 0.05)
				(type solid)
			)
			(fill no)
			(layer "F.CrtYd")
		)
		(fp_rect
			(start -0.8 -0.4)
			(end 0.8 0.4)
			(stroke
				(width 0.15)
				(type solid)
			)
			(fill no)
			(layer "F.Fab")
		)
		(pad "1" smd roundrect
			(at -0.7 0 270)
			(size 0.8 1)
			(layers "F.Cu" "F.Mask" "F.Paste")
			(roundrect_rratio 0.2)
			(net 748 "/DC-DC Converters/MGTAVTT_OUT")
			(pintype "passive")
		)
		(pad "2" smd roundrect
			(at 0.7 0 270)
			(size 0.8 1)
			(layers "F.Cu" "F.Mask" "F.Paste")
			(roundrect_rratio 0.2)
			(net 8 "+1V2_MGTAVTT")
			(pintype "passive")
		)
	)
	(footprint "antmicro-footprints:R_0402_1005Metric"
		(layer "F.Cu")
		(at 244.999 113.904)
		(descr "Resistor SMD 0402")
		(tags "resistor SMD 0402")
		(property "Reference" "R350"
			(at -1.299 -0.504 0)
			(layer "F.SilkS")
			(effects
				(font
					(size 0.7 0.7)
					(thickness 0.15)
				)
				(justify left bottom)
			)
		)
		(property "Value" "R_10k_0402"
			(at 0 1.4 0)
			(layer "F.Fab")
			(effects
				(font
					(size 0.7 0.7)
					(thickness 0.15)
				)
				(justify left bottom)
			)
		)
		(property "Description" "SMD Chip Resistor, 10 kohm, ± 1%, 62.5 mW, 0402 [1005 Metric], Thick Film, General Purpose"
			(at 0 0 0)
			(layer "F.Fab")
			(hide yes)
			(effects
				(font
					(size 1.27 1.27)
					(thickness 0.15)
				)
			)
		)
		(property "Author" "Antmicro"
			(at 0 0 0)
			(layer "F.Fab")
			(hide yes)
			(effects
				(font
					(size 1 1)
					(thickness 0.15)
				)
			)
		)
		(property "License" "Apache-2.0"
			(at 0 0 0)
			(layer "F.Fab")
			(hide yes)
			(effects
				(font
					(size 1 1)
					(thickness 0.15)
				)
			)
		)
		(property "MPN" "CR0402-FX-1002GLF"
			(at 0 0 0)
			(layer "F.Fab")
			(hide yes)
			(effects
				(font
					(size 1 1)
					(thickness 0.15)
				)
			)
		)
		(property "Manufacturer" "Bourns"
			(at 0 0 0)
			(layer "F.Fab")
			(hide yes)
			(effects
				(font
					(size 1 1)
					(thickness 0.15)
				)
			)
		)
		(property "Tolerance" "1%"
			(at 0 0 0)
			(layer "F.Fab")
			(hide yes)
			(effects
				(font
					(size 1 1)
					(thickness 0.15)
				)
			)
		)
		(property "Val" "10k"
			(at 0 0 0)
			(layer "F.Fab")
			(hide yes)
			(effects
				(font
					(size 1 1)
					(thickness 0.15)
				)
			)
		)
		(sheetname "USB PHY")
		(sheetfile "usb-phy.kicad_sch")
		(attr smd)
		(fp_rect
			(start -0.925 -0.47)
			(end 0.925 0.47)
			(stroke
				(width 0.05)
				(type default)
			)
			(fill no)
			(layer "F.CrtYd")
		)
		(fp_rect
			(start -0.5 -0.25)
			(end 0.5 0.25)
			(stroke
				(width 0.15)
				(type solid)
			)
			(fill no)
			(layer "F.Fab")
		)
		(pad "1" smd roundrect
			(at -0.48 0)
			(size 0.59 0.64)
			(layers "F.Cu" "F.Mask" "F.Paste")
			(roundrect_rratio 0.25)
			(net 385 "Net-(U43-EN)")
			(pintype "passive")
		)
		(pad "2" smd roundrect
			(at 0.48 0)
			(size 0.59 0.64)
			(layers "F.Cu" "F.Mask" "F.Paste")
			(roundrect_rratio 0.25)
			(net 1 "GND")
			(pintype "passive")
		)
	)
	(footprint "antmicro-footprints:C_0402_1005Metric"
		(layer "F.Cu")
		(at 157.7 147.9)
		(descr "Capacitor SMD 0402")
		(tags "capacitor SMD 0402")
		(property "Reference" "C362"
			(at -1.9 1.25 0)
			(layer "F.SilkS")
			(effects
				(font
					(size 0.7 0.7)
					(thickness 0.15)
				)
				(justify left bottom)
			)
		)
		(property "Value" "C_100n_0402"
			(at 0 1.4 0)
			(layer "F.Fab")
			(effects
				(font
					(size 0.7 0.7)
					(thickness 0.15)
				)
				(justify left bottom)
			)
		)
		(property "Description" "SMD Multilayer Ceramic Capacitor, 0.1 µF, 50 V, 0402 [1005 Metric], ± 10%, X5R, GRM Series"
			(at 0 0 0)
			(layer "F.Fab")
			(hide yes)
			(effects
				(font
					(size 1.27 1.27)
					(thickness 0.15)
				)
			)
		)
		(property "Author" "Antmicro"
			(at 0 0 0)
			(layer "F.Fab")
			(hide yes)
			(effects
				(font
					(size 1 1)
					(thickness 0.15)
				)
			)
		)
		(property "Dielectric" "X5R"
			(at 0 0 0)
			(layer "F.Fab")
			(hide yes)
			(effects
				(font
					(size 1 1)
					(thickness 0.15)
				)
			)
		)
		(property "License" "Apache-2.0"
			(at 0 0 0)
			(layer "F.Fab")
			(hide yes)
			(effects
				(font
					(size 1 1)
					(thickness 0.15)
				)
			)
		)
		(property "MPN" "GRM155R61H104KE14D"
			(at 0 0 0)
			(layer "F.Fab")
			(hide yes)
			(effects
				(font
					(size 1 1)
					(thickness 0.15)
				)
			)
		)
		(property "Manufacturer" "Murata"
			(at 0 0 0)
			(layer "F.Fab")
			(hide yes)
			(effects
				(font
					(size 1 1)
					(thickness 0.15)
				)
			)
		)
		(property "Val" "100n"
			(at 0 0 0)
			(layer "F.Fab")
			(hide yes)
			(effects
				(font
					(size 1 1)
					(thickness 0.15)
				)
			)
		)
		(property "Voltage" "50V"
			(at 0 0 0)
			(layer "F.Fab")
			(hide yes)
			(effects
				(font
					(size 1 1)
					(thickness 0.15)
				)
			)
		)
		(sheetname "DC-DC Converters")
		(sheetfile "dc-dc.kicad_sch")
		(attr smd)
		(fp_rect
			(start -0.925 -0.47)
			(end 0.925 0.47)
			(stroke
				(width 0.05)
				(type default)
			)
			(fill no)
			(layer "F.CrtYd")
		)
		(fp_line
			(start -0.494 -0.25)
			(end 0.504 -0.25)
			(stroke
				(width 0.15)
				(type solid)
			)
			(layer "F.Fab")
		)
		(fp_line
			(start -0.494 0.248)
			(end -0.494 -0.25)
			(stroke
				(width 0.15)
				(type solid)
			)
			(layer "F.Fab")
		)
		(fp_line
			(start 0.504 -0.25)
			(end 0.504 0.248)
			(stroke
				(width 0.15)
				(type solid)
			)
			(layer "F.Fab")
		)
		(fp_line
			(start 0.504 0.248)
			(end -0.494 0.248)
			(stroke
				(width 0.15)
				(type solid)
			)
			(layer "F.Fab")
		)
		(pad "1" smd roundrect
			(at -0.48 0)
			(size 0.59 0.64)
			(layers "F.Cu" "F.Mask" "F.Paste")
			(roundrect_rratio 0.25)
			(net 1 "GND")
			(pintype "passive")
		)
		(pad "2" smd roundrect
			(at 0.48 0)
			(size 0.59 0.64)
			(layers "F.Cu" "F.Mask" "F.Paste")
			(roundrect_rratio 0.25)
			(net 15 "Net-(U41-OUT)")
			(pintype "passive")
		)
	)
	(footprint "antmicro-footprints:USON-10_2.5x1mm_P0.5mm"
		(layer "F.Cu")
		(at 261.7 146 180)
		(descr "USON-10 2.5x1mm_ Pitch 0.5mm")
		(tags "USON-10 2.5x1mm Pitch 0.5mm")
		(property "Reference" "U17"
			(at 1.1 -2.4 180)
			(layer "F.SilkS")
			(effects
				(font
					(size 0.7 0.7)
					(thickness 0.15)
				)
				(justify left bottom)
			)
		)
		(property "Value" "TPD4E05U06QDQARQ1"
			(at 0.018 2.499 180)
			(layer "F.Fab")
			(effects
				(font
					(size 0.7 0.7)
					(thickness 0.15)
				)
				(justify left bottom)
			)
		)
		(property "Description" "ESD protection"
			(at 0 0 180)
			(layer "F.Fab")
			(hide yes)
			(effects
				(font
					(size 1.27 1.27)
					(thickness 0.15)
				)
			)
		)
		(property "Author" "Antmicro"
			(at 523.4 292 0)
			(layer "F.Fab")
			(hide yes)
			(effects
				(font
					(size 1 1)
					(thickness 0.15)
				)
			)
		)
		(property "License" "Apache-2.0"
			(at 523.4 292 0)
			(layer "F.Fab")
			(hide yes)
			(effects
				(font
					(size 1 1)
					(thickness 0.15)
				)
			)
		)
		(property "MPN" "TPD4E05U06QDQARQ1"
			(at 523.4 292 0)
			(layer "F.Fab")
			(hide yes)
			(effects
				(font
					(size 1 1)
					(thickness 0.15)
				)
			)
		)
		(property "Manufacturer" "Texas Instruments"
			(at 523.4 292 0)
			(layer "F.Fab")
			(hide yes)
			(effects
				(font
					(size 1 1)
					(thickness 0.15)
				)
			)
		)
		(sheetname "USB PHY")
		(sheetfile "usb-phy.kicad_sch")
		(attr smd)
		(fp_line
			(start 0.498 1.398)
			(end -0.5 1.398)
			(stroke
				(width 0.15)
				(type solid)
			)
			(layer "F.SilkS")
		)
		(fp_line
			(start 0.498 -1.401)
			(end -0.5 -1.401)
			(stroke
				(width 0.15)
				(type solid)
			)
			(layer "F.SilkS")
		)
		(fp_circle
			(center -0.68 -1.27)
			(end -0.63 -1.27)
			(stroke
				(width 0.15)
				(type solid)
			)
			(fill yes)
			(layer "F.SilkS")
		)
		(fp_rect
			(start -0.8 -1.5)
			(end 0.8 1.499)
			(stroke
				(width 0.05)
				(type solid)
			)
			(fill no)
			(layer "F.CrtYd")
		)
		(fp_line
			(start 0.498 -1.25)
			(end 0.498 1.249)
			(stroke
				(width 0.15)
				(type solid)
			)
			(layer "F.Fab")
		)
		(fp_line
			(start 0.498 -1.25)
			(end -0.25 -1.25)
			(stroke
				(width 0.15)
				(type solid)
			)
			(layer "F.Fab")
		)
		(fp_line
			(start -0.25 -1.25)
			(end -0.5 -1)
			(stroke
				(width 0.15)
				(type solid)
			)
			(layer "F.Fab")
		)
		(fp_line
			(start -0.5 1.249)
			(end 0.498 1.249)
			(stroke
				(width 0.15)
				(type solid)
			)
			(layer "F.Fab")
		)
		(fp_line
			(start -0.5 -1)
			(end -0.5 1.249)
			(stroke
				(width 0.15)
				(type solid)
			)
			(layer "F.Fab")
		)
		(pad "1" smd roundrect
			(at -0.387 -1 90)
			(size 0.25 0.55)
			(layers "F.Cu" "F.Mask" "F.Paste")
			(roundrect_rratio 0.25)
			(net 837 "/Power supply/USB_DBG_PD.CC1")
			(pintype "passive")
		)
		(pad "2" smd roundrect
			(at -0.387 -0.5 90)
			(size 0.25 0.55)
			(layers "F.Cu" "F.Mask" "F.Paste")
			(roundrect_rratio 0.25)
			(net 838 "/USB PHY/USB_DBG_CONN_D+")
			(pintype "passive")
		)
		(pad "3" smd roundrect
			(at -0.387 0 90)
			(size 0.4 0.55)
			(layers "F.Cu" "F.Mask" "F.Paste")
			(roundrect_rratio 0.25)
			(net 1 "GND")
			(pintype "power_in")
		)
		(pad "4" smd roundrect
			(at -0.387 0.498 90)
			(size 0.25 0.55)
			(layers "F.Cu" "F.Mask" "F.Paste")
			(roundrect_rratio 0.25)
			(net 839 "/USB PHY/USB_DBG_CONN_D-")
			(pintype "passive")
		)
		(pad "5" smd roundrect
			(at -0.387 0.998 90)
			(size 0.25 0.55)
			(layers "F.Cu" "F.Mask" "F.Paste")
			(roundrect_rratio 0.25)
			(net 840 "/Power supply/USB_DBG_PD.CC2")
			(pintype "passive")
		)
		(pad "6" smd roundrect
			(at 0.385 0.998 90)
			(size 0.25 0.55)
			(layers "F.Cu" "F.Mask" "F.Paste")
			(roundrect_rratio 0.25)
			(net 840 "/Power supply/USB_DBG_PD.CC2")
			(pintype "passive")
		)
		(pad "7" smd roundrect
			(at 0.385 0.498 90)
			(size 0.25 0.55)
			(layers "F.Cu" "F.Mask" "F.Paste")
			(roundrect_rratio 0.25)
			(net 839 "/USB PHY/USB_DBG_CONN_D-")
			(pintype "passive")
		)
		(pad "8" smd roundrect
			(at 0.385 0 90)
			(size 0.4 0.55)
			(layers "F.Cu" "F.Mask" "F.Paste")
			(roundrect_rratio 0.25)
			(net 1 "GND")
			(pintype "passive")
		)
		(pad "9" smd roundrect
			(at 0.385 -0.5 90)
			(size 0.25 0.55)
			(layers "F.Cu" "F.Mask" "F.Paste")
			(roundrect_rratio 0.25)
			(net 838 "/USB PHY/USB_DBG_CONN_D+")
			(pintype "passive")
		)
		(pad "10" smd roundrect
			(at 0.385 -1 90)
			(size 0.25 0.55)
			(layers "F.Cu" "F.Mask" "F.Paste")
			(roundrect_rratio 0.25)
			(net 837 "/Power supply/USB_DBG_PD.CC1")
			(pintype "passive")
		)
	)
	(footprint "antmicro-footprints:R_0402_1005Metric"
		(layer "F.Cu")
		(at 171.25 169.3125 90)
		(descr "Resistor SMD 0402")
		(tags "resistor SMD 0402")
		(property "Reference" "R300"
			(at -1.4375 -0.5 90)
			(layer "F.SilkS")
			(effects
				(font
					(size 0.7 0.7)
					(thickness 0.15)
				)
				(justify left bottom)
			)
		)
		(property "Value" "R_0R_0402"
			(at 0 1.4 90)
			(layer "F.Fab")
			(effects
				(font
					(size 0.7 0.7)
					(thickness 0.15)
				)
				(justify left bottom)
			)
		)
		(property "Description" "SMD Chip Resistor, Jumper, 0 ohm, 100 mW, 0402 [1005 Metric], Thick Film, General Purpose"
			(at 0 0 90)
			(layer "F.Fab")
			(hide yes)
			(effects
				(font
					(size 1.27 1.27)
					(thickness 0.15)
				)
			)
		)
		(property "Author" "Antmicro"
			(at 340.5625 -1.9375 0)
			(layer "F.Fab")
			(hide yes)
			(effects
				(font
					(size 1 1)
					(thickness 0.15)
				)
			)
		)
		(property "Current" "1A"
			(at 340.5625 -1.9375 0)
			(layer "F.Fab")
			(hide yes)
			(effects
				(font
					(size 1 1)
					(thickness 0.15)
				)
			)
		)
		(property "License" "Apache-2.0"
			(at 340.5625 -1.9375 0)
			(layer "F.Fab")
			(hide yes)
			(effects
				(font
					(size 1 1)
					(thickness 0.15)
				)
			)
		)
		(property "MPN" "ERJ2GE0R00X"
			(at 340.5625 -1.9375 0)
			(layer "F.Fab")
			(hide yes)
			(effects
				(font
					(size 1 1)
					(thickness 0.15)
				)
			)
		)
		(property "Manufacturer" "Panasonic"
			(at 340.5625 -1.9375 0)
			(layer "F.Fab")
			(hide yes)
			(effects
				(font
					(size 1 1)
					(thickness 0.15)
				)
			)
		)
		(property "Tolerance" ""
			(at 340.5625 -1.9375 0)
			(layer "F.Fab")
			(hide yes)
			(effects
				(font
					(size 1 1)
					(thickness 0.15)
				)
			)
		)
		(property "Val" "0R"
			(at 340.5625 -1.9375 0)
			(layer "F.Fab")
			(hide yes)
			(effects
				(font
					(size 1 1)
					(thickness 0.15)
				)
			)
		)
		(sheetname "DC-DC Converters")
		(sheetfile "dc-dc.kicad_sch")
		(attr smd)
		(fp_rect
			(start -0.925 -0.47)
			(end 0.925 0.47)
			(stroke
				(width 0.05)
				(type default)
			)
			(fill no)
			(layer "F.CrtYd")
		)
		(fp_rect
			(start -0.5 -0.25)
			(end 0.5 0.25)
			(stroke
				(width 0.15)
				(type solid)
			)
			(fill no)
			(layer "F.Fab")
		)
		(pad "1" smd roundrect
			(at -0.48 0 90)
			(size 0.59 0.64)
			(layers "F.Cu" "F.Mask" "F.Paste")
			(roundrect_rratio 0.25)
			(net 958 "/DC-DC Converters/FB5")
			(pintype "passive")
		)
		(pad "2" smd roundrect
			(at 0.48 0 90)
			(size 0.59 0.64)
			(layers "F.Cu" "F.Mask" "F.Paste")
			(roundrect_rratio 0.25)
			(net 735 "/DC-DC Converters/3V3_local")
			(pintype "passive")
		)
	)
	(footprint "antmicro-footprints:C_0402_1005Metric"
		(layer "F.Cu")
		(at 256.945 139.835 90)
		(descr "Capacitor SMD 0402")
		(tags "capacitor SMD 0402")
		(property "Reference" "C228"
			(at -1.315 -0.495 90)
			(layer "F.SilkS")
			(effects
				(font
					(size 0.7 0.7)
					(thickness 0.15)
				)
				(justify left bottom)
			)
		)
		(property "Value" "C_22p_0402"
			(at 0 1.4 90)
			(layer "F.Fab")
			(effects
				(font
					(size 0.7 0.7)
					(thickness 0.15)
				)
				(justify left bottom)
			)
		)
		(property "Description" "SMD Multilayer Ceramic Capacitor, 22 pF, 50 V, 0402 [1005 Metric], ± 5%, C0G / NP0, CC Series"
			(at 0 0 90)
			(layer "F.Fab")
			(hide yes)
			(effects
				(font
					(size 1.27 1.27)
					(thickness 0.15)
				)
			)
		)
		(property "Author" "Antmicro"
			(at 396.78 -117.11 0)
			(layer "F.Fab")
			(hide yes)
			(effects
				(font
					(size 1 1)
					(thickness 0.15)
				)
			)
		)
		(property "Dielectric" ""
			(at 396.78 -117.11 0)
			(layer "F.Fab")
			(hide yes)
			(effects
				(font
					(size 1 1)
					(thickness 0.15)
				)
			)
		)
		(property "License" "Apache-2.0"
			(at 396.78 -117.11 0)
			(layer "F.Fab")
			(hide yes)
			(effects
				(font
					(size 1 1)
					(thickness 0.15)
				)
			)
		)
		(property "MPN" "CC0402JRNPO9BN220"
			(at 396.78 -117.11 0)
			(layer "F.Fab")
			(hide yes)
			(effects
				(font
					(size 1 1)
					(thickness 0.15)
				)
			)
		)
		(property "Manufacturer" "YAGEO"
			(at 396.78 -117.11 0)
			(layer "F.Fab")
			(hide yes)
			(effects
				(font
					(size 1 1)
					(thickness 0.15)
				)
			)
		)
		(property "Val" "22p"
			(at 396.78 -117.11 0)
			(layer "F.Fab")
			(hide yes)
			(effects
				(font
					(size 1 1)
					(thickness 0.15)
				)
			)
		)
		(property "Voltage" ""
			(at 396.78 -117.11 0)
			(layer "F.Fab")
			(hide yes)
			(effects
				(font
					(size 1 1)
					(thickness 0.15)
				)
			)
		)
		(sheetname "USB PHY")
		(sheetfile "usb-phy.kicad_sch")
		(attr smd)
		(fp_rect
			(start -0.925 -0.47)
			(end 0.925 0.47)
			(stroke
				(width 0.05)
				(type default)
			)
			(fill no)
			(layer "F.CrtYd")
		)
		(fp_line
			(start 0.504 -0.25)
			(end 0.504 0.248)
			(stroke
				(width 0.15)
				(type solid)
			)
			(layer "F.Fab")
		)
		(fp_line
			(start -0.494 -0.25)
			(end 0.504 -0.25)
			(stroke
				(width 0.15)
				(type solid)
			)
			(layer "F.Fab")
		)
		(fp_line
			(start 0.504 0.248)
			(end -0.494 0.248)
			(stroke
				(width 0.15)
				(type solid)
			)
			(layer "F.Fab")
		)
		(fp_line
			(start -0.494 0.248)
			(end -0.494 -0.25)
			(stroke
				(width 0.15)
				(type solid)
			)
			(layer "F.Fab")
		)
		(pad "1" smd roundrect
			(at -0.48 0 90)
			(size 0.59 0.64)
			(layers "F.Cu" "F.Mask" "F.Paste")
			(roundrect_rratio 0.25)
			(net 1 "GND")
			(pintype "passive")
		)
		(pad "2" smd roundrect
			(at 0.48 0 90)
			(size 0.59 0.64)
			(layers "F.Cu" "F.Mask" "F.Paste")
			(roundrect_rratio 0.25)
			(net 710 "/USB PHY/FTDI_XI")
			(pintype "passive")
		)
	)
	(footprint "antmicro-footprints:FB_0402_1005Metric"
		(layer "F.Cu")
		(at 152.5 148.15 180)
		(descr "Ferrite Bead SMD 0402")
		(tags "ferrite bead SMD 0402")
		(property "Reference" "FB11"
			(at 1.25 -1.25 180)
			(layer "F.SilkS")
			(effects
				(font
					(size 0.7 0.7)
					(thickness 0.15)
				)
				(justify left bottom)
			)
		)
		(property "Value" "FB_120Z_1.3A_Murata-BLM15PD_0402"
			(at 0 1.4 180)
			(layer "F.Fab")
			(effects
				(font
					(size 0.7 0.7)
					(thickness 0.15)
				)
				(justify left bottom)
			)
		)
		(property "Description" "Ferrite Bead, 0402 [1005 Metric], 120 ohm, 1.3 A, BLM15PD, 0.09 ohm, ± 25%, DC power line"
			(at 0 0 180)
			(layer "F.Fab")
			(hide yes)
			(effects
				(font
					(size 1.27 1.27)
					(thickness 0.15)
				)
			)
		)
		(property "Author" "Antmicro"
			(at 305 296.3 0)
			(layer "F.Fab")
			(hide yes)
			(effects
				(font
					(size 1 1)
					(thickness 0.15)
				)
			)
		)
		(property "Current" ""
			(at 305 296.3 0)
			(layer "F.Fab")
			(hide yes)
			(effects
				(font
					(size 1 1)
					(thickness 0.15)
				)
			)
		)
		(property "License" "Apache-2.0"
			(at 305 296.3 0)
			(layer "F.Fab")
			(hide yes)
			(effects
				(font
					(size 1 1)
					(thickness 0.15)
				)
			)
		)
		(property "MPN" "BLM15PD121SN1D"
			(at 305 296.3 0)
			(layer "F.Fab")
			(hide yes)
			(effects
				(font
					(size 1 1)
					(thickness 0.15)
				)
			)
		)
		(property "Manufacturer" "Murata"
			(at 305 296.3 0)
			(layer "F.Fab")
			(hide yes)
			(effects
				(font
					(size 1 1)
					(thickness 0.15)
				)
			)
		)
		(property "Val" "120Z/1.3A"
			(at 305 296.3 0)
			(layer "F.Fab")
			(hide yes)
			(effects
				(font
					(size 1 1)
					(thickness 0.15)
				)
			)
		)
		(sheetname "DC-DC Converters")
		(sheetfile "dc-dc.kicad_sch")
		(attr smd)
		(fp_rect
			(start -0.925 -0.47)
			(end 0.925 0.47)
			(stroke
				(width 0.05)
				(type default)
			)
			(fill no)
			(layer "F.CrtYd")
		)
		(fp_rect
			(start -0.5 -0.25)
			(end 0.5 0.25)
			(stroke
				(width 0.15)
				(type solid)
			)
			(fill no)
			(layer "F.Fab")
		)
		(pad "1" smd roundrect
			(at -0.48 0 180)
			(size 0.59 0.64)
			(layers "F.Cu" "F.Mask" "F.Paste")
			(roundrect_rratio 0.25)
			(net 24 "+3V3")
			(pintype "passive")
		)
		(pad "2" smd roundrect
			(at 0.48 0 180)
			(size 0.59 0.64)
			(layers "F.Cu" "F.Mask" "F.Paste")
			(roundrect_rratio 0.25)
			(net 742 "/DC-DC Converters/1V85_VIN")
			(pintype "passive")
		)
	)
	(footprint "antmicro-footprints:R_0402_1005Metric"
		(layer "F.Cu")
		(at 194.6 165.649 -90)
		(descr "Resistor SMD 0402")
		(tags "resistor SMD 0402")
		(property "Reference" "R327"
			(at 4.851 -2.225 270)
			(layer "F.SilkS")
			(effects
				(font
					(size 0.7 0.7)
					(thickness 0.15)
				)
				(justify left bottom)
			)
		)
		(property "Value" "R_10k_0402"
			(at 0 1.4 270)
			(layer "F.Fab")
			(effects
				(font
					(size 0.7 0.7)
					(thickness 0.15)
				)
				(justify left bottom)
			)
		)
		(property "Description" "SMD Chip Resistor, 10 kohm, ± 1%, 62.5 mW, 0402 [1005 Metric], Thick Film, General Purpose"
			(at 0 0 270)
			(layer "F.Fab")
			(hide yes)
			(effects
				(font
					(size 1.27 1.27)
					(thickness 0.15)
				)
			)
		)
		(property "Author" "Antmicro"
			(at 28.951 360.249 0)
			(layer "F.Fab")
			(hide yes)
			(effects
				(font
					(size 1 1)
					(thickness 0.15)
				)
			)
		)
		(property "License" "Apache-2.0"
			(at 28.951 360.249 0)
			(layer "F.Fab")
			(hide yes)
			(effects
				(font
					(size 1 1)
					(thickness 0.15)
				)
			)
		)
		(property "MPN" "CR0402-FX-1002GLF"
			(at 28.951 360.249 0)
			(layer "F.Fab")
			(hide yes)
			(effects
				(font
					(size 1 1)
					(thickness 0.15)
				)
			)
		)
		(property "Manufacturer" "Bourns"
			(at 28.951 360.249 0)
			(layer "F.Fab")
			(hide yes)
			(effects
				(font
					(size 1 1)
					(thickness 0.15)
				)
			)
		)
		(property "Tolerance" "1%"
			(at 28.951 360.249 0)
			(layer "F.Fab")
			(hide yes)
			(effects
				(font
					(size 1 1)
					(thickness 0.15)
				)
			)
		)
		(property "Val" "10k"
			(at 28.951 360.249 0)
			(layer "F.Fab")
			(hide yes)
			(effects
				(font
					(size 1 1)
					(thickness 0.15)
				)
			)
		)
		(sheetname "DC-DC Converters")
		(sheetfile "dc-dc.kicad_sch")
		(attr smd)
		(fp_rect
			(start -0.925 -0.47)
			(end 0.925 0.47)
			(stroke
				(width 0.05)
				(type default)
			)
			(fill no)
			(layer "F.CrtYd")
		)
		(fp_rect
			(start -0.5 -0.25)
			(end 0.5 0.25)
			(stroke
				(width 0.15)
				(type solid)
			)
			(fill no)
			(layer "F.Fab")
		)
		(pad "1" smd roundrect
			(at -0.48 0 270)
			(size 0.59 0.64)
			(layers "F.Cu" "F.Mask" "F.Paste")
			(roundrect_rratio 0.25)
			(net 970 "/DC-DC Converters/1V0_FB")
			(pintype "passive")
		)
		(pad "2" smd roundrect
			(at 0.48 0 270)
			(size 0.59 0.64)
			(layers "F.Cu" "F.Mask" "F.Paste")
			(roundrect_rratio 0.25)
			(net 1230 "Net-(C364-Pad1)")
			(pintype "passive")
		)
	)
	(footprint "antmicro-footprints:NetTie-2_SMD_Pad0.127mm"
		(layer "F.Cu")
		(at 246.5 143.602 -90)
		(descr "Net tie, 2 pin, 0.127mm  SMD pads")
		(tags "net tie")
		(property "Reference" "NT23"
			(at -0.128 -1.345 270)
			(layer "F.SilkS")
			(hide yes)
			(effects
				(font
					(size 0.7 0.7)
					(thickness 0.15)
				)
				(justify left bottom)
			)
		)
		(property "Value" "Net-Tie_2"
			(at 0 1.199 270)
			(layer "F.Fab")
			(effects
				(font
					(size 0.7 0.7)
					(thickness 0.15)
				)
				(justify left bottom)
			)
		)
		(property "Description" "Net tie, 2 pins"
			(at 0 0 270)
			(layer "F.Fab")
			(hide yes)
			(effects
				(font
					(size 1.27 1.27)
					(thickness 0.15)
				)
			)
		)
		(property "Author" "Antmicro"
			(at 102.898 390.102 0)
			(layer "F.Fab")
			(hide yes)
			(effects
				(font
					(size 1 1)
					(thickness 0.15)
				)
			)
		)
		(property "License" "Apache-2.0"
			(at 102.898 390.102 0)
			(layer "F.Fab")
			(hide yes)
			(effects
				(font
					(size 1 1)
					(thickness 0.15)
				)
			)
		)
		(property "MPN" ""
			(at 102.898 390.102 0)
			(layer "F.Fab")
			(hide yes)
			(effects
				(font
					(size 1 1)
					(thickness 0.15)
				)
			)
		)
		(property "Manufacturer" ""
			(at 102.898 390.102 0)
			(layer "F.Fab")
			(hide yes)
			(effects
				(font
					(size 1 1)
					(thickness 0.15)
				)
			)
		)
		(sheetname "Supervisior MCU")
		(sheetfile "supervisor-mcu.kicad_sch")
		(attr exclude_from_pos_files)
		(net_tie_pad_groups "1, 2")
		(fp_poly
			(pts
				(xy -0.0635 -0.0635) (xy 0.0625 -0.0635) (xy 0.0625 0.0635) (xy -0.0635 0.0635)
			)
			(stroke
				(width 0)
				(type solid)
			)
			(fill yes)
			(layer "F.Cu")
		)
		(pad "1" smd roundrect
			(at -0.127 0 90)
			(size 0.127 0.127)
			(layers "F.Cu")
			(roundrect_rratio 0.5)
			(chamfer_ratio 0)
			(chamfer top_left bottom_left)
			(net 1338 "/I2C.SCL")
			(pinfunction "1")
			(pintype "passive")
		)
		(pad "2" smd roundrect
			(at 0.126 0 270)
			(size 0.127 0.127)
			(layers "F.Cu")
			(roundrect_rratio 0.5)
			(chamfer_ratio 0)
			(chamfer top_left bottom_left)
			(net 1339 "/SUP_MCU.SCL")
			(pinfunction "2")
			(pintype "passive")
		)
	)
	(footprint "antmicro-footprints:R_0402_1005Metric"
		(layer "F.Cu")
		(at 254.899 96 180)
		(descr "Resistor SMD 0402")
		(tags "resistor SMD 0402")
		(property "Reference" "R343"
			(at 1.999 1.6 180)
			(layer "F.SilkS")
			(effects
				(font
					(size 0.7 0.7)
					(thickness 0.15)
				)
				(justify left bottom)
			)
		)
		(property "Value" "R_10k_0402"
			(at 0 1.4 180)
			(layer "F.Fab")
			(effects
				(font
					(size 0.7 0.7)
					(thickness 0.15)
				)
				(justify left bottom)
			)
		)
		(property "Description" "SMD Chip Resistor, 10 kohm, ± 1%, 62.5 mW, 0402 [1005 Metric], Thick Film, General Purpose"
			(at 0 0 180)
			(layer "F.Fab")
			(hide yes)
			(effects
				(font
					(size 1.27 1.27)
					(thickness 0.15)
				)
			)
		)
		(property "Author" "Antmicro"
			(at 509.798 192 0)
			(layer "F.Fab")
			(hide yes)
			(effects
				(font
					(size 1 1)
					(thickness 0.15)
				)
			)
		)
		(property "License" "Apache-2.0"
			(at 509.798 192 0)
			(layer "F.Fab")
			(hide yes)
			(effects
				(font
					(size 1 1)
					(thickness 0.15)
				)
			)
		)
		(property "MPN" "CR0402-FX-1002GLF"
			(at 509.798 192 0)
			(layer "F.Fab")
			(hide yes)
			(effects
				(font
					(size 1 1)
					(thickness 0.15)
				)
			)
		)
		(property "Manufacturer" "Bourns"
			(at 509.798 192 0)
			(layer "F.Fab")
			(hide yes)
			(effects
				(font
					(size 1 1)
					(thickness 0.15)
				)
			)
		)
		(property "Tolerance" "1%"
			(at 509.798 192 0)
			(layer "F.Fab")
			(hide yes)
			(effects
				(font
					(size 1 1)
					(thickness 0.15)
				)
			)
		)
		(property "Val" "10k"
			(at 509.798 192 0)
			(layer "F.Fab")
			(hide yes)
			(effects
				(font
					(size 1 1)
					(thickness 0.15)
				)
			)
		)
		(sheetname "USB PHY")
		(sheetfile "usb-phy.kicad_sch")
		(attr smd)
		(fp_rect
			(start -0.925 -0.47)
			(end 0.925 0.47)
			(stroke
				(width 0.05)
				(type default)
			)
			(fill no)
			(layer "F.CrtYd")
		)
		(fp_rect
			(start -0.5 -0.25)
			(end 0.5 0.25)
			(stroke
				(width 0.15)
				(type solid)
			)
			(fill no)
			(layer "F.Fab")
		)
		(pad "1" smd roundrect
			(at -0.48 0 180)
			(size 0.59 0.64)
			(layers "F.Cu" "F.Mask" "F.Paste")
			(roundrect_rratio 0.25)
			(net 703 "+5V")
			(pintype "passive")
		)
		(pad "2" smd roundrect
			(at 0.48 0 180)
			(size 0.59 0.64)
			(layers "F.Cu" "F.Mask" "F.Paste")
			(roundrect_rratio 0.25)
			(net 637 "/USB PHY/USB_HOST_VBUS_FLG")
			(pintype "passive")
		)
	)
	(footprint "antmicro-footprints:C_0402_1005Metric"
		(layer "F.Cu")
		(at 191.925 176.699 -90)
		(descr "Capacitor SMD 0402")
		(tags "capacitor SMD 0402")
		(property "Reference" "C205"
			(at 4.401 -4.575 180)
			(layer "F.SilkS")
			(effects
				(font
					(size 0.7 0.7)
					(thickness 0.15)
				)
				(justify right bottom)
			)
		)
		(property "Value" "C_100n_0402"
			(at 0 1.4 90)
			(layer "F.Fab")
			(effects
				(font
					(size 0.7 0.7)
					(thickness 0.15)
				)
				(justify right bottom)
			)
		)
		(property "Description" "SMD Multilayer Ceramic Capacitor, 0.1 µF, 50 V, 0402 [1005 Metric], ± 10%, X5R, GRM Series"
			(at 0 0 270)
			(layer "F.Fab")
			(hide yes)
			(effects
				(font
					(size 1.27 1.27)
					(thickness 0.15)
				)
			)
		)
		(property "Author" "Antmicro"
			(at 15.226 368.624 0)
			(layer "F.Fab")
			(hide yes)
			(effects
				(font
					(size 1 1)
					(thickness 0.15)
				)
			)
		)
		(property "Dielectric" "X5R"
			(at 15.226 368.624 0)
			(layer "F.Fab")
			(hide yes)
			(effects
				(font
					(size 1 1)
					(thickness 0.15)
				)
			)
		)
		(property "License" "Apache-2.0"
			(at 15.226 368.624 0)
			(layer "F.Fab")
			(hide yes)
			(effects
				(font
					(size 1 1)
					(thickness 0.15)
				)
			)
		)
		(property "MPN" "GRM155R61H104KE14D"
			(at 15.226 368.624 0)
			(layer "F.Fab")
			(hide yes)
			(effects
				(font
					(size 1 1)
					(thickness 0.15)
				)
			)
		)
		(property "Manufacturer" "Murata"
			(at 15.226 368.624 0)
			(layer "F.Fab")
			(hide yes)
			(effects
				(font
					(size 1 1)
					(thickness 0.15)
				)
			)
		)
		(property "Val" "100n"
			(at 15.226 368.624 0)
			(layer "F.Fab")
			(hide yes)
			(effects
				(font
					(size 1 1)
					(thickness 0.15)
				)
			)
		)
		(property "Voltage" "50V"
			(at 15.226 368.624 0)
			(layer "F.Fab")
			(hide yes)
			(effects
				(font
					(size 1 1)
					(thickness 0.15)
				)
			)
		)
		(sheetname "Power supply")
		(sheetfile "power-supply.kicad_sch")
		(attr smd)
		(fp_rect
			(start -0.925 -0.47)
			(end 0.925 0.47)
			(stroke
				(width 0.05)
				(type default)
			)
			(fill no)
			(layer "F.CrtYd")
		)
		(fp_line
			(start -0.494 0.248)
			(end -0.494 -0.25)
			(stroke
				(width 0.15)
				(type solid)
			)
			(layer "F.Fab")
		)
		(fp_line
			(start 0.504 0.248)
			(end -0.494 0.248)
			(stroke
				(width 0.15)
				(type solid)
			)
			(layer "F.Fab")
		)
		(fp_line
			(start -0.494 -0.25)
			(end 0.504 -0.25)
			(stroke
				(width 0.15)
				(type solid)
			)
			(layer "F.Fab")
		)
		(fp_line
			(start 0.504 -0.25)
			(end 0.504 0.248)
			(stroke
				(width 0.15)
				(type solid)
			)
			(layer "F.Fab")
		)
		(pad "1" smd roundrect
			(at -0.48 0 270)
			(size 0.59 0.64)
			(layers "F.Cu" "F.Mask" "F.Paste")
			(roundrect_rratio 0.25)
			(net 1 "GND")
			(pintype "passive")
		)
		(pad "2" smd roundrect
			(at 0.48 0 270)
			(size 0.59 0.64)
			(layers "F.Cu" "F.Mask" "F.Paste")
			(roundrect_rratio 0.25)
			(net 956 "/DC-DC Converters/POE_DC")
			(pintype "passive")
		)
	)
	(footprint "antmicro-footprints:TP_SMD_0.75mm"
		(layer "F.Cu")
		(at 163.9625 171.075)
		(property "Reference" "TP7"
			(at 0.3875 0.425 0)
			(layer "F.SilkS")
			(effects
				(font
					(size 0.7 0.7)
					(thickness 0.15)
				)
				(justify left bottom)
			)
		)
		(property "Value" "TP_0.75mm_SMD"
			(at 0 1.2 0)
			(layer "F.Fab")
			(effects
				(font
					(size 0.7 0.7)
					(thickness 0.15)
				)
				(justify left bottom)
			)
		)
		(property "Description" "SMT test point"
			(at 0 0 0)
			(layer "F.Fab")
			(hide yes)
			(effects
				(font
					(size 1.27 1.27)
					(thickness 0.15)
				)
			)
		)
		(property "Author" "Antmicro"
			(at 0 0 0)
			(layer "F.Fab")
			(hide yes)
			(effects
				(font
					(size 1 1)
					(thickness 0.15)
				)
			)
		)
		(property "License" "Apache-2.0"
			(at 0 0 0)
			(layer "F.Fab")
			(hide yes)
			(effects
				(font
					(size 1 1)
					(thickness 0.15)
				)
			)
		)
		(property "MPN" ""
			(at 0 0 0)
			(layer "F.Fab")
			(hide yes)
			(effects
				(font
					(size 1 1)
					(thickness 0.15)
				)
			)
		)
		(property "Manufacturer" ""
			(at 0 0 0)
			(layer "F.Fab")
			(hide yes)
			(effects
				(font
					(size 1 1)
					(thickness 0.15)
				)
			)
		)
		(sheetname "DC-DC Converters")
		(sheetfile "dc-dc.kicad_sch")
		(attr exclude_from_pos_files)
		(pad "1" smd circle
			(at 0 0)
			(size 0.75 0.75)
			(layers "F.Cu" "F.Mask")
			(net 1336 "/I2C.SDA")
			(pinfunction "1")
			(pintype "passive")
		)
	)
	(footprint "antmicro-footprints:C_0603_1608Metric"
		(layer "F.Cu")
		(at 174.9 164 180)
		(descr "Capacitor SMD 0603")
		(tags "capacitor 0603")
		(property "Reference" "C324"
			(at 1 -0.4 0)
			(layer "F.SilkS")
			(effects
				(font
					(size 0.7 0.7)
					(thickness 0.15)
				)
				(justify right bottom)
			)
		)
		(property "Value" "C_22u_0603"
			(at 0 1.6 0)
			(layer "F.Fab")
			(effects
				(font
					(size 0.7 0.7)
					(thickness 0.15)
				)
				(justify right bottom)
			)
		)
		(property "Description" "SMD Multilayer Ceramic Capacitor, 22 µF, 6.3 V, 0603 [1608 Metric], ± 20%, X5R, GRM Series"
			(at 0 0 180)
			(layer "F.Fab")
			(hide yes)
			(effects
				(font
					(size 1.27 1.27)
					(thickness 0.15)
				)
			)
		)
		(property "Author" "Antmicro"
			(at 349.8 328 0)
			(layer "F.Fab")
			(hide yes)
			(effects
				(font
					(size 1 1)
					(thickness 0.15)
				)
			)
		)
		(property "Dielectric" ""
			(at 349.8 328 0)
			(layer "F.Fab")
			(hide yes)
			(effects
				(font
					(size 1 1)
					(thickness 0.15)
				)
			)
		)
		(property "License" "Apache-2.0"
			(at 349.8 328 0)
			(layer "F.Fab")
			(hide yes)
			(effects
				(font
					(size 1 1)
					(thickness 0.15)
				)
			)
		)
		(property "MPN" "GRM188R60J226MEA0D"
			(at 349.8 328 0)
			(layer "F.Fab")
			(hide yes)
			(effects
				(font
					(size 1 1)
					(thickness 0.15)
				)
			)
		)
		(property "Manufacturer" "Murata"
			(at 349.8 328 0)
			(layer "F.Fab")
			(hide yes)
			(effects
				(font
					(size 1 1)
					(thickness 0.15)
				)
			)
		)
		(property "Val" "22u"
			(at 349.8 328 0)
			(layer "F.Fab")
			(hide yes)
			(effects
				(font
					(size 1 1)
					(thickness 0.15)
				)
			)
		)
		(property "Voltage" ""
			(at 349.8 328 0)
			(layer "F.Fab")
			(hide yes)
			(effects
				(font
					(size 1 1)
					(thickness 0.15)
				)
			)
		)
		(sheetname "DC-DC Converters")
		(sheetfile "dc-dc.kicad_sch")
		(attr smd)
		(fp_line
			(start -0.15 0.4)
			(end 0.15 0.4)
			(stroke
				(width 0.15)
				(type solid)
			)
			(layer "F.SilkS")
		)
		(fp_line
			(start -0.15 -0.4)
			(end 0.15 -0.4)
			(stroke
				(width 0.15)
				(type solid)
			)
			(layer "F.SilkS")
		)
		(fp_rect
			(start -1.25 -0.65)
			(end 1.25 0.65)
			(stroke
				(width 0.05)
				(type solid)
			)
			(fill no)
			(layer "F.CrtYd")
		)
		(fp_rect
			(start -0.8 -0.4)
			(end 0.8 0.4)
			(stroke
				(width 0.15)
				(type solid)
			)
			(fill no)
			(layer "F.Fab")
		)
		(pad "1" smd roundrect
			(at -0.7 0 180)
			(size 0.8 1)
			(layers "F.Cu" "F.Mask" "F.Paste")
			(roundrect_rratio 0.2)
			(net 1 "GND")
			(pintype "passive")
		)
		(pad "2" smd roundrect
			(at 0.7 0 180)
			(size 0.8 1)
			(layers "F.Cu" "F.Mask" "F.Paste")
			(roundrect_rratio 0.2)
			(net 735 "/DC-DC Converters/3V3_local")
			(pintype "passive")
		)
	)
	(footprint "antmicro-footprints:R_0402_1005Metric"
		(layer "F.Cu")
		(at 151.975 155.25 180)
		(descr "Resistor SMD 0402")
		(tags "resistor SMD 0402")
		(property "Reference" "R341"
			(at 1.575 0.5 180)
			(layer "F.SilkS")
			(effects
				(font
					(size 0.7 0.7)
					(thickness 0.15)
				)
				(justify left bottom)
			)
		)
		(property "Value" "R_100k_0402"
			(at 0 1.4 180)
			(layer "F.Fab")
			(effects
				(font
					(size 0.7 0.7)
					(thickness 0.15)
				)
				(justify left bottom)
			)
		)
		(property "Description" "SMD Chip Resistor, 100 kohm, ± 1%, 62.5 mW, 0402 [1005 Metric], Thick Film, General Purpose"
			(at 0 0 180)
			(layer "F.Fab")
			(hide yes)
			(effects
				(font
					(size 1.27 1.27)
					(thickness 0.15)
				)
			)
		)
		(property "Author" "Antmicro"
			(at 303.95 310.5 0)
			(layer "F.Fab")
			(hide yes)
			(effects
				(font
					(size 1 1)
					(thickness 0.15)
				)
			)
		)
		(property "License" "Apache-2.0"
			(at 303.95 310.5 0)
			(layer "F.Fab")
			(hide yes)
			(effects
				(font
					(size 1 1)
					(thickness 0.15)
				)
			)
		)
		(property "MPN" "CR0402-FX-1003GLF"
			(at 303.95 310.5 0)
			(layer "F.Fab")
			(hide yes)
			(effects
				(font
					(size 1 1)
					(thickness 0.15)
				)
			)
		)
		(property "Manufacturer" "Bourns"
			(at 303.95 310.5 0)
			(layer "F.Fab")
			(hide yes)
			(effects
				(font
					(size 1 1)
					(thickness 0.15)
				)
			)
		)
		(property "Tolerance" "1%"
			(at 303.95 310.5 0)
			(layer "F.Fab")
			(hide yes)
			(effects
				(font
					(size 1 1)
					(thickness 0.15)
				)
			)
		)
		(property "Val" "100k"
			(at 303.95 310.5 0)
			(layer "F.Fab")
			(hide yes)
			(effects
				(font
					(size 1 1)
					(thickness 0.15)
				)
			)
		)
		(sheetname "DC-DC Converters")
		(sheetfile "dc-dc.kicad_sch")
		(attr smd)
		(fp_rect
			(start -0.925 -0.47)
			(end 0.925 0.47)
			(stroke
				(width 0.05)
				(type default)
			)
			(fill no)
			(layer "F.CrtYd")
		)
		(fp_rect
			(start -0.5 -0.25)
			(end 0.5 0.25)
			(stroke
				(width 0.15)
				(type solid)
			)
			(fill no)
			(layer "F.Fab")
		)
		(pad "1" smd roundrect
			(at -0.48 0 180)
			(size 0.59 0.64)
			(layers "F.Cu" "F.Mask" "F.Paste")
			(roundrect_rratio 0.25)
			(net 1055 "/DC-DC Converters/VDDR_PGOOD")
			(pintype "passive")
		)
		(pad "2" smd roundrect
			(at 0.48 0 180)
			(size 0.59 0.64)
			(layers "F.Cu" "F.Mask" "F.Paste")
			(roundrect_rratio 0.25)
			(net 24 "+3V3")
			(pintype "passive")
		)
	)
	(footprint "antmicro-footprints:R_0402_1005Metric"
		(layer "F.Cu")
		(at 219.2 137.2 180)
		(descr "Resistor SMD 0402")
		(tags "resistor SMD 0402")
		(property "Reference" "R336"
			(at 3.65 -0.4 180)
			(layer "F.SilkS")
			(effects
				(font
					(size 0.7 0.7)
					(thickness 0.15)
				)
				(justify left bottom)
			)
		)
		(property "Value" "R_22R_0402"
			(at 0 1.4 180)
			(layer "F.Fab")
			(effects
				(font
					(size 0.7 0.7)
					(thickness 0.15)
				)
				(justify left bottom)
			)
		)
		(property "Description" "SMD Chip Resistor, 22 ohm, ± 1%, 62.5 mW, 0402 [1005 Metric], Thick Film, General Purpose"
			(at 0 0 180)
			(layer "F.Fab")
			(hide yes)
			(effects
				(font
					(size 1.27 1.27)
					(thickness 0.15)
				)
			)
		)
		(property "Author" "Antmicro"
			(at 438.4 274.4 0)
			(layer "F.Fab")
			(hide yes)
			(effects
				(font
					(size 1 1)
					(thickness 0.15)
				)
			)
		)
		(property "License" "Apache-2.0"
			(at 438.4 274.4 0)
			(layer "F.Fab")
			(hide yes)
			(effects
				(font
					(size 1 1)
					(thickness 0.15)
				)
			)
		)
		(property "MPN" "CR0402-FX-22R0GLF"
			(at 438.4 274.4 0)
			(layer "F.Fab")
			(hide yes)
			(effects
				(font
					(size 1 1)
					(thickness 0.15)
				)
			)
		)
		(property "Manufacturer" "Bourns"
			(at 438.4 274.4 0)
			(layer "F.Fab")
			(hide yes)
			(effects
				(font
					(size 1 1)
					(thickness 0.15)
				)
			)
		)
		(property "Tolerance" "1%"
			(at 438.4 274.4 0)
			(layer "F.Fab")
			(hide yes)
			(effects
				(font
					(size 1 1)
					(thickness 0.15)
				)
			)
		)
		(property "Val" "22R"
			(at 438.4 274.4 0)
			(layer "F.Fab")
			(hide yes)
			(effects
				(font
					(size 1 1)
					(thickness 0.15)
				)
			)
		)
		(sheetname "Clocks")
		(sheetfile "clocks.kicad_sch")
		(attr smd)
		(fp_rect
			(start -0.925 -0.47)
			(end 0.925 0.47)
			(stroke
				(width 0.05)
				(type default)
			)
			(fill no)
			(layer "F.CrtYd")
		)
		(fp_rect
			(start -0.5 -0.25)
			(end 0.5 0.25)
			(stroke
				(width 0.15)
				(type solid)
			)
			(fill no)
			(layer "F.Fab")
		)
		(pad "1" smd roundrect
			(at -0.48 0 180)
			(size 0.59 0.64)
			(layers "F.Cu" "F.Mask" "F.Paste")
			(roundrect_rratio 0.25)
			(net 972 "/Clocks/PLL_Y1")
			(pintype "passive")
		)
		(pad "2" smd roundrect
			(at 0.48 0 180)
			(size 0.59 0.64)
			(layers "F.Cu" "F.Mask" "F.Paste")
			(roundrect_rratio 0.25)
			(net 1402 "/PLL.CLK2")
			(pintype "passive")
		)
	)
	(footprint "antmicro-footprints:C_0402_1005Metric"
		(layer "F.Cu")
		(at 225.7 152.1 90)
		(descr "Capacitor SMD 0402")
		(tags "capacitor SMD 0402")
		(property "Reference" "C270"
			(at -1.65 1.3 90)
			(layer "F.SilkS")
			(effects
				(font
					(size 0.7 0.7)
					(thickness 0.15)
				)
				(justify left bottom)
			)
		)
		(property "Value" "C_100n_0402"
			(at 0 1.169 90)
			(layer "F.Fab")
			(effects
				(font
					(size 0.7 0.7)
					(thickness 0.15)
				)
				(justify left bottom)
			)
		)
		(property "Description" "SMD Multilayer Ceramic Capacitor, 0.1 µF, 50 V, 0402 [1005 Metric], ± 10%, X5R, GRM Series"
			(at 0 0 90)
			(layer "F.Fab")
			(hide yes)
			(effects
				(font
					(size 1.27 1.27)
					(thickness 0.15)
				)
			)
		)
		(property "Author" "Antmicro"
			(at 377.8 -73.6 0)
			(layer "F.Fab")
			(hide yes)
			(effects
				(font
					(size 1 1)
					(thickness 0.15)
				)
			)
		)
		(property "Dielectric" "X5R"
			(at 377.8 -73.6 0)
			(layer "F.Fab")
			(hide yes)
			(effects
				(font
					(size 1 1)
					(thickness 0.15)
				)
			)
		)
		(property "License" "Apache-2.0"
			(at 377.8 -73.6 0)
			(layer "F.Fab")
			(hide yes)
			(effects
				(font
					(size 1 1)
					(thickness 0.15)
				)
			)
		)
		(property "MPN" "GRM155R61H104KE14D"
			(at 377.8 -73.6 0)
			(layer "F.Fab")
			(hide yes)
			(effects
				(font
					(size 1 1)
					(thickness 0.15)
				)
			)
		)
		(property "Manufacturer" "Murata"
			(at 377.8 -73.6 0)
			(layer "F.Fab")
			(hide yes)
			(effects
				(font
					(size 1 1)
					(thickness 0.15)
				)
			)
		)
		(property "Val" "100n"
			(at 377.8 -73.6 0)
			(layer "F.Fab")
			(hide yes)
			(effects
				(font
					(size 1 1)
					(thickness 0.15)
				)
			)
		)
		(property "Voltage" "50V"
			(at 377.8 -73.6 0)
			(layer "F.Fab")
			(hide yes)
			(effects
				(font
					(size 1 1)
					(thickness 0.15)
				)
			)
		)
		(sheetname "HDMI + Ethernet")
		(sheetfile "hdmi-ethernet.kicad_sch")
		(attr smd)
		(fp_rect
			(start -0.925 -0.47)
			(end 0.925 0.47)
			(stroke
				(width 0.05)
				(type default)
			)
			(fill no)
			(layer "F.CrtYd")
		)
		(fp_line
			(start 0.504 -0.25)
			(end 0.504 0.248)
			(stroke
				(width 0.15)
				(type solid)
			)
			(layer "F.Fab")
		)
		(fp_line
			(start -0.494 -0.25)
			(end 0.504 -0.25)
			(stroke
				(width 0.15)
				(type solid)
			)
			(layer "F.Fab")
		)
		(fp_line
			(start 0.504 0.248)
			(end -0.494 0.248)
			(stroke
				(width 0.15)
				(type solid)
			)
			(layer "F.Fab")
		)
		(fp_line
			(start -0.494 0.248)
			(end -0.494 -0.25)
			(stroke
				(width 0.15)
				(type solid)
			)
			(layer "F.Fab")
		)
		(pad "1" smd roundrect
			(at -0.48 0 90)
			(size 0.59 0.64)
			(layers "F.Cu" "F.Mask" "F.Paste")
			(roundrect_rratio 0.25)
			(net 1 "GND")
			(pintype "passive")
		)
		(pad "2" smd roundrect
			(at 0.48 0 90)
			(size 0.59 0.64)
			(layers "F.Cu" "F.Mask" "F.Paste")
			(roundrect_rratio 0.25)
			(net 721 "/HDMI + Ethernet/ETH_3V3")
			(pintype "passive")
		)
	)
	(footprint "antmicro-footprints:SOT-753"
		(layer "F.Cu")
		(at 163.75 187.1 180)
		(property "Reference" "U35"
			(at 1.1 2.15 180)
			(layer "F.SilkS")
			(effects
				(font
					(size 0.7 0.7)
					(thickness 0.15)
				)
				(justify left bottom)
			)
		)
		(property "Value" "SN74LVC1G125_SOT"
			(at 0 2.9 180)
			(layer "F.Fab")
			(effects
				(font
					(size 0.7 0.7)
					(thickness 0.15)
				)
				(justify left bottom)
			)
		)
		(property "Description" "Buffer, 74LVC1G125, 1.65 V to 5.5 V, SOT-23-5"
			(at 0 0 180)
			(layer "F.Fab")
			(hide yes)
			(effects
				(font
					(size 1.27 1.27)
					(thickness 0.15)
				)
			)
		)
		(property "Author" "Antmicro"
			(at 327.5 374.2 0)
			(layer "F.Fab")
			(hide yes)
			(effects
				(font
					(size 1 1)
					(thickness 0.15)
				)
			)
		)
		(property "License" "Apache-2.0"
			(at 327.5 374.2 0)
			(layer "F.Fab")
			(hide yes)
			(effects
				(font
					(size 1 1)
					(thickness 0.15)
				)
			)
		)
		(property "MPN" "SN74LVC1G125DBVR"
			(at 327.5 374.2 0)
			(layer "F.Fab")
			(hide yes)
			(effects
				(font
					(size 1 1)
					(thickness 0.15)
				)
			)
		)
		(property "Manufacturer" "Texas Instruments"
			(at 327.5 374.2 0)
			(layer "F.Fab")
			(hide yes)
			(effects
				(font
					(size 1 1)
					(thickness 0.15)
				)
			)
		)
		(sheetname "DC-DC Converters")
		(sheetfile "dc-dc.kicad_sch")
		(attr smd)
		(fp_line
			(start 1.648 0.998)
			(end 1.648 0.699)
			(stroke
				(width 0.15)
				(type solid)
			)
			(layer "F.SilkS")
		)
		(fp_line
			(start 1.648 -1)
			(end 1.648 -0.677)
			(stroke
				(width 0.15)
				(type solid)
			)
			(layer "F.SilkS")
		)
		(fp_line
			(start 1.5 0.998)
			(end 1.648 0.998)
			(stroke
				(width 0.15)
				(type solid)
			)
			(layer "F.SilkS")
		)
		(fp_line
			(start 1.5 -1)
			(end 1.648 -1)
			(stroke
				(width 0.15)
				(type solid)
			)
			(layer "F.SilkS")
		)
		(fp_line
			(start -1.5 1)
			(end -1.648 1)
			(stroke
				(width 0.15)
				(type solid)
			)
			(layer "F.SilkS")
		)
		(fp_line
			(start -1.5 -1)
			(end -1.651 -1)
			(stroke
				(width 0.15)
				(type solid)
			)
			(layer "F.SilkS")
		)
		(fp_line
			(start -1.648 1)
			(end -1.648 0.677)
			(stroke
				(width 0.15)
				(type solid)
			)
			(layer "F.SilkS")
		)
		(fp_line
			(start -1.651 -1)
			(end -1.651 -0.701)
			(stroke
				(width 0.15)
				(type solid)
			)
			(layer "F.SilkS")
		)
		(fp_circle
			(center -1.5 1.35)
			(end -1.46 1.4)
			(stroke
				(width 0.15)
				(type solid)
			)
			(fill yes)
			(layer "F.SilkS")
		)
		(fp_rect
			(start -1.7 -1.901)
			(end 1.699 1.898)
			(stroke
				(width 0.05)
				(type solid)
			)
			(fill no)
			(layer "F.CrtYd")
		)
		(fp_line
			(start 1.523 -0.875)
			(end 1.523 0.873)
			(stroke
				(width 0.15)
				(type solid)
			)
			(layer "F.Fab")
		)
		(fp_line
			(start -1.351 0.873)
			(end 1.523 0.873)
			(stroke
				(width 0.15)
				(type solid)
			)
			(layer "F.Fab")
		)
		(fp_line
			(start -1.526 0.623)
			(end -1.351 0.873)
			(stroke
				(width 0.15)
				(type solid)
			)
			(layer "F.Fab")
		)
		(fp_line
			(start -1.526 0.623)
			(end -1.526 -0.875)
			(stroke
				(width 0.15)
				(type solid)
			)
			(layer "F.Fab")
		)
		(fp_line
			(start -1.526 -0.875)
			(end 1.523 -0.875)
			(stroke
				(width 0.15)
				(type solid)
			)
			(layer "F.Fab")
		)
		(pad "1" smd roundrect
			(at -0.951 1.35 180)
			(size 0.6 1.05)
			(layers "F.Cu" "F.Mask" "F.Paste")
			(roundrect_rratio 0.25)
			(net 797 "/DC-DC Converters/PB_CTRL_OE")
			(pinfunction "~{OE}")
			(pintype "input")
		)
		(pad "2" smd roundrect
			(at 0 1.35 180)
			(size 0.6 1.05)
			(layers "F.Cu" "F.Mask" "F.Paste")
			(roundrect_rratio 0.25)
			(net 701 "/DC-DC Converters/PB_CTRL_OUT")
			(pinfunction "A")
			(pintype "input")
		)
		(pad "3" smd roundrect
			(at 0.949 1.35 180)
			(size 0.6 1.05)
			(layers "F.Cu" "F.Mask" "F.Paste")
			(roundrect_rratio 0.25)
			(net 1 "GND")
			(pinfunction "GND")
			(pintype "power_in")
		)
		(pad "4" smd roundrect
			(at 0.949 -1.351 180)
			(size 0.6 1.05)
			(layers "F.Cu" "F.Mask" "F.Paste")
			(roundrect_rratio 0.25)
			(net 961 "/DC-DC Converters/ON{slash}OFF")
			(pinfunction "Y")
			(pintype "output")
		)
		(pad "5" smd roundrect
			(at -0.951 -1.351 180)
			(size 0.6 1.05)
			(layers "F.Cu" "F.Mask" "F.Paste")
			(roundrect_rratio 0.25)
			(net 37 "+3V3_AON")
			(pinfunction "V_{CC}")
			(pintype "power_in")
		)
	)
	(footprint "antmicro-footprints:C_0402_1005Metric"
		(layer "F.Cu")
		(at 218.8 155.1 90)
		(descr "Capacitor SMD 0402")
		(tags "capacitor SMD 0402")
		(property "Reference" "C280"
			(at -1.85 -0.45 270)
			(layer "F.SilkS")
			(effects
				(font
					(size 0.7 0.7)
					(thickness 0.15)
				)
				(justify left bottom)
			)
		)
		(property "Value" "C_10u_0402"
			(at 0 1.4 90)
			(layer "F.Fab")
			(effects
				(font
					(size 0.7 0.7)
					(thickness 0.15)
				)
				(justify left bottom)
			)
		)
		(property "Description" "SMD Multilayer Ceramic Capacitor, 10 µF, 6.3 V, 0402 [1005 Metric], ± 20%, X5R, CC Series"
			(at 0 0 90)
			(layer "F.Fab")
			(hide yes)
			(effects
				(font
					(size 1.27 1.27)
					(thickness 0.15)
				)
			)
		)
		(property "Author" "Antmicro"
			(at 373.9 -63.7 0)
			(layer "F.Fab")
			(hide yes)
			(effects
				(font
					(size 1 1)
					(thickness 0.15)
				)
			)
		)
		(property "Dielectric" ""
			(at 373.9 -63.7 0)
			(layer "F.Fab")
			(hide yes)
			(effects
				(font
					(size 1 1)
					(thickness 0.15)
				)
			)
		)
		(property "License" "Apache-2.0"
			(at 373.9 -63.7 0)
			(layer "F.Fab")
			(hide yes)
			(effects
				(font
					(size 1 1)
					(thickness 0.15)
				)
			)
		)
		(property "MPN" "CC0402MRX5R5BB106"
			(at 373.9 -63.7 0)
			(layer "F.Fab")
			(hide yes)
			(effects
				(font
					(size 1 1)
					(thickness 0.15)
				)
			)
		)
		(property "Manufacturer" "YAGEO"
			(at 373.9 -63.7 0)
			(layer "F.Fab")
			(hide yes)
			(effects
				(font
					(size 1 1)
					(thickness 0.15)
				)
			)
		)
		(property "Val" "10u"
			(at 373.9 -63.7 0)
			(layer "F.Fab")
			(hide yes)
			(effects
				(font
					(size 1 1)
					(thickness 0.15)
				)
			)
		)
		(property "Voltage" ""
			(at 373.9 -63.7 0)
			(layer "F.Fab")
			(hide yes)
			(effects
				(font
					(size 1 1)
					(thickness 0.15)
				)
			)
		)
		(sheetname "HDMI + Ethernet")
		(sheetfile "hdmi-ethernet.kicad_sch")
		(attr smd)
		(fp_rect
			(start -0.925 -0.47)
			(end 0.925 0.47)
			(stroke
				(width 0.05)
				(type default)
			)
			(fill no)
			(layer "F.CrtYd")
		)
		(fp_line
			(start 0.504 -0.25)
			(end 0.504 0.248)
			(stroke
				(width 0.15)
				(type solid)
			)
			(layer "F.Fab")
		)
		(fp_line
			(start -0.494 -0.25)
			(end 0.504 -0.25)
			(stroke
				(width 0.15)
				(type solid)
			)
			(layer "F.Fab")
		)
		(fp_line
			(start 0.504 0.248)
			(end -0.494 0.248)
			(stroke
				(width 0.15)
				(type solid)
			)
			(layer "F.Fab")
		)
		(fp_line
			(start -0.494 0.248)
			(end -0.494 -0.25)
			(stroke
				(width 0.15)
				(type solid)
			)
			(layer "F.Fab")
		)
		(pad "1" smd roundrect
			(at -0.48 0 90)
			(size 0.59 0.64)
			(layers "F.Cu" "F.Mask" "F.Paste")
			(roundrect_rratio 0.25)
			(net 1 "GND")
			(pintype "passive")
		)
		(pad "2" smd roundrect
			(at 0.48 0 90)
			(size 0.59 0.64)
			(layers "F.Cu" "F.Mask" "F.Paste")
			(roundrect_rratio 0.25)
			(net 24 "+3V3")
			(pintype "passive")
		)
	)
	(footprint "antmicro-footprints:R_0402_1005Metric"
		(layer "F.Cu")
		(at 244.15 107.8)
		(descr "Resistor SMD 0402")
		(tags "resistor SMD 0402")
		(property "Reference" "R258"
			(at 0.8 0.35 0)
			(layer "F.SilkS")
			(effects
				(font
					(size 0.7 0.7)
					(thickness 0.15)
				)
				(justify left bottom)
			)
		)
		(property "Value" "R_0R_0402"
			(at 0 1.4 0)
			(layer "F.Fab")
			(effects
				(font
					(size 0.7 0.7)
					(thickness 0.15)
				)
				(justify left bottom)
			)
		)
		(property "Description" "SMD Chip Resistor, Jumper, 0 ohm, 100 mW, 0402 [1005 Metric], Thick Film, General Purpose"
			(at 0 0 0)
			(layer "F.Fab")
			(hide yes)
			(effects
				(font
					(size 1.27 1.27)
					(thickness 0.15)
				)
			)
		)
		(property "Author" "Antmicro"
			(at 0 0 0)
			(layer "F.Fab")
			(hide yes)
			(effects
				(font
					(size 1 1)
					(thickness 0.15)
				)
			)
		)
		(property "Current" "1A"
			(at 0 0 0)
			(layer "F.Fab")
			(hide yes)
			(effects
				(font
					(size 1 1)
					(thickness 0.15)
				)
			)
		)
		(property "License" "Apache-2.0"
			(at 0 0 0)
			(layer "F.Fab")
			(hide yes)
			(effects
				(font
					(size 1 1)
					(thickness 0.15)
				)
			)
		)
		(property "MPN" "ERJ2GE0R00X"
			(at 0 0 0)
			(layer "F.Fab")
			(hide yes)
			(effects
				(font
					(size 1 1)
					(thickness 0.15)
				)
			)
		)
		(property "Manufacturer" "Panasonic"
			(at 0 0 0)
			(layer "F.Fab")
			(hide yes)
			(effects
				(font
					(size 1 1)
					(thickness 0.15)
				)
			)
		)
		(property "Tolerance" ""
			(at 0 0 0)
			(layer "F.Fab")
			(hide yes)
			(effects
				(font
					(size 1 1)
					(thickness 0.15)
				)
			)
		)
		(property "Val" "0R"
			(at 0 0 0)
			(layer "F.Fab")
			(hide yes)
			(effects
				(font
					(size 1 1)
					(thickness 0.15)
				)
			)
		)
		(sheetname "HDMI + Ethernet")
		(sheetfile "hdmi-ethernet.kicad_sch")
		(attr smd)
		(fp_rect
			(start -0.925 -0.47)
			(end 0.925 0.47)
			(stroke
				(width 0.05)
				(type default)
			)
			(fill no)
			(layer "F.CrtYd")
		)
		(fp_rect
			(start -0.5 -0.25)
			(end 0.5 0.25)
			(stroke
				(width 0.15)
				(type solid)
			)
			(fill no)
			(layer "F.Fab")
		)
		(pad "1" smd roundrect
			(at -0.48 0)
			(size 0.59 0.64)
			(layers "F.Cu" "F.Mask" "F.Paste")
			(roundrect_rratio 0.25)
			(net 528 "/FPGA Bank 16 & 17/HDMI.D0_P")
			(pintype "passive")
		)
		(pad "2" smd roundrect
			(at 0.48 0)
			(size 0.59 0.64)
			(layers "F.Cu" "F.Mask" "F.Paste")
			(roundrect_rratio 0.25)
			(net 863 "/HDMI + Ethernet/HDMI_CONN_D0_P")
			(pintype "passive")
		)
	)
	(footprint "antmicro-footprints:R_0402_1005Metric"
		(layer "F.Cu")
		(at 172.75 175.7125 180)
		(descr "Resistor SMD 0402")
		(tags "resistor SMD 0402")
		(property "Reference" "R315"
			(at 1.25 -1.2875 180)
			(layer "F.SilkS")
			(effects
				(font
					(size 0.7 0.7)
					(thickness 0.15)
				)
				(justify left bottom)
			)
		)
		(property "Value" "R_0R_0402"
			(at 0 1.4 180)
			(layer "F.Fab")
			(effects
				(font
					(size 0.7 0.7)
					(thickness 0.15)
				)
				(justify left bottom)
			)
		)
		(property "Description" "SMD Chip Resistor, Jumper, 0 ohm, 100 mW, 0402 [1005 Metric], Thick Film, General Purpose"
			(at 0 0 180)
			(layer "F.Fab")
			(hide yes)
			(effects
				(font
					(size 1.27 1.27)
					(thickness 0.15)
				)
			)
		)
		(property "Author" "Antmicro"
			(at 345.5 351.425 0)
			(layer "F.Fab")
			(hide yes)
			(effects
				(font
					(size 1 1)
					(thickness 0.15)
				)
			)
		)
		(property "Current" "1A"
			(at 345.5 351.425 0)
			(layer "F.Fab")
			(hide yes)
			(effects
				(font
					(size 1 1)
					(thickness 0.15)
				)
			)
		)
		(property "License" "Apache-2.0"
			(at 345.5 351.425 0)
			(layer "F.Fab")
			(hide yes)
			(effects
				(font
					(size 1 1)
					(thickness 0.15)
				)
			)
		)
		(property "MPN" "ERJ2GE0R00X"
			(at 345.5 351.425 0)
			(layer "F.Fab")
			(hide yes)
			(effects
				(font
					(size 1 1)
					(thickness 0.15)
				)
			)
		)
		(property "Manufacturer" "Panasonic"
			(at 345.5 351.425 0)
			(layer "F.Fab")
			(hide yes)
			(effects
				(font
					(size 1 1)
					(thickness 0.15)
				)
			)
		)
		(property "Tolerance" ""
			(at 345.5 351.425 0)
			(layer "F.Fab")
			(hide yes)
			(effects
				(font
					(size 1 1)
					(thickness 0.15)
				)
			)
		)
		(property "Val" "0R"
			(at 345.5 351.425 0)
			(layer "F.Fab")
			(hide yes)
			(effects
				(font
					(size 1 1)
					(thickness 0.15)
				)
			)
		)
		(sheetname "DC-DC Converters")
		(sheetfile "dc-dc.kicad_sch")
		(attr smd)
		(fp_rect
			(start -0.925 -0.47)
			(end 0.925 0.47)
			(stroke
				(width 0.05)
				(type default)
			)
			(fill no)
			(layer "F.CrtYd")
		)
		(fp_rect
			(start -0.5 -0.25)
			(end 0.5 0.25)
			(stroke
				(width 0.15)
				(type solid)
			)
			(fill no)
			(layer "F.Fab")
		)
		(pad "1" smd roundrect
			(at -0.48 0 180)
			(size 0.59 0.64)
			(layers "F.Cu" "F.Mask" "F.Paste")
			(roundrect_rratio 0.25)
			(net 965 "/DC-DC Converters/FB8")
			(pintype "passive")
		)
		(pad "2" smd roundrect
			(at 0.48 0 180)
			(size 0.59 0.64)
			(layers "F.Cu" "F.Mask" "F.Paste")
			(roundrect_rratio 0.25)
			(net 740 "/DC-DC Converters/1V35_local")
			(pintype "passive")
		)
	)
	(footprint "antmicro-footprints:NetTie-2_SMD_Pad0.127mm"
		(layer "F.Cu")
		(at 240.4 128.373 -90)
		(descr "Net tie, 2 pin, 0.127mm  SMD pads")
		(tags "net tie")
		(property "Reference" "NT18"
			(at -0.128 -1.345 270)
			(layer "F.SilkS")
			(hide yes)
			(effects
				(font
					(size 0.7 0.7)
					(thickness 0.15)
				)
				(justify left bottom)
			)
		)
		(property "Value" "Net-Tie_2"
			(at 0 1.199 270)
			(layer "F.Fab")
			(effects
				(font
					(size 0.7 0.7)
					(thickness 0.15)
				)
				(justify left bottom)
			)
		)
		(property "Description" "Net tie, 2 pins"
			(at 0 0 270)
			(layer "F.Fab")
			(hide yes)
			(effects
				(font
					(size 1.27 1.27)
					(thickness 0.15)
				)
			)
		)
		(property "Author" "Antmicro"
			(at 112.027 368.773 0)
			(layer "F.Fab")
			(hide yes)
			(effects
				(font
					(size 1 1)
					(thickness 0.15)
				)
			)
		)
		(property "License" "Apache-2.0"
			(at 112.027 368.773 0)
			(layer "F.Fab")
			(hide yes)
			(effects
				(font
					(size 1 1)
					(thickness 0.15)
				)
			)
		)
		(property "MPN" ""
			(at 112.027 368.773 0)
			(layer "F.Fab")
			(hide yes)
			(effects
				(font
					(size 1 1)
					(thickness 0.15)
				)
			)
		)
		(property "Manufacturer" ""
			(at 112.027 368.773 0)
			(layer "F.Fab")
			(hide yes)
			(effects
				(font
					(size 1 1)
					(thickness 0.15)
				)
			)
		)
		(sheetname "FPGA Bank 12 & 13")
		(sheetfile "fpga-bank-12-13.kicad_sch")
		(attr exclude_from_pos_files)
		(net_tie_pad_groups "1, 2")
		(fp_poly
			(pts
				(xy -0.0635 -0.0635) (xy 0.0625 -0.0635) (xy 0.0625 0.0635) (xy -0.0635 0.0635)
			)
			(stroke
				(width 0)
				(type solid)
			)
			(fill yes)
			(layer "F.Cu")
		)
		(pad "1" smd roundrect
			(at -0.127 0 90)
			(size 0.127 0.127)
			(layers "F.Cu")
			(roundrect_rratio 0.5)
			(chamfer_ratio 0)
			(chamfer top_left bottom_left)
			(net 1331 "/SUP_MCU.RX0")
			(pinfunction "1")
			(pintype "passive")
		)
		(pad "2" smd roundrect
			(at 0.126 0 270)
			(size 0.127 0.127)
			(layers "F.Cu")
			(roundrect_rratio 0.5)
			(chamfer_ratio 0)
			(chamfer top_left bottom_left)
			(net 55 "/FPGA Bank 12 & 13/UART0.TX")
			(pinfunction "2")
			(pintype "passive")
		)
	)
	(footprint "antmicro-footprints:C_0402_1005Metric"
		(layer "F.Cu")
		(at 158.85 153.75 90)
		(descr "Capacitor SMD 0402")
		(tags "capacitor SMD 0402")
		(property "Reference" "C358"
			(at 0.8 0.35 90)
			(layer "F.SilkS")
			(effects
				(font
					(size 0.7 0.7)
					(thickness 0.15)
				)
				(justify left bottom)
			)
		)
		(property "Value" "C_10u_0402"
			(at 0 1.4 90)
			(layer "F.Fab")
			(effects
				(font
					(size 0.7 0.7)
					(thickness 0.15)
				)
				(justify left bottom)
			)
		)
		(property "Description" "SMD Multilayer Ceramic Capacitor, 10 µF, 6.3 V, 0402 [1005 Metric], ± 20%, X5R, CC Series"
			(at 0 0 90)
			(layer "F.Fab")
			(hide yes)
			(effects
				(font
					(size 1.27 1.27)
					(thickness 0.15)
				)
			)
		)
		(property "Author" "Antmicro"
			(at 312.6 -5.1 0)
			(layer "F.Fab")
			(hide yes)
			(effects
				(font
					(size 1 1)
					(thickness 0.15)
				)
			)
		)
		(property "Dielectric" ""
			(at 312.6 -5.1 0)
			(layer "F.Fab")
			(hide yes)
			(effects
				(font
					(size 1 1)
					(thickness 0.15)
				)
			)
		)
		(property "License" "Apache-2.0"
			(at 312.6 -5.1 0)
			(layer "F.Fab")
			(hide yes)
			(effects
				(font
					(size 1 1)
					(thickness 0.15)
				)
			)
		)
		(property "MPN" "CC0402MRX5R5BB106"
			(at 312.6 -5.1 0)
			(layer "F.Fab")
			(hide yes)
			(effects
				(font
					(size 1 1)
					(thickness 0.15)
				)
			)
		)
		(property "Manufacturer" "YAGEO"
			(at 312.6 -5.1 0)
			(layer "F.Fab")
			(hide yes)
			(effects
				(font
					(size 1 1)
					(thickness 0.15)
				)
			)
		)
		(property "Val" "10u"
			(at 312.6 -5.1 0)
			(layer "F.Fab")
			(hide yes)
			(effects
				(font
					(size 1 1)
					(thickness 0.15)
				)
			)
		)
		(property "Voltage" ""
			(at 312.6 -5.1 0)
			(layer "F.Fab")
			(hide yes)
			(effects
				(font
					(size 1 1)
					(thickness 0.15)
				)
			)
		)
		(sheetname "DC-DC Converters")
		(sheetfile "dc-dc.kicad_sch")
		(attr smd)
		(fp_rect
			(start -0.925 -0.47)
			(end 0.925 0.47)
			(stroke
				(width 0.05)
				(type default)
			)
			(fill no)
			(layer "F.CrtYd")
		)
		(fp_line
			(start 0.504 -0.25)
			(end 0.504 0.248)
			(stroke
				(width 0.15)
				(type solid)
			)
			(layer "F.Fab")
		)
		(fp_line
			(start -0.494 -0.25)
			(end 0.504 -0.25)
			(stroke
				(width 0.15)
				(type solid)
			)
			(layer "F.Fab")
		)
		(fp_line
			(start 0.504 0.248)
			(end -0.494 0.248)
			(stroke
				(width 0.15)
				(type solid)
			)
			(layer "F.Fab")
		)
		(fp_line
			(start -0.494 0.248)
			(end -0.494 -0.25)
			(stroke
				(width 0.15)
				(type solid)
			)
			(layer "F.Fab")
		)
		(pad "1" smd roundrect
			(at -0.48 0 90)
			(size 0.59 0.64)
			(layers "F.Cu" "F.Mask" "F.Paste")
			(roundrect_rratio 0.25)
			(net 1 "GND")
			(pintype "passive")
		)
		(pad "2" smd roundrect
			(at 0.48 0 90)
			(size 0.59 0.64)
			(layers "F.Cu" "F.Mask" "F.Paste")
			(roundrect_rratio 0.25)
			(net 750 "/DC-DC Converters/VDDR_VTT")
			(pintype "passive")
		)
	)
	(footprint "antmicro-footprints:C_2220_5650Metric"
		(layer "F.Cu")
		(at 240.275 185.575 90)
		(descr "Capacitor SMD 2220")
		(tags "capacitor SMD 2220")
		(property "Reference" "C196"
			(at 3.675 -1.425 180)
			(layer "F.SilkS")
			(effects
				(font
					(size 0.7 0.7)
					(thickness 0.15)
				)
				(justify left bottom)
			)
		)
		(property "Value" "C_22u_100V_2220"
			(at 0 3.9 90)
			(layer "F.Fab")
			(effects
				(font
					(size 0.7 0.7)
					(thickness 0.15)
				)
				(justify left bottom)
			)
		)
		(property "Description" "SMT Multilayer Ceramic Capacitor, 22 µF, 100 V, 2220 [5750 Metric], ± 20%, X7S, C"
			(at 0 0 90)
			(layer "F.Fab")
			(hide yes)
			(effects
				(font
					(size 1.27 1.27)
					(thickness 0.15)
				)
			)
		)
		(property "Author" "Antmicro"
			(at 425.85 -54.7 0)
			(layer "F.Fab")
			(hide yes)
			(effects
				(font
					(size 1 1)
					(thickness 0.15)
				)
			)
		)
		(property "Dielectric" "X7S"
			(at 425.85 -54.7 0)
			(layer "F.Fab")
			(hide yes)
			(effects
				(font
					(size 1 1)
					(thickness 0.15)
				)
			)
		)
		(property "License" "Apache-2.0"
			(at 425.85 -54.7 0)
			(layer "F.Fab")
			(hide yes)
			(effects
				(font
					(size 1 1)
					(thickness 0.15)
				)
			)
		)
		(property "MPN" "C5750X7S2A226M280KB"
			(at 425.85 -54.7 0)
			(layer "F.Fab")
			(hide yes)
			(effects
				(font
					(size 1 1)
					(thickness 0.15)
				)
			)
		)
		(property "Manufacturer" "TDK"
			(at 425.85 -54.7 0)
			(layer "F.Fab")
			(hide yes)
			(effects
				(font
					(size 1 1)
					(thickness 0.15)
				)
			)
		)
		(property "Val" "22u"
			(at 425.85 -54.7 0)
			(layer "F.Fab")
			(hide yes)
			(effects
				(font
					(size 1 1)
					(thickness 0.15)
				)
			)
		)
		(property "Voltage" "100V"
			(at 425.85 -54.7 0)
			(layer "F.Fab")
			(hide yes)
			(effects
				(font
					(size 1 1)
					(thickness 0.15)
				)
			)
		)
		(sheetname "Power supply")
		(sheetfile "power-supply.kicad_sch")
		(attr smd)
		(fp_line
			(start -1.415 -2.61)
			(end 1.415 -2.61)
			(stroke
				(width 0.15)
				(type solid)
			)
			(layer "F.SilkS")
		)
		(fp_line
			(start -1.415 2.61)
			(end 1.415 2.61)
			(stroke
				(width 0.15)
				(type solid)
			)
			(layer "F.SilkS")
		)
		(fp_rect
			(start -3.7 -2.95)
			(end 3.7 2.95)
			(stroke
				(width 0.05)
				(type solid)
			)
			(fill no)
			(layer "F.CrtYd")
		)
		(fp_rect
			(start -2.85 -2.5)
			(end 2.85 2.5)
			(stroke
				(width 0.15)
				(type solid)
			)
			(fill no)
			(layer "F.Fab")
		)
		(pad "1" smd roundrect
			(at -2.55 0 90)
			(size 1.8 5.4)
			(layers "F.Cu" "F.Mask" "F.Paste")
			(roundrect_rratio 0.138889)
			(net 699 "GNDD")
			(pintype "passive")
		)
		(pad "2" smd roundrect
			(at 2.55 0 90)
			(size 1.8 5.4)
			(layers "F.Cu" "F.Mask" "F.Paste")
			(roundrect_rratio 0.138889)
			(net 698 "/Power supply/VDD")
			(pintype "passive")
		)
	)
	(footprint "antmicro-footprints:C_0402_1005Metric"
		(layer "F.Cu")
		(at 156.225 158)
		(descr "Capacitor SMD 0402")
		(tags "capacitor SMD 0402")
		(property "Reference" "C350"
			(at -1.874 2.35 0)
			(layer "F.SilkS")
			(effects
				(font
					(size 0.7 0.7)
					(thickness 0.15)
				)
				(justify left bottom)
			)
		)
		(property "Value" "C_1n_0402"
			(at 0 1.4 0)
			(layer "F.Fab")
			(effects
				(font
					(size 0.7 0.7)
					(thickness 0.15)
				)
				(justify left bottom)
			)
		)
		(property "Description" "SMD Multilayer Ceramic Capacitor, 1000 pF, 50 V, 0402 [1005 Metric], ± 5%, C0G / NP0, GRM Series"
			(at 0 0 0)
			(layer "F.Fab")
			(hide yes)
			(effects
				(font
					(size 1.27 1.27)
					(thickness 0.15)
				)
			)
		)
		(property "Author" "Antmicro"
			(at 0 0 0)
			(layer "F.Fab")
			(hide yes)
			(effects
				(font
					(size 1 1)
					(thickness 0.15)
				)
			)
		)
		(property "Dielectric" "C0G"
			(at 0 0 0)
			(layer "F.Fab")
			(hide yes)
			(effects
				(font
					(size 1 1)
					(thickness 0.15)
				)
			)
		)
		(property "License" "Apache-2.0"
			(at 0 0 0)
			(layer "F.Fab")
			(hide yes)
			(effects
				(font
					(size 1 1)
					(thickness 0.15)
				)
			)
		)
		(property "MPN" "GRM1555C1H102JA01D"
			(at 0 0 0)
			(layer "F.Fab")
			(hide yes)
			(effects
				(font
					(size 1 1)
					(thickness 0.15)
				)
			)
		)
		(property "Manufacturer" "Murata"
			(at 0 0 0)
			(layer "F.Fab")
			(hide yes)
			(effects
				(font
					(size 1 1)
					(thickness 0.15)
				)
			)
		)
		(property "Val" "1n"
			(at 0 0 0)
			(layer "F.Fab")
			(hide yes)
			(effects
				(font
					(size 1 1)
					(thickness 0.15)
				)
			)
		)
		(property "Voltage" "50V"
			(at 0 0 0)
			(layer "F.Fab")
			(hide yes)
			(effects
				(font
					(size 1 1)
					(thickness 0.15)
				)
			)
		)
		(sheetname "DC-DC Converters")
		(sheetfile "dc-dc.kicad_sch")
		(attr smd)
		(fp_rect
			(start -0.925 -0.47)
			(end 0.925 0.47)
			(stroke
				(width 0.05)
				(type default)
			)
			(fill no)
			(layer "F.CrtYd")
		)
		(fp_line
			(start -0.494 -0.25)
			(end 0.504 -0.25)
			(stroke
				(width 0.15)
				(type solid)
			)
			(layer "F.Fab")
		)
		(fp_line
			(start -0.494 0.248)
			(end -0.494 -0.25)
			(stroke
				(width 0.15)
				(type solid)
			)
			(layer "F.Fab")
		)
		(fp_line
			(start 0.504 -0.25)
			(end 0.504 0.248)
			(stroke
				(width 0.15)
				(type solid)
			)
			(layer "F.Fab")
		)
		(fp_line
			(start 0.504 0.248)
			(end -0.494 0.248)
			(stroke
				(width 0.15)
				(type solid)
			)
			(layer "F.Fab")
		)
		(pad "1" smd roundrect
			(at -0.48 0)
			(size 0.59 0.64)
			(layers "F.Cu" "F.Mask" "F.Paste")
			(roundrect_rratio 0.25)
			(net 1 "GND")
			(pintype "passive")
		)
		(pad "2" smd roundrect
			(at 0.48 0)
			(size 0.59 0.64)
			(layers "F.Cu" "F.Mask" "F.Paste")
			(roundrect_rratio 0.25)
			(net 744 "/DC-DC Converters/VDDR_VRI")
			(pintype "passive")
		)
	)
	(footprint "antmicro-footprints:LED_0603_1608Metric_G"
		(layer "F.Cu")
		(at 266.585 139.31 180)
		(descr "LED SMD 0603 Green")
		(tags "LED SMD 0603 Green")
		(property "Reference" "D26"
			(at -1.065 -1.59 0)
			(layer "F.SilkS")
			(effects
				(font
					(size 0.7 0.7)
					(thickness 0.15)
				)
				(justify right bottom)
			)
		)
		(property "Value" "LED_G_0603_KP-1608CGCK"
			(at -0.001 1.599 0)
			(layer "F.Fab")
			(effects
				(font
					(size 0.7 0.7)
					(thickness 0.15)
				)
				(justify right bottom)
			)
		)
		(property "Description" "LED, Green, SMD, 0603, 20 mA, 2.1 V, 570 nm"
			(at 0 0 180)
			(layer "F.Fab")
			(hide yes)
			(effects
				(font
					(size 1.27 1.27)
					(thickness 0.15)
				)
			)
		)
		(property "Author" "Antmicro"
			(at 533.17 278.62 0)
			(layer "F.Fab")
			(hide yes)
			(effects
				(font
					(size 1 1)
					(thickness 0.15)
				)
			)
		)
		(property "Color" "Green"
			(at 533.17 278.62 0)
			(layer "F.Fab")
			(hide yes)
			(effects
				(font
					(size 1 1)
					(thickness 0.15)
				)
			)
		)
		(property "License" "Apache-2.0"
			(at 533.17 278.62 0)
			(layer "F.Fab")
			(hide yes)
			(effects
				(font
					(size 1 1)
					(thickness 0.15)
				)
			)
		)
		(property "MPN" "KP-1608CGCK"
			(at 533.17 278.62 0)
			(layer "F.Fab")
			(hide yes)
			(effects
				(font
					(size 1 1)
					(thickness 0.15)
				)
			)
		)
		(property "Manufacturer" "Kingbright"
			(at 533.17 278.62 0)
			(layer "F.Fab")
			(hide yes)
			(effects
				(font
					(size 1 1)
					(thickness 0.15)
				)
			)
		)
		(sheetname "USB PHY")
		(sheetfile "usb-phy.kicad_sch")
		(attr smd)
		(fp_line
			(start 0.22 0.35)
			(end -0.22 0.35)
			(stroke
				(width 0.15)
				(type solid)
			)
			(layer "F.SilkS")
		)
		(fp_line
			(start 0.22 -0.35)
			(end -0.22 -0.35)
			(stroke
				(width 0.15)
				(type solid)
			)
			(layer "F.SilkS")
		)
		(fp_line
			(start 0.105328 0.201008)
			(end 0.105328 -0.198992)
			(stroke
				(width 0.1)
				(type solid)
			)
			(layer "F.SilkS")
		)
		(fp_line
			(start 0.105328 0.201008)
			(end -0.094672 0.001008)
			(stroke
				(width 0.1)
				(type solid)
			)
			(layer "F.SilkS")
		)
		(fp_line
			(start 0.105328 0.001008)
			(end 0.24 0.001)
			(stroke
				(width 0.1)
				(type solid)
			)
			(layer "F.SilkS")
		)
		(fp_line
			(start -0.094672 0.201008)
			(end -0.094672 -0.198992)
			(stroke
				(width 0.1)
				(type solid)
			)
			(layer "F.SilkS")
		)
		(fp_line
			(start -0.094672 0.001008)
			(end 0.105328 -0.198992)
			(stroke
				(width 0.1)
				(type solid)
			)
			(layer "F.SilkS")
		)
		(fp_line
			(start -0.094672 0.001008)
			(end -0.24 0.001008)
			(stroke
				(width 0.1)
				(type solid)
			)
			(layer "F.SilkS")
		)
		(fp_line
			(start -1.18 -0.319)
			(end -1.18 0.321)
			(stroke
				(width 0.15)
				(type solid)
			)
			(layer "F.SilkS")
		)
		(fp_rect
			(start 1.25 0.65)
			(end -1.25 -0.65)
			(stroke
				(width 0.05)
				(type solid)
			)
			(fill no)
			(layer "F.CrtYd")
		)
		(fp_line
			(start 0.599 0)
			(end 0.201 0)
			(stroke
				(width 0.15)
				(type solid)
			)
			(layer "F.Fab")
		)
		(fp_line
			(start 0.201 0.2)
			(end 0.201 0)
			(stroke
				(width 0.15)
				(type solid)
			)
			(layer "F.Fab")
		)
		(fp_line
			(start 0.201 0)
			(end 0.201 -0.202)
			(stroke
				(width 0.15)
				(type solid)
			)
			(layer "F.Fab")
		)
		(fp_line
			(start 0.201 -0.202)
			(end -0.101 0)
			(stroke
				(width 0.15)
				(type solid)
			)
			(layer "F.Fab")
		)
		(fp_line
			(start -0.101 0)
			(end 0.201 0.2)
			(stroke
				(width 0.15)
				(type solid)
			)
			(layer "F.Fab")
		)
		(fp_line
			(start -0.199 0.2)
			(end -0.199 0.1)
			(stroke
				(width 0.15)
				(type solid)
			)
			(layer "F.Fab")
		)
		(fp_line
			(start -0.199 0)
			(end -0.597 0)
			(stroke
				(width 0.15)
				(type solid)
			)
			(layer "F.Fab")
		)
		(fp_line
			(start -0.199 -0.202)
			(end -0.199 0.1)
			(stroke
				(width 0.15)
				(type solid)
			)
			(layer "F.Fab")
		)
		(fp_rect
			(start 0.848 0.4)
			(end -0.85 -0.402)
			(stroke
				(width 0.15)
				(type solid)
			)
			(fill no)
			(layer "F.Fab")
		)
		(pad "1" smd roundrect
			(at -0.7 0)
			(size 0.8 1)
			(layers "F.Cu" "F.Mask" "F.Paste")
			(roundrect_rratio 0.2)
			(net 1 "GND")
			(pinfunction "C")
			(pintype "passive")
		)
		(pad "2" smd roundrect
			(at 0.7 0)
			(size 0.8 1)
			(layers "F.Cu" "F.Mask" "F.Paste")
			(roundrect_rratio 0.2)
			(net 790 "Net-(D26-A)")
			(pinfunction "A")
			(pintype "passive")
		)
	)
	(footprint "antmicro-footprints:R_0402_1005Metric"
		(layer "F.Cu")
		(at 236.2 132.55 180)
		(descr "Resistor SMD 0402")
		(tags "resistor SMD 0402")
		(property "Reference" "R176"
			(at 1.825 3.525 180)
			(layer "F.SilkS")
			(effects
				(font
					(size 0.7 0.7)
					(thickness 0.15)
				)
				(justify left bottom)
			)
		)
		(property "Value" "R_33R_0402"
			(at 0 1.4 180)
			(layer "F.Fab")
			(effects
				(font
					(size 0.7 0.7)
					(thickness 0.15)
				)
				(justify left bottom)
			)
		)
		(property "Description" "SMD Chip Resistor, 33 ohm, ± 1%, 62.5 mW, 0402 [1005 Metric], Thick Film, General Purpose"
			(at 0 0 180)
			(layer "F.Fab")
			(hide yes)
			(effects
				(font
					(size 1.27 1.27)
					(thickness 0.15)
				)
			)
		)
		(property "Author" "Antmicro"
			(at 472.4 265.1 0)
			(layer "F.Fab")
			(hide yes)
			(effects
				(font
					(size 1 1)
					(thickness 0.15)
				)
			)
		)
		(property "License" "Apache-2.0"
			(at 472.4 265.1 0)
			(layer "F.Fab")
			(hide yes)
			(effects
				(font
					(size 1 1)
					(thickness 0.15)
				)
			)
		)
		(property "MPN" "CR0402-FX-33R0GLF"
			(at 472.4 265.1 0)
			(layer "F.Fab")
			(hide yes)
			(effects
				(font
					(size 1 1)
					(thickness 0.15)
				)
			)
		)
		(property "Manufacturer" "Bourns"
			(at 472.4 265.1 0)
			(layer "F.Fab")
			(hide yes)
			(effects
				(font
					(size 1 1)
					(thickness 0.15)
				)
			)
		)
		(property "Tolerance" "1%"
			(at 472.4 265.1 0)
			(layer "F.Fab")
			(hide yes)
			(effects
				(font
					(size 1 1)
					(thickness 0.15)
				)
			)
		)
		(property "Val" "33R"
			(at 472.4 265.1 0)
			(layer "F.Fab")
			(hide yes)
			(effects
				(font
					(size 1 1)
					(thickness 0.15)
				)
			)
		)
		(sheetname "USB PHY")
		(sheetfile "usb-phy.kicad_sch")
		(attr smd)
		(fp_rect
			(start -0.925 -0.47)
			(end 0.925 0.47)
			(stroke
				(width 0.05)
				(type default)
			)
			(fill no)
			(layer "F.CrtYd")
		)
		(fp_rect
			(start -0.5 -0.25)
			(end 0.5 0.25)
			(stroke
				(width 0.15)
				(type solid)
			)
			(fill no)
			(layer "F.Fab")
		)
		(pad "1" smd roundrect
			(at -0.48 0 180)
			(size 0.59 0.64)
			(layers "F.Cu" "F.Mask" "F.Paste")
			(roundrect_rratio 0.25)
			(net 368 "Net-(U22-B1Y)")
			(pintype "passive")
		)
		(pad "2" smd roundrect
			(at 0.48 0 180)
			(size 0.59 0.64)
			(layers "F.Cu" "F.Mask" "F.Paste")
			(roundrect_rratio 0.25)
			(net 165 "/FPGA Config/JTAG.TCK")
			(pintype "passive")
		)
	)
	(footprint "antmicro-footprints:C_0402_1005Metric"
		(layer "F.Cu")
		(at 173.570001 121.430001 180)
		(descr "Capacitor SMD 0402")
		(tags "capacitor SMD 0402")
		(property "Reference" "C312"
			(at -3.729999 -0.369999 0)
			(layer "F.SilkS")
			(effects
				(font
					(size 0.7 0.7)
					(thickness 0.15)
				)
				(justify right bottom)
			)
		)
		(property "Value" "C_100n_0402"
			(at 0 1.4 0)
			(layer "F.Fab")
			(effects
				(font
					(size 0.7 0.7)
					(thickness 0.15)
				)
				(justify right bottom)
			)
		)
		(property "Description" "SMD Multilayer Ceramic Capacitor, 0.1 µF, 50 V, 0402 [1005 Metric], ± 10%, X5R, GRM Series"
			(at 0 0 180)
			(layer "F.Fab")
			(hide yes)
			(effects
				(font
					(size 1.27 1.27)
					(thickness 0.15)
				)
			)
		)
		(property "Author" "Antmicro"
			(at 347.140002 242.860002 0)
			(layer "F.Fab")
			(hide yes)
			(effects
				(font
					(size 1 1)
					(thickness 0.15)
				)
			)
		)
		(property "Dielectric" "X5R"
			(at 347.140002 242.860002 0)
			(layer "F.Fab")
			(hide yes)
			(effects
				(font
					(size 1 1)
					(thickness 0.15)
				)
			)
		)
		(property "License" "Apache-2.0"
			(at 347.140002 242.860002 0)
			(layer "F.Fab")
			(hide yes)
			(effects
				(font
					(size 1 1)
					(thickness 0.15)
				)
			)
		)
		(property "MPN" "GRM155R61H104KE14D"
			(at 347.140002 242.860002 0)
			(layer "F.Fab")
			(hide yes)
			(effects
				(font
					(size 1 1)
					(thickness 0.15)
				)
			)
		)
		(property "Manufacturer" "Murata"
			(at 347.140002 242.860002 0)
			(layer "F.Fab")
			(hide yes)
			(effects
				(font
					(size 1 1)
					(thickness 0.15)
				)
			)
		)
		(property "Val" "100n"
			(at 347.140002 242.860002 0)
			(layer "F.Fab")
			(hide yes)
			(effects
				(font
					(size 1 1)
					(thickness 0.15)
				)
			)
		)
		(property "Voltage" "50V"
			(at 347.140002 242.860002 0)
			(layer "F.Fab")
			(hide yes)
			(effects
				(font
					(size 1 1)
					(thickness 0.15)
				)
			)
		)
		(sheetname "FMC+ HSPC")
		(sheetfile "fmc-hspc.kicad_sch")
		(attr smd)
		(fp_rect
			(start -0.925 -0.47)
			(end 0.925 0.47)
			(stroke
				(width 0.05)
				(type default)
			)
			(fill no)
			(layer "F.CrtYd")
		)
		(fp_line
			(start 0.504 0.248)
			(end -0.494 0.248)
			(stroke
				(width 0.15)
				(type solid)
			)
			(layer "F.Fab")
		)
		(fp_line
			(start 0.504 -0.25)
			(end 0.504 0.248)
			(stroke
				(width 0.15)
				(type solid)
			)
			(layer "F.Fab")
		)
		(fp_line
			(start -0.494 0.248)
			(end -0.494 -0.25)
			(stroke
				(width 0.15)
				(type solid)
			)
			(layer "F.Fab")
		)
		(fp_line
			(start -0.494 -0.25)
			(end 0.504 -0.25)
			(stroke
				(width 0.15)
				(type solid)
			)
			(layer "F.Fab")
		)
		(pad "1" smd roundrect
			(at -0.48 0 180)
			(size 0.59 0.64)
			(layers "F.Cu" "F.Mask" "F.Paste")
			(roundrect_rratio 0.25)
			(net 122 "/FMC+ HSPC/GTX115.TX0_P")
			(pintype "passive")
		)
		(pad "2" smd roundrect
			(at 0.48 0 180)
			(size 0.59 0.64)
			(layers "F.Cu" "F.Mask" "F.Paste")
			(roundrect_rratio 0.25)
			(net 119 "/FMC+ HSPC/GTX_TX7_C_P")
			(pintype "passive")
		)
	)
	(footprint "antmicro-footprints:QFN-32-1EP_5x5mm"
		(layer "F.Cu")
		(at 195.346 108.702)
		(property "Reference" "U19"
			(at -3.169 -3.12 0)
			(layer "F.SilkS")
			(effects
				(font
					(size 0.7 0.7)
					(thickness 0.15)
				)
				(justify left bottom)
			)
		)
		(property "Value" "MAX3421EETJ+"
			(at -4.939 3.91 0)
			(layer "F.Fab")
			(effects
				(font
					(size 0.7 0.7)
					(thickness 0.15)
				)
				(justify left bottom)
			)
		)
		(property "Description" "USB Interface, ESD-Protected USB Peripheral/Host Controller, USB 2.0, 3 V, 3.6 V, TQFN, 32 Pins"
			(at 0 0 0)
			(layer "F.Fab")
			(hide yes)
			(effects
				(font
					(size 1.27 1.27)
					(thickness 0.15)
				)
			)
		)
		(property "Author" "Antmicro"
			(at 0 0 0)
			(layer "F.Fab")
			(hide yes)
			(effects
				(font
					(size 1 1)
					(thickness 0.15)
				)
			)
		)
		(property "License" "Apache-2.0"
			(at 0 0 0)
			(layer "F.Fab")
			(hide yes)
			(effects
				(font
					(size 1 1)
					(thickness 0.15)
				)
			)
		)
		(property "MPN" "MAX3421EETJ+"
			(at 0 0 0)
			(layer "F.Fab")
			(hide yes)
			(effects
				(font
					(size 1 1)
					(thickness 0.15)
				)
			)
		)
		(property "Manufacturer" "Maxim Integrated Products"
			(at 0 0 0)
			(layer "F.Fab")
			(hide yes)
			(effects
				(font
					(size 1 1)
					(thickness 0.15)
				)
			)
		)
		(sheetname "USB PHY")
		(sheetfile "usb-phy.kicad_sch")
		(attr smd)
		(fp_line
			(start -2.62 2.648)
			(end -2.62 2.249)
			(stroke
				(width 0.15)
				(type solid)
			)
			(layer "F.SilkS")
		)
		(fp_line
			(start -2.221 -2.551)
			(end -2.62 -2.149)
			(stroke
				(width 0.15)
				(type solid)
			)
			(layer "F.SilkS")
		)
		(fp_line
			(start -2.221 2.648)
			(end -2.62 2.648)
			(stroke
				(width 0.15)
				(type solid)
			)
			(layer "F.SilkS")
		)
		(fp_line
			(start 2.581 -2.551)
			(end 2.178 -2.551)
			(stroke
				(width 0.15)
				(type solid)
			)
			(layer "F.SilkS")
		)
		(fp_line
			(start 2.581 -2.551)
			(end 2.581 -2.149)
			(stroke
				(width 0.15)
				(type solid)
			)
			(layer "F.SilkS")
		)
		(fp_line
			(start 2.581 2.249)
			(end 2.581 2.648)
			(stroke
				(width 0.15)
				(type solid)
			)
			(layer "F.SilkS")
		)
		(fp_line
			(start 2.581 2.648)
			(end 2.178 2.648)
			(stroke
				(width 0.15)
				(type solid)
			)
			(layer "F.SilkS")
		)
		(fp_circle
			(center -3.25 -1.702)
			(end -3.2 -1.702)
			(stroke
				(width 0.15)
				(type solid)
			)
			(fill yes)
			(layer "F.SilkS")
		)
		(fp_rect
			(start -1.446 -0.175)
			(end -0.246 -1.375)
			(stroke
				(width 0.2)
				(type solid)
			)
			(fill yes)
			(layer "F.Paste")
		)
		(fp_rect
			(start -1.446 1.474)
			(end -0.246 0.274)
			(stroke
				(width 0.2)
				(type solid)
			)
			(fill yes)
			(layer "F.Paste")
		)
		(fp_rect
			(start 0.203 -0.175)
			(end 1.403 -1.375)
			(stroke
				(width 0.2)
				(type solid)
			)
			(fill yes)
			(layer "F.Paste")
		)
		(fp_rect
			(start 0.203 1.474)
			(end 1.403 0.274)
			(stroke
				(width 0.2)
				(type solid)
			)
			(fill yes)
			(layer "F.Paste")
		)
		(fp_rect
			(start -2.74 -2.75)
			(end 2.75 2.74)
			(stroke
				(width 0.05)
				(type solid)
			)
			(fill no)
			(layer "F.CrtYd")
		)
		(fp_line
			(start -2.499 -2.299)
			(end -2.298 -2.5)
			(stroke
				(width 0.15)
				(type solid)
			)
			(layer "F.Fab")
		)
		(fp_rect
			(start -2.499 -2.5)
			(end 2.5 2.499)
			(stroke
				(width 0.15)
				(type solid)
			)
			(fill no)
			(layer "F.Fab")
		)
		(pad "1" smd rect
			(at -2.495 -1.702 270)
			(size 0.28 0.85)
			(layers "F.Cu" "F.Mask" "F.Paste")
			(net 1166 "unconnected-(U19-GPIN7-Pad1)")
			(pinfunction "GPIN7")
			(pintype "input+no_connect")
			(solder_mask_margin 0.07)
		)
		(pad "2" smd rect
			(at -2.495 -1.2 270)
			(size 0.28 0.85)
			(layers "F.Cu" "F.Mask" "F.Paste")
			(net 24 "+3V3")
			(pinfunction "VL")
			(pintype "power_in")
			(solder_mask_margin 0.07)
		)
		(pad "3" smd rect
			(at -2.495 -0.701 270)
			(size 0.28 0.85)
			(layers "F.Cu" "F.Mask" "F.Paste")
			(net 1 "GND")
			(pinfunction "GND")
			(pintype "passive")
			(solder_mask_margin 0.07)
		)
		(pad "4" smd rect
			(at -2.495 -0.201 270)
			(size 0.28 0.85)
			(layers "F.Cu" "F.Mask" "F.Paste")
			(net 1167 "unconnected-(U19-GPOUT0-Pad4)")
			(pinfunction "GPOUT0")
			(pintype "output+no_connect")
			(solder_mask_margin 0.07)
		)
		(pad "5" smd rect
			(at -2.495 0.296 270)
			(size 0.28 0.85)
			(layers "F.Cu" "F.Mask" "F.Paste")
			(net 1168 "unconnected-(U19-GPOUT1-Pad5)")
			(pinfunction "GPOUT1")
			(pintype "output+no_connect")
			(solder_mask_margin 0.07)
		)
		(pad "6" smd rect
			(at -2.495 0.8 270)
			(size 0.28 0.85)
			(layers "F.Cu" "F.Mask" "F.Paste")
			(net 1169 "unconnected-(U19-GPOUT2-Pad6)")
			(pinfunction "GPOUT2")
			(pintype "output+no_connect")
			(solder_mask_margin 0.07)
		)
		(pad "7" smd rect
			(at -2.495 1.3 270)
			(size 0.28 0.85)
			(layers "F.Cu" "F.Mask" "F.Paste")
			(net 1170 "unconnected-(U19-GPOUT3-Pad7)")
			(pinfunction "GPOUT3")
			(pintype "output+no_connect")
			(solder_mask_margin 0.07)
		)
		(pad "8" smd rect
			(at -2.495 1.8 270)
			(size 0.28 0.85)
			(layers "F.Cu" "F.Mask" "F.Paste")
			(net 1171 "unconnected-(U19-GPOUT4-Pad8)")
			(pinfunction "GPOUT4")
			(pintype "output+no_connect")
			(solder_mask_margin 0.07)
		)
		(pad "9" smd rect
			(at -1.768 2.523 270)
			(size 0.85 0.28)
			(layers "F.Cu" "F.Mask" "F.Paste")
			(net 1172 "unconnected-(U19-GPOUT5-Pad9)")
			(pinfunction "GPOUT5")
			(pintype "output+no_connect")
			(solder_mask_margin 0.07)
		)
		(pad "10" smd rect
			(at -1.269 2.523 270)
			(size 0.85 0.28)
			(layers "F.Cu" "F.Mask" "F.Paste")
			(net 1173 "unconnected-(U19-GPOUT6-Pad10)")
			(pinfunction "GPOUT6")
			(pintype "output+no_connect")
			(solder_mask_margin 0.07)
		)
		(pad "11" smd rect
			(at -0.772 2.523 270)
			(size 0.85 0.28)
			(layers "F.Cu" "F.Mask" "F.Paste")
			(net 1174 "unconnected-(U19-GPOUT7-Pad11)")
			(pinfunction "GPOUT7")
			(pintype "output+no_connect")
			(solder_mask_margin 0.07)
		)
		(pad "12" smd rect
			(at -0.272 2.523 270)
			(size 0.85 0.28)
			(layers "F.Cu" "F.Mask" "F.Paste")
			(net 496 "/FPGA Bank 12 & 13/USB_HOST.~{RESET}")
			(pinfunction "~{RES}")
			(pintype "input")
			(solder_mask_margin 0.07)
		)
		(pad "13" smd rect
			(at 0.229 2.523 270)
			(size 0.85 0.28)
			(layers "F.Cu" "F.Mask" "F.Paste")
			(net 578 "/FPGA Bank 12 & 13/USB_HOST.CLK")
			(pinfunction "SCLK")
			(pintype "input")
			(solder_mask_margin 0.07)
		)
		(pad "14" smd rect
			(at 0.728 2.523 270)
			(size 0.85 0.28)
			(layers "F.Cu" "F.Mask" "F.Paste")
			(net 893 "/FPGA Bank 12 & 13/USB_HOST.~{CS}")
			(pinfunction "~{SS}")
			(pintype "input")
			(solder_mask_margin 0.07)
		)
		(pad "15" smd rect
			(at 1.23 2.523 270)
			(size 0.85 0.28)
			(layers "F.Cu" "F.Mask" "F.Paste")
			(net 579 "/FPGA Bank 12 & 13/USB_HOST.MISO")
			(pinfunction "MISO")
			(pintype "output")
			(solder_mask_margin 0.07)
		)
		(pad "16" smd rect
			(at 1.73 2.523 270)
			(size 0.85 0.28)
			(layers "F.Cu" "F.Mask" "F.Paste")
			(net 938 "/FPGA Bank 12 & 13/USB_HOST.MOSI")
			(pinfunction "MOSI")
			(pintype "input")
			(solder_mask_margin 0.07)
		)
		(pad "17" smd rect
			(at 2.456 1.8 270)
			(size 0.28 0.85)
			(layers "F.Cu" "F.Mask" "F.Paste")
			(net 580 "/FPGA Bank 12 & 13/USB_HOST.GPX")
			(pinfunction "GPX")
			(pintype "output")
			(solder_mask_margin 0.07)
		)
		(pad "18" smd rect
			(at 2.456 1.3 270)
			(size 0.28 0.85)
			(layers "F.Cu" "F.Mask" "F.Paste")
			(net 495 "/FPGA Bank 12 & 13/USB_HOST.INT")
			(pinfunction "INT")
			(pintype "output")
			(solder_mask_margin 0.07)
		)
		(pad "19" smd rect
			(at 2.456 0.8 270)
			(size 0.28 0.85)
			(layers "F.Cu" "F.Mask" "F.Paste")
			(net 1 "GND")
			(pinfunction "GND")
			(pintype "passive")
			(solder_mask_margin 0.07)
		)
		(pad "20" smd rect
			(at 2.456 0.296 270)
			(size 0.28 0.85)
			(layers "F.Cu" "F.Mask" "F.Paste")
			(net 916 "/USB PHY/USB_HOST_D-")
			(pinfunction "D-")
			(pintype "bidirectional")
			(solder_mask_margin 0.07)
		)
		(pad "21" smd rect
			(at 2.456 -0.201 270)
			(size 0.28 0.85)
			(layers "F.Cu" "F.Mask" "F.Paste")
			(net 917 "/USB PHY/USB_HOST_D+")
			(pinfunction "D+")
			(pintype "bidirectional")
			(solder_mask_margin 0.07)
		)
		(pad "22" smd rect
			(at 2.456 -0.701 270)
			(size 0.28 0.85)
			(layers "F.Cu" "F.Mask" "F.Paste")
			(net 709 "/USB PHY/USB_HOST_VBCOMP")
			(pinfunction "VBCOMP")
			(pintype "input")
			(solder_mask_margin 0.07)
		)
		(pad "23" smd rect
			(at 2.456 -1.2 270)
			(size 0.28 0.85)
			(layers "F.Cu" "F.Mask" "F.Paste")
			(net 24 "+3V3")
			(pinfunction "VCC")
			(pintype "power_in")
			(solder_mask_margin 0.07)
		)
		(pad "24" smd rect
			(at 2.456 -1.702 270)
			(size 0.28 0.85)
			(layers "F.Cu" "F.Mask" "F.Paste")
			(net 706 "/USB PHY/USB_HOST_XI")
			(pinfunction "XI")
			(pintype "input")
			(solder_mask_margin 0.07)
		)
		(pad "25" smd rect
			(at 1.73 -2.426 270)
			(size 0.85 0.28)
			(layers "F.Cu" "F.Mask" "F.Paste")
			(net 708 "/USB PHY/USB_HOST_XO")
			(pinfunction "XO")
			(pintype "output")
			(solder_mask_margin 0.07)
		)
		(pad "26" smd rect
			(at 1.23 -2.426 270)
			(size 0.85 0.28)
			(layers "F.Cu" "F.Mask" "F.Paste")
			(net 1175 "unconnected-(U19-GPIN0-Pad26)")
			(pinfunction "GPIN0")
			(pintype "input+no_connect")
			(solder_mask_margin 0.07)
		)
		(pad "27" smd rect
			(at 0.728 -2.426 270)
			(size 0.85 0.28)
			(layers "F.Cu" "F.Mask" "F.Paste")
			(net 1176 "unconnected-(U19-GPIN1-Pad27)")
			(pinfunction "GPIN1")
			(pintype "input+no_connect")
			(solder_mask_margin 0.07)
		)
		(pad "28" smd rect
			(at 0.229 -2.426 270)
			(size 0.85 0.28)
			(layers "F.Cu" "F.Mask" "F.Paste")
			(net 1177 "unconnected-(U19-GPIN2-Pad28)")
			(pinfunction "GPIN2")
			(pintype "input+no_connect")
			(solder_mask_margin 0.07)
		)
		(pad "29" smd rect
			(at -0.272 -2.426 270)
			(size 0.85 0.28)
			(layers "F.Cu" "F.Mask" "F.Paste")
			(net 1178 "unconnected-(U19-GPIN3-Pad29)")
			(pinfunction "GPIN3")
			(pintype "input+no_connect")
			(solder_mask_margin 0.07)
		)
		(pad "30" smd rect
			(at -0.772 -2.426 270)
			(size 0.85 0.28)
			(layers "F.Cu" "F.Mask" "F.Paste")
			(net 1179 "unconnected-(U19-GPIN4-Pad30)")
			(pinfunction "GPIN4")
			(pintype "input+no_connect")
			(solder_mask_margin 0.07)
		)
		(pad "31" smd rect
			(at -1.269 -2.426 270)
			(size 0.85 0.28)
			(layers "F.Cu" "F.Mask" "F.Paste")
			(net 1180 "unconnected-(U19-GPIN5-Pad31)")
			(pinfunction "GPIN5")
			(pintype "input+no_connect")
			(solder_mask_margin 0.07)
		)
		(pad "32" smd rect
			(at -1.768 -2.426 270)
			(size 0.85 0.28)
			(layers "F.Cu" "F.Mask" "F.Paste")
			(net 1181 "unconnected-(U19-GPIN6-Pad32)")
			(pinfunction "GPIN6")
			(pintype "input+no_connect")
			(solder_mask_margin 0.07)
		)
		(pad "33" smd rect
			(at -0.02 0.048 270)
			(size 3.45 3.45)
			(layers "F.Cu" "F.Mask")
			(net 1 "GND")
			(pinfunction "EP")
			(pintype "passive")
		)
	)
	(footprint "antmicro-footprints:C_0402_1005Metric"
		(layer "F.Cu")
		(at 250.899 101)
		(descr "Capacitor SMD 0402")
		(tags "capacitor SMD 0402")
		(property "Reference" "C242"
			(at -1.449 2.35 0)
			(layer "F.SilkS")
			(effects
				(font
					(size 0.7 0.7)
					(thickness 0.15)
				)
				(justify left bottom)
			)
		)
		(property "Value" "C_100n_0402"
			(at 0 1.169 0)
			(layer "F.Fab")
			(effects
				(font
					(size 0.7 0.7)
					(thickness 0.15)
				)
				(justify left bottom)
			)
		)
		(property "Description" "SMD Multilayer Ceramic Capacitor, 0.1 µF, 50 V, 0402 [1005 Metric], ± 10%, X5R, GRM Series"
			(at 0 0 0)
			(layer "F.Fab")
			(hide yes)
			(effects
				(font
					(size 1.27 1.27)
					(thickness 0.15)
				)
			)
		)
		(property "Author" "Antmicro"
			(at 0 0 0)
			(layer "F.Fab")
			(hide yes)
			(effects
				(font
					(size 1 1)
					(thickness 0.15)
				)
			)
		)
		(property "Dielectric" "X5R"
			(at 0 0 0)
			(layer "F.Fab")
			(hide yes)
			(effects
				(font
					(size 1 1)
					(thickness 0.15)
				)
			)
		)
		(property "License" "Apache-2.0"
			(at 0 0 0)
			(layer "F.Fab")
			(hide yes)
			(effects
				(font
					(size 1 1)
					(thickness 0.15)
				)
			)
		)
		(property "MPN" "GRM155R61H104KE14D"
			(at 0 0 0)
			(layer "F.Fab")
			(hide yes)
			(effects
				(font
					(size 1 1)
					(thickness 0.15)
				)
			)
		)
		(property "Manufacturer" "Murata"
			(at 0 0 0)
			(layer "F.Fab")
			(hide yes)
			(effects
				(font
					(size 1 1)
					(thickness 0.15)
				)
			)
		)
		(property "Val" "100n"
			(at 0 0 0)
			(layer "F.Fab")
			(hide yes)
			(effects
				(font
					(size 1 1)
					(thickness 0.15)
				)
			)
		)
		(property "Voltage" "50V"
			(at 0 0 0)
			(layer "F.Fab")
			(hide yes)
			(effects
				(font
					(size 1 1)
					(thickness 0.15)
				)
			)
		)
		(sheetname "USB PHY")
		(sheetfile "usb-phy.kicad_sch")
		(attr smd)
		(fp_rect
			(start -0.925 -0.47)
			(end 0.925 0.47)
			(stroke
				(width 0.05)
				(type default)
			)
			(fill no)
			(layer "F.CrtYd")
		)
		(fp_line
			(start -0.494 -0.25)
			(end 0.504 -0.25)
			(stroke
				(width 0.15)
				(type solid)
			)
			(layer "F.Fab")
		)
		(fp_line
			(start -0.494 0.248)
			(end -0.494 -0.25)
			(stroke
				(width 0.15)
				(type solid)
			)
			(layer "F.Fab")
		)
		(fp_line
			(start 0.504 -0.25)
			(end 0.504 0.248)
			(stroke
				(width 0.15)
				(type solid)
			)
			(layer "F.Fab")
		)
		(fp_line
			(start 0.504 0.248)
			(end -0.494 0.248)
			(stroke
				(width 0.15)
				(type solid)
			)
			(layer "F.Fab")
		)
		(pad "1" smd roundrect
			(at -0.48 0)
			(size 0.59 0.64)
			(layers "F.Cu" "F.Mask" "F.Paste")
			(roundrect_rratio 0.25)
			(net 1 "GND")
			(pintype "passive")
		)
		(pad "2" smd roundrect
			(at 0.48 0)
			(size 0.59 0.64)
			(layers "F.Cu" "F.Mask" "F.Paste")
			(roundrect_rratio 0.25)
			(net 703 "+5V")
			(pintype "passive")
		)
	)
	(footprint "antmicro-footprints:R_0402_1005Metric"
		(layer "F.Cu")
		(at 199.901 108.249 180)
		(descr "Resistor SMD 0402")
		(tags "resistor SMD 0402")
		(property "Reference" "R155"
			(at -0.899 -0.351 180)
			(layer "F.SilkS")
			(effects
				(font
					(size 0.7 0.7)
					(thickness 0.15)
				)
				(justify left bottom)
			)
		)
		(property "Value" "R_33R_0402"
			(at 0 1.4 180)
			(layer "F.Fab")
			(effects
				(font
					(size 0.7 0.7)
					(thickness 0.15)
				)
				(justify left bottom)
			)
		)
		(property "Description" "SMD Chip Resistor, 33 ohm, ± 1%, 62.5 mW, 0402 [1005 Metric], Thick Film, General Purpose"
			(at 0 0 180)
			(layer "F.Fab")
			(hide yes)
			(effects
				(font
					(size 1.27 1.27)
					(thickness 0.15)
				)
			)
		)
		(property "Author" "Antmicro"
			(at 399.802 216.498 0)
			(layer "F.Fab")
			(hide yes)
			(effects
				(font
					(size 1 1)
					(thickness 0.15)
				)
			)
		)
		(property "License" "Apache-2.0"
			(at 399.802 216.498 0)
			(layer "F.Fab")
			(hide yes)
			(effects
				(font
					(size 1 1)
					(thickness 0.15)
				)
			)
		)
		(property "MPN" "CR0402-FX-33R0GLF"
			(at 399.802 216.498 0)
			(layer "F.Fab")
			(hide yes)
			(effects
				(font
					(size 1 1)
					(thickness 0.15)
				)
			)
		)
		(property "Manufacturer" "Bourns"
			(at 399.802 216.498 0)
			(layer "F.Fab")
			(hide yes)
			(effects
				(font
					(size 1 1)
					(thickness 0.15)
				)
			)
		)
		(property "Tolerance" "1%"
			(at 399.802 216.498 0)
			(layer "F.Fab")
			(hide yes)
			(effects
				(font
					(size 1 1)
					(thickness 0.15)
				)
			)
		)
		(property "Val" "33R"
			(at 399.802 216.498 0)
			(layer "F.Fab")
			(hide yes)
			(effects
				(font
					(size 1 1)
					(thickness 0.15)
				)
			)
		)
		(sheetname "USB PHY")
		(sheetfile "usb-phy.kicad_sch")
		(attr smd)
		(fp_rect
			(start -0.925 -0.47)
			(end 0.925 0.47)
			(stroke
				(width 0.05)
				(type default)
			)
			(fill no)
			(layer "F.CrtYd")
		)
		(fp_rect
			(start -0.5 -0.25)
			(end 0.5 0.25)
			(stroke
				(width 0.15)
				(type solid)
			)
			(fill no)
			(layer "F.Fab")
		)
		(pad "1" smd roundrect
			(at -0.48 0 180)
			(size 0.59 0.64)
			(layers "F.Cu" "F.Mask" "F.Paste")
			(roundrect_rratio 0.25)
			(net 836 "/USB PHY/USB_HOST_CONN_D+")
			(pintype "passive")
		)
		(pad "2" smd roundrect
			(at 0.48 0 180)
			(size 0.59 0.64)
			(layers "F.Cu" "F.Mask" "F.Paste")
			(roundrect_rratio 0.25)
			(net 917 "/USB PHY/USB_HOST_D+")
			(pintype "passive")
		)
	)
	(footprint "antmicro-footprints:Nexperia_SOD128"
		(layer "F.Cu")
		(at 188.625 179.999)
		(property "Reference" "D17"
			(at -3.275 0.001 90)
			(layer "F.SilkS")
			(effects
				(font
					(size 0.7 0.7)
					(thickness 0.15)
				)
			)
		)
		(property "Value" "PMEG3050EP,115"
			(at 0 2.4765 0)
			(layer "F.Fab")
			(effects
				(font
					(size 1 1)
					(thickness 0.15)
				)
			)
		)
		(property "Description" "Schottky Rectifier, 30 V, 5 A, Single, SOD-128, 2 Pins, 360 mV"
			(at 0 0 0)
			(layer "F.Fab")
			(hide yes)
			(effects
				(font
					(size 1.27 1.27)
					(thickness 0.15)
				)
			)
		)
		(property "Author" "Antmicro"
			(at 0 0 0)
			(layer "F.Fab")
			(hide yes)
			(effects
				(font
					(size 1 1)
					(thickness 0.15)
				)
			)
		)
		(property "DNP" "DNP"
			(at 0 0 0)
			(layer "F.Fab")
			(hide yes)
			(effects
				(font
					(size 1 1)
					(thickness 0.15)
				)
			)
		)
		(property "License" "Apache-2.0"
			(at 0 0 0)
			(layer "F.Fab")
			(hide yes)
			(effects
				(font
					(size 1 1)
					(thickness 0.15)
				)
			)
		)
		(property "MPN" "PMEG3050EP,115"
			(at 0 0 0)
			(layer "F.Fab")
			(hide yes)
			(effects
				(font
					(size 1 1)
					(thickness 0.15)
				)
			)
		)
		(property "Manufacturer" "Nexperia"
			(at 0 0 0)
			(layer "F.Fab")
			(hide yes)
			(effects
				(font
					(size 1 1)
					(thickness 0.15)
				)
			)
		)
		(property "dnp" ""
			(at 0 0 0)
			(layer "F.Fab")
			(hide yes)
			(effects
				(font
					(size 1 1)
					(thickness 0.15)
				)
			)
		)
		(property "exclude_from_bom" ""
			(at 0 0 0)
			(layer "F.Fab")
			(hide yes)
			(effects
				(font
					(size 1 1)
					(thickness 0.15)
				)
			)
		)
		(sheetname "Power supply")
		(sheetfile "power-supply.kicad_sch")
		(attr smd exclude_from_bom)
		(fp_line
			(start -2.121 -1.474)
			(end -2.121 -1.287)
			(stroke
				(width 0.15)
				(type solid)
			)
			(layer "F.SilkS")
		)
		(fp_line
			(start -2.121 1.284)
			(end -2.121 1.473)
			(stroke
				(width 0.15)
				(type solid)
			)
			(layer "F.SilkS")
		)
		(fp_line
			(start -2.121 1.473)
			(end 2.12 1.473)
			(stroke
				(width 0.15)
				(type solid)
			)
			(layer "F.SilkS")
		)
		(fp_line
			(start -1.6 -1.4)
			(end -1.6 1.4)
			(stroke
				(width 0.12)
				(type solid)
			)
			(layer "F.SilkS")
		)
		(fp_line
			(start 2.12 -1.474)
			(end -2.121 -1.474)
			(stroke
				(width 0.15)
				(type solid)
			)
			(layer "F.SilkS")
		)
		(fp_line
			(start 2.12 -1.287)
			(end 2.12 -1.474)
			(stroke
				(width 0.15)
				(type solid)
			)
			(layer "F.SilkS")
		)
		(fp_line
			(start 2.12 1.473)
			(end 2.12 1.284)
			(stroke
				(width 0.15)
				(type solid)
			)
			(layer "F.SilkS")
		)
		(fp_rect
			(start -2.8 -1.6)
			(end 2.8 1.6)
			(stroke
				(width 0.05)
				(type solid)
			)
			(fill no)
			(layer "F.CrtYd")
		)
		(fp_line
			(start -2.503 -0.954)
			(end -2.503 0.952)
			(stroke
				(width 0.15)
				(type solid)
			)
			(layer "F.Fab")
		)
		(fp_line
			(start -2.503 0.952)
			(end -1.994 0.952)
			(stroke
				(width 0.15)
				(type solid)
			)
			(layer "F.Fab")
		)
		(fp_line
			(start -1.994 -1.347)
			(end -1.994 1.346)
			(stroke
				(width 0.15)
				(type solid)
			)
			(layer "F.Fab")
		)
		(fp_line
			(start -1.994 -0.954)
			(end -2.503 -0.954)
			(stroke
				(width 0.15)
				(type solid)
			)
			(layer "F.Fab")
		)
		(fp_line
			(start -1.994 -0.675)
			(end -1.321 -1.347)
			(stroke
				(width 0.15)
				(type solid)
			)
			(layer "F.Fab")
		)
		(fp_line
			(start -1.994 0.673)
			(end -1.321 1.346)
			(stroke
				(width 0.15)
				(type solid)
			)
			(layer "F.Fab")
		)
		(fp_line
			(start -1.994 0.952)
			(end -1.994 -0.954)
			(stroke
				(width 0.15)
				(type solid)
			)
			(layer "F.Fab")
		)
		(fp_line
			(start -1.994 1.346)
			(end 1.993 1.346)
			(stroke
				(width 0.15)
				(type solid)
			)
			(layer "F.Fab")
		)
		(fp_line
			(start 1.993 -1.347)
			(end -1.994 -1.347)
			(stroke
				(width 0.15)
				(type solid)
			)
			(layer "F.Fab")
		)
		(fp_line
			(start 1.993 -0.954)
			(end 1.993 0.952)
			(stroke
				(width 0.15)
				(type solid)
			)
			(layer "F.Fab")
		)
		(fp_line
			(start 1.993 0.952)
			(end 2.5 0.952)
			(stroke
				(width 0.15)
				(type solid)
			)
			(layer "F.Fab")
		)
		(fp_line
			(start 1.993 1.346)
			(end 1.993 -1.347)
			(stroke
				(width 0.15)
				(type solid)
			)
			(layer "F.Fab")
		)
		(fp_line
			(start 2.5 -0.954)
			(end 1.993 -0.954)
			(stroke
				(width 0.15)
				(type solid)
			)
			(layer "F.Fab")
		)
		(fp_line
			(start 2.5 0.952)
			(end 2.5 -0.954)
			(stroke
				(width 0.15)
				(type solid)
			)
			(layer "F.Fab")
		)
		(pad "1" smd rect
			(at -2.298 0)
			(size 0.8096 1.905)
			(layers "F.Cu" "F.Mask" "F.Paste")
			(net 702 "VDC")
			(pinfunction "1")
			(pintype "passive")
		)
		(pad "2" smd rect
			(at 2.297 0)
			(size 0.8096 1.905)
			(layers "F.Cu" "F.Mask" "F.Paste")
			(net 956 "/DC-DC Converters/POE_DC")
			(pinfunction "2")
			(pintype "passive")
		)
	)
	(footprint "antmicro-footprints:C_0402_1005Metric"
		(layer "F.Cu")
		(at 203.7625 88.3365 -90)
		(descr "Capacitor SMD 0402")
		(tags "capacitor SMD 0402")
		(property "Reference" "C277"
			(at -0.8865 -0.3875 270)
			(layer "F.SilkS")
			(effects
				(font
					(size 0.7 0.7)
					(thickness 0.15)
				)
				(justify left bottom)
			)
		)
		(property "Value" "C_100n_0402"
			(at 0 1.169 270)
			(layer "F.Fab")
			(effects
				(font
					(size 0.7 0.7)
					(thickness 0.15)
				)
				(justify left bottom)
			)
		)
		(property "Description" "SMD Multilayer Ceramic Capacitor, 0.1 µF, 50 V, 0402 [1005 Metric], ± 10%, X5R, GRM Series"
			(at 0 0 270)
			(layer "F.Fab")
			(hide yes)
			(effects
				(font
					(size 1.27 1.27)
					(thickness 0.15)
				)
			)
		)
		(property "Author" "Antmicro"
			(at 115.426 292.099 0)
			(layer "F.Fab")
			(hide yes)
			(effects
				(font
					(size 1 1)
					(thickness 0.15)
				)
			)
		)
		(property "Dielectric" "X5R"
			(at 115.426 292.099 0)
			(layer "F.Fab")
			(hide yes)
			(effects
				(font
					(size 1 1)
					(thickness 0.15)
				)
			)
		)
		(property "License" "Apache-2.0"
			(at 115.426 292.099 0)
			(layer "F.Fab")
			(hide yes)
			(effects
				(font
					(size 1 1)
					(thickness 0.15)
				)
			)
		)
		(property "MPN" "GRM155R61H104KE14D"
			(at 115.426 292.099 0)
			(layer "F.Fab")
			(hide yes)
			(effects
				(font
					(size 1 1)
					(thickness 0.15)
				)
			)
		)
		(property "Manufacturer" "Murata"
			(at 115.426 292.099 0)
			(layer "F.Fab")
			(hide yes)
			(effects
				(font
					(size 1 1)
					(thickness 0.15)
				)
			)
		)
		(property "Val" "100n"
			(at 115.426 292.099 0)
			(layer "F.Fab")
			(hide yes)
			(effects
				(font
					(size 1 1)
					(thickness 0.15)
				)
			)
		)
		(property "Voltage" "50V"
			(at 115.426 292.099 0)
			(layer "F.Fab")
			(hide yes)
			(effects
				(font
					(size 1 1)
					(thickness 0.15)
				)
			)
		)
		(sheetname "HDMI + Ethernet")
		(sheetfile "hdmi-ethernet.kicad_sch")
		(attr smd)
		(fp_rect
			(start -0.925 -0.47)
			(end 0.925 0.47)
			(stroke
				(width 0.05)
				(type default)
			)
			(fill no)
			(layer "F.CrtYd")
		)
		(fp_line
			(start -0.494 0.248)
			(end -0.494 -0.25)
			(stroke
				(width 0.15)
				(type solid)
			)
			(layer "F.Fab")
		)
		(fp_line
			(start 0.504 0.248)
			(end -0.494 0.248)
			(stroke
				(width 0.15)
				(type solid)
			)
			(layer "F.Fab")
		)
		(fp_line
			(start -0.494 -0.25)
			(end 0.504 -0.25)
			(stroke
				(width 0.15)
				(type solid)
			)
			(layer "F.Fab")
		)
		(fp_line
			(start 0.504 -0.25)
			(end 0.504 0.248)
			(stroke
				(width 0.15)
				(type solid)
			)
			(layer "F.Fab")
		)
		(pad "1" smd roundrect
			(at -0.48 0 270)
			(size 0.59 0.64)
			(layers "F.Cu" "F.Mask" "F.Paste")
			(roundrect_rratio 0.25)
			(net 1 "GND")
			(pintype "passive")
		)
		(pad "2" smd roundrect
			(at 0.48 0 270)
			(size 0.59 0.64)
			(layers "F.Cu" "F.Mask" "F.Paste")
			(roundrect_rratio 0.25)
			(net 727 "+1V2")
			(pintype "passive")
		)
	)
	(footprint "antmicro-footprints:C_0402_1005Metric"
		(layer "F.Cu")
		(at 199.901 107.199 180)
		(descr "Capacitor SMD 0402")
		(tags "capacitor SMD 0402")
		(property "Reference" "C227"
			(at -0.899 -0.401 180)
			(layer "F.SilkS")
			(effects
				(font
					(size 0.7 0.7)
					(thickness 0.15)
				)
				(justify left bottom)
			)
		)
		(property "Value" "C_100n_0402"
			(at 0 1.169 180)
			(layer "F.Fab")
			(effects
				(font
					(size 0.7 0.7)
					(thickness 0.15)
				)
				(justify left bottom)
			)
		)
		(property "Description" "SMD Multilayer Ceramic Capacitor, 0.1 µF, 50 V, 0402 [1005 Metric], ± 10%, X5R, GRM Series"
			(at 0 0 180)
			(layer "F.Fab")
			(hide yes)
			(effects
				(font
					(size 1.27 1.27)
					(thickness 0.15)
				)
			)
		)
		(property "Author" "Antmicro"
			(at 399.802 214.398 0)
			(layer "F.Fab")
			(hide yes)
			(effects
				(font
					(size 1 1)
					(thickness 0.15)
				)
			)
		)
		(property "Dielectric" "X5R"
			(at 399.802 214.398 0)
			(layer "F.Fab")
			(hide yes)
			(effects
				(font
					(size 1 1)
					(thickness 0.15)
				)
			)
		)
		(property "License" "Apache-2.0"
			(at 399.802 214.398 0)
			(layer "F.Fab")
			(hide yes)
			(effects
				(font
					(size 1 1)
					(thickness 0.15)
				)
			)
		)
		(property "MPN" "GRM155R61H104KE14D"
			(at 399.802 214.398 0)
			(layer "F.Fab")
			(hide yes)
			(effects
				(font
					(size 1 1)
					(thickness 0.15)
				)
			)
		)
		(property "Manufacturer" "Murata"
			(at 399.802 214.398 0)
			(layer "F.Fab")
			(hide yes)
			(effects
				(font
					(size 1 1)
					(thickness 0.15)
				)
			)
		)
		(property "Val" "100n"
			(at 399.802 214.398 0)
			(layer "F.Fab")
			(hide yes)
			(effects
				(font
					(size 1 1)
					(thickness 0.15)
				)
			)
		)
		(property "Voltage" "50V"
			(at 399.802 214.398 0)
			(layer "F.Fab")
			(hide yes)
			(effects
				(font
					(size 1 1)
					(thickness 0.15)
				)
			)
		)
		(sheetname "USB PHY")
		(sheetfile "usb-phy.kicad_sch")
		(attr smd)
		(fp_rect
			(start -0.925 -0.47)
			(end 0.925 0.47)
			(stroke
				(width 0.05)
				(type default)
			)
			(fill no)
			(layer "F.CrtYd")
		)
		(fp_line
			(start 0.504 0.248)
			(end -0.494 0.248)
			(stroke
				(width 0.15)
				(type solid)
			)
			(layer "F.Fab")
		)
		(fp_line
			(start 0.504 -0.25)
			(end 0.504 0.248)
			(stroke
				(width 0.15)
				(type solid)
			)
			(layer "F.Fab")
		)
		(fp_line
			(start -0.494 0.248)
			(end -0.494 -0.25)
			(stroke
				(width 0.15)
				(type solid)
			)
			(layer "F.Fab")
		)
		(fp_line
			(start -0.494 -0.25)
			(end 0.504 -0.25)
			(stroke
				(width 0.15)
				(type solid)
			)
			(layer "F.Fab")
		)
		(pad "1" smd roundrect
			(at -0.48 0 180)
			(size 0.59 0.64)
			(layers "F.Cu" "F.Mask" "F.Paste")
			(roundrect_rratio 0.25)
			(net 1 "GND")
			(pintype "passive")
		)
		(pad "2" smd roundrect
			(at 0.48 0 180)
			(size 0.59 0.64)
			(layers "F.Cu" "F.Mask" "F.Paste")
			(roundrect_rratio 0.25)
			(net 709 "/USB PHY/USB_HOST_VBCOMP")
			(pintype "passive")
		)
	)
	(footprint "antmicro-footprints:R_0402_1005Metric"
		(layer "F.Cu")
		(at 225.55 149.7 90)
		(descr "Resistor SMD 0402")
		(tags "resistor SMD 0402")
		(property "Reference" "R241"
			(at -1.4 1.3 90)
			(layer "F.SilkS")
			(effects
				(font
					(size 0.7 0.7)
					(thickness 0.15)
				)
				(justify left bottom)
			)
		)
		(property "Value" "R_1M_0402"
			(at 0 1.4 90)
			(layer "F.Fab")
			(effects
				(font
					(size 0.7 0.7)
					(thickness 0.15)
				)
				(justify left bottom)
			)
		)
		(property "Description" "SMD Chip Resistor, 1 Mohm, ± 1%, 62.5 mW, 0402 [1005 Metric], Thick Film, General Purpose"
			(at 0 0 90)
			(layer "F.Fab")
			(hide yes)
			(effects
				(font
					(size 1.27 1.27)
					(thickness 0.15)
				)
			)
		)
		(property "Author" "Antmicro"
			(at 375.25 -75.85 0)
			(layer "F.Fab")
			(hide yes)
			(effects
				(font
					(size 1 1)
					(thickness 0.15)
				)
			)
		)
		(property "License" "Apache-2.0"
			(at 375.25 -75.85 0)
			(layer "F.Fab")
			(hide yes)
			(effects
				(font
					(size 1 1)
					(thickness 0.15)
				)
			)
		)
		(property "MPN" "CR0402-FX-1004GLF"
			(at 375.25 -75.85 0)
			(layer "F.Fab")
			(hide yes)
			(effects
				(font
					(size 1 1)
					(thickness 0.15)
				)
			)
		)
		(property "Manufacturer" "Bourns"
			(at 375.25 -75.85 0)
			(layer "F.Fab")
			(hide yes)
			(effects
				(font
					(size 1 1)
					(thickness 0.15)
				)
			)
		)
		(property "Tolerance" "1%"
			(at 375.25 -75.85 0)
			(layer "F.Fab")
			(hide yes)
			(effects
				(font
					(size 1 1)
					(thickness 0.15)
				)
			)
		)
		(property "Val" "1M"
			(at 375.25 -75.85 0)
			(layer "F.Fab")
			(hide yes)
			(effects
				(font
					(size 1 1)
					(thickness 0.15)
				)
			)
		)
		(sheetname "HDMI + Ethernet")
		(sheetfile "hdmi-ethernet.kicad_sch")
		(attr smd)
		(fp_rect
			(start -0.925 -0.47)
			(end 0.925 0.47)
			(stroke
				(width 0.05)
				(type default)
			)
			(fill no)
			(layer "F.CrtYd")
		)
		(fp_rect
			(start -0.5 -0.25)
			(end 0.5 0.25)
			(stroke
				(width 0.15)
				(type solid)
			)
			(fill no)
			(layer "F.Fab")
		)
		(pad "1" smd roundrect
			(at -0.48 0 90)
			(size 0.59 0.64)
			(layers "F.Cu" "F.Mask" "F.Paste")
			(roundrect_rratio 0.25)
			(net 719 "/HDMI + Ethernet/ETH_XO")
			(pintype "passive")
		)
		(pad "2" smd roundrect
			(at 0.48 0 90)
			(size 0.59 0.64)
			(layers "F.Cu" "F.Mask" "F.Paste")
			(roundrect_rratio 0.25)
			(net 716 "/HDMI + Ethernet/ETH_XI")
			(pintype "passive")
		)
	)
	(footprint "antmicro-footprints:Torex_USP-6C"
		(layer "F.Cu")
		(at 154.125 141)
		(tags "Integrated Circuit")
		(property "Reference" "U40"
			(at 1.975 -0.05 90)
			(layer "F.SilkS")
			(effects
				(font
					(size 0.7 0.7)
					(thickness 0.254)
				)
			)
		)
		(property "Value" "XC6230H001ER-G"
			(at 0 2.8 0)
			(layer "F.Fab")
			(effects
				(font
					(size 1.27 1.27)
					(thickness 0.254)
				)
			)
		)
		(property "Description" "LDO Voltage Regulator, Adjustable, 1.7 V to 6 V in, 350 mV Drop, 1.188-1.212 V/2 A out, USP-6C-6"
			(at 0 0 0)
			(layer "F.Fab")
			(hide yes)
			(effects
				(font
					(size 1.27 1.27)
					(thickness 0.15)
				)
			)
		)
		(property "Author" "Antmicro"
			(at 0 0 0)
			(layer "F.Fab")
			(hide yes)
			(effects
				(font
					(size 1 1)
					(thickness 0.15)
				)
			)
		)
		(property "License" "Apache-2.0"
			(at 0 0 0)
			(layer "F.Fab")
			(hide yes)
			(effects
				(font
					(size 1 1)
					(thickness 0.15)
				)
			)
		)
		(property "MPN" "XC6230H001ER-G"
			(at 0 0 0)
			(layer "F.Fab")
			(hide yes)
			(effects
				(font
					(size 1 1)
					(thickness 0.15)
				)
			)
		)
		(property "Manufacturer" "Torex Semiconductor"
			(at 0 0 0)
			(layer "F.Fab")
			(hide yes)
			(effects
				(font
					(size 1 1)
					(thickness 0.15)
				)
			)
		)
		(sheetname "DC-DC Converters")
		(sheetfile "dc-dc.kicad_sch")
		(attr smd)
		(fp_circle
			(center -1.801 -0.554)
			(end -1.751 -0.554)
			(stroke
				(width 0.15)
				(type solid)
			)
			(fill yes)
			(layer "F.SilkS")
		)
		(fp_rect
			(start -0.403 -0.701)
			(end 0.4 -0.203)
			(stroke
				(width 0.01)
				(type solid)
			)
			(fill yes)
			(layer "F.Paste")
		)
		(fp_rect
			(start -0.403 0.2)
			(end 0.4 0.698)
			(stroke
				(width 0.01)
				(type solid)
			)
			(fill yes)
			(layer "F.Paste")
		)
		(fp_rect
			(start -1.5 -1.402)
			(end 1.498 1.4)
			(stroke
				(width 0.05)
				(type solid)
			)
			(fill no)
			(layer "F.CrtYd")
		)
		(fp_line
			(start -1 -0.903)
			(end 0.997 -0.903)
			(stroke
				(width 0.15)
				(type solid)
			)
			(layer "F.Fab")
		)
		(fp_line
			(start -1 -0.7)
			(end -0.8 -0.9)
			(stroke
				(width 0.15)
				(type solid)
			)
			(layer "F.Fab")
		)
		(fp_line
			(start -1 0.9)
			(end -1 -0.903)
			(stroke
				(width 0.15)
				(type solid)
			)
			(layer "F.Fab")
		)
		(fp_line
			(start 0.997 -0.903)
			(end 0.997 0.9)
			(stroke
				(width 0.15)
				(type solid)
			)
			(layer "F.Fab")
		)
		(fp_line
			(start 0.997 0.9)
			(end -1 0.9)
			(stroke
				(width 0.15)
				(type solid)
			)
			(layer "F.Fab")
		)
		(pad "1" smd rect
			(at -0.975 -0.553 90)
			(size 0.35 0.45)
			(layers "F.Cu" "F.Mask" "F.Paste")
			(net 748 "/DC-DC Converters/MGTAVTT_OUT")
			(pinfunction "OUT")
			(pintype "power_out")
		)
		(pad "2" smd rect
			(at -0.975 0 90)
			(size 0.25 0.45)
			(layers "F.Cu" "F.Mask" "F.Paste")
			(net 969 "/DC-DC Converters/MGTAVTT_ILIM")
			(pinfunction "ILIM")
			(pintype "output")
		)
		(pad "3" smd rect
			(at -0.975 0.497 90)
			(size 0.25 0.45)
			(layers "F.Cu" "F.Mask" "F.Paste")
			(net 748 "/DC-DC Converters/MGTAVTT_OUT")
			(pinfunction "FB")
			(pintype "open_collector")
		)
		(pad "4" smd rect
			(at 0.972 0.497 90)
			(size 0.25 0.45)
			(layers "F.Cu" "F.Mask" "F.Paste")
			(net 743 "/DC-DC Converters/1V7")
			(pinfunction "EN")
			(pintype "input")
		)
		(pad "5" smd rect
			(at 0.972 0 90)
			(size 0.25 0.45)
			(layers "F.Cu" "F.Mask" "F.Paste")
			(net 1 "GND")
			(pinfunction "GND")
			(pintype "power_in")
		)
		(pad "6" smd rect
			(at 0.972 -0.5 90)
			(size 0.25 0.45)
			(layers "F.Cu" "F.Mask" "F.Paste")
			(net 743 "/DC-DC Converters/1V7")
			(pinfunction "IN")
			(pintype "power_out")
		)
		(pad "7" smd rect
			(at 0 0)
			(size 1 1.6)
			(layers "F.Cu" "F.Mask")
			(net 1 "GND")
			(pinfunction "EP")
			(pintype "passive")
		)
		(pad "7" smd rect
			(at 0 0 90)
			(size 1.8 0.9)
			(layers "F.Cu" "F.Mask")
			(net 1 "GND")
			(pinfunction "EP")
			(pintype "passive")
		)
	)
	(footprint "antmicro-footprints:R_0402_1005Metric"
		(layer "F.Cu")
		(at 159 184 90)
		(descr "Resistor SMD 0402")
		(tags "resistor SMD 0402")
		(property "Reference" "R365"
			(at 0.7 0.4 90)
			(layer "F.SilkS")
			(effects
				(font
					(size 0.7 0.7)
					(thickness 0.15)
				)
				(justify left bottom)
			)
		)
		(property "Value" "R_0R_0402"
			(at 0 1.4 90)
			(layer "F.Fab")
			(effects
				(font
					(size 0.7 0.7)
					(thickness 0.15)
				)
				(justify left bottom)
			)
		)
		(property "Description" "SMD Chip Resistor, Jumper, 0 ohm, 100 mW, 0402 [1005 Metric], Thick Film, General Purpose"
			(at 0 0 90)
			(layer "F.Fab")
			(hide yes)
			(effects
				(font
					(size 1.27 1.27)
					(thickness 0.15)
				)
			)
		)
		(property "Author" "Antmicro"
			(at 343 25 0)
			(layer "F.Fab")
			(hide yes)
			(effects
				(font
					(size 1 1)
					(thickness 0.15)
				)
			)
		)
		(property "Current" "1A"
			(at 343 25 0)
			(layer "F.Fab")
			(hide yes)
			(effects
				(font
					(size 1 1)
					(thickness 0.15)
				)
			)
		)
		(property "DNP" "DNP"
			(at 343 25 0)
			(layer "F.Fab")
			(hide yes)
			(effects
				(font
					(size 1 1)
					(thickness 0.15)
				)
			)
		)
		(property "License" "Apache-2.0"
			(at 343 25 0)
			(layer "F.Fab")
			(hide yes)
			(effects
				(font
					(size 1 1)
					(thickness 0.15)
				)
			)
		)
		(property "MPN" "ERJ2GE0R00X"
			(at 343 25 0)
			(layer "F.Fab")
			(hide yes)
			(effects
				(font
					(size 1 1)
					(thickness 0.15)
				)
			)
		)
		(property "Manufacturer" "Panasonic"
			(at 343 25 0)
			(layer "F.Fab")
			(hide yes)
			(effects
				(font
					(size 1 1)
					(thickness 0.15)
				)
			)
		)
		(property "Tolerance" ""
			(at 343 25 0)
			(layer "F.Fab")
			(hide yes)
			(effects
				(font
					(size 1 1)
					(thickness 0.15)
				)
			)
		)
		(property "Val" "0R"
			(at 343 25 0)
			(layer "F.Fab")
			(hide yes)
			(effects
				(font
					(size 1 1)
					(thickness 0.15)
				)
			)
		)
		(property "dnp" ""
			(at 343 25 0)
			(layer "F.Fab")
			(hide yes)
			(effects
				(font
					(size 1 1)
					(thickness 0.15)
				)
			)
		)
		(property "exclude_from_bom" ""
			(at 343 25 0)
			(layer "F.Fab")
			(hide yes)
			(effects
				(font
					(size 1 1)
					(thickness 0.15)
				)
			)
		)
		(sheetname "FPGA Bank 12 & 13")
		(sheetfile "fpga-bank-12-13.kicad_sch")
		(attr smd exclude_from_bom)
		(fp_rect
			(start -0.925 -0.47)
			(end 0.925 0.47)
			(stroke
				(width 0.05)
				(type default)
			)
			(fill no)
			(layer "F.CrtYd")
		)
		(fp_rect
			(start -0.5 -0.25)
			(end 0.5 0.25)
			(stroke
				(width 0.15)
				(type solid)
			)
			(fill no)
			(layer "F.Fab")
		)
		(pad "1" smd roundrect
			(at -0.48 0 90)
			(size 0.59 0.64)
			(layers "F.Cu" "F.Mask" "F.Paste")
			(roundrect_rratio 0.25)
			(net 571 "/FPGA Bank 12 & 13/~{PB_CTRL_CLR}")
			(pintype "passive")
		)
		(pad "2" smd roundrect
			(at 0.48 0 90)
			(size 0.59 0.64)
			(layers "F.Cu" "F.Mask" "F.Paste")
			(roundrect_rratio 0.25)
			(net 279 "/DC-DC Converters/PB_CTRL.~{PB_CTRL_CLR}")
			(pintype "passive")
		)
	)
	(footprint "antmicro-footprints:C_0402_1005Metric"
		(layer "F.Cu")
		(at 173.570001 126.510001 180)
		(descr "Capacitor SMD 0402")
		(tags "capacitor SMD 0402")
		(property "Reference" "C310"
			(at -3.729999 -0.389999 0)
			(layer "F.SilkS")
			(effects
				(font
					(size 0.7 0.7)
					(thickness 0.15)
				)
				(justify right bottom)
			)
		)
		(property "Value" "C_100n_0402"
			(at 0 1.4 0)
			(layer "F.Fab")
			(effects
				(font
					(size 0.7 0.7)
					(thickness 0.15)
				)
				(justify right bottom)
			)
		)
		(property "Description" "SMD Multilayer Ceramic Capacitor, 0.1 µF, 50 V, 0402 [1005 Metric], ± 10%, X5R, GRM Series"
			(at 0 0 180)
			(layer "F.Fab")
			(hide yes)
			(effects
				(font
					(size 1.27 1.27)
					(thickness 0.15)
				)
			)
		)
		(property "Author" "Antmicro"
			(at 347.140002 253.020002 0)
			(layer "F.Fab")
			(hide yes)
			(effects
				(font
					(size 1 1)
					(thickness 0.15)
				)
			)
		)
		(property "Dielectric" "X5R"
			(at 347.140002 253.020002 0)
			(layer "F.Fab")
			(hide yes)
			(effects
				(font
					(size 1 1)
					(thickness 0.15)
				)
			)
		)
		(property "License" "Apache-2.0"
			(at 347.140002 253.020002 0)
			(layer "F.Fab")
			(hide yes)
			(effects
				(font
					(size 1 1)
					(thickness 0.15)
				)
			)
		)
		(property "MPN" "GRM155R61H104KE14D"
			(at 347.140002 253.020002 0)
			(layer "F.Fab")
			(hide yes)
			(effects
				(font
					(size 1 1)
					(thickness 0.15)
				)
			)
		)
		(property "Manufacturer" "Murata"
			(at 347.140002 253.020002 0)
			(layer "F.Fab")
			(hide yes)
			(effects
				(font
					(size 1 1)
					(thickness 0.15)
				)
			)
		)
		(property "Val" "100n"
			(at 347.140002 253.020002 0)
			(layer "F.Fab")
			(hide yes)
			(effects
				(font
					(size 1 1)
					(thickness 0.15)
				)
			)
		)
		(property "Voltage" "50V"
			(at 347.140002 253.020002 0)
			(layer "F.Fab")
			(hide yes)
			(effects
				(font
					(size 1 1)
					(thickness 0.15)
				)
			)
		)
		(sheetname "FMC+ HSPC")
		(sheetfile "fmc-hspc.kicad_sch")
		(attr smd)
		(fp_rect
			(start -0.925 -0.47)
			(end 0.925 0.47)
			(stroke
				(width 0.05)
				(type default)
			)
			(fill no)
			(layer "F.CrtYd")
		)
		(fp_line
			(start 0.504 0.248)
			(end -0.494 0.248)
			(stroke
				(width 0.15)
				(type solid)
			)
			(layer "F.Fab")
		)
		(fp_line
			(start 0.504 -0.25)
			(end 0.504 0.248)
			(stroke
				(width 0.15)
				(type solid)
			)
			(layer "F.Fab")
		)
		(fp_line
			(start -0.494 0.248)
			(end -0.494 -0.25)
			(stroke
				(width 0.15)
				(type solid)
			)
			(layer "F.Fab")
		)
		(fp_line
			(start -0.494 -0.25)
			(end 0.504 -0.25)
			(stroke
				(width 0.15)
				(type solid)
			)
			(layer "F.Fab")
		)
		(pad "1" smd roundrect
			(at -0.48 0 180)
			(size 0.59 0.64)
			(layers "F.Cu" "F.Mask" "F.Paste")
			(roundrect_rratio 0.25)
			(net 107 "/FMC+ HSPC/GTX115.TX1_P")
			(pintype "passive")
		)
		(pad "2" smd roundrect
			(at 0.48 0 180)
			(size 0.59 0.64)
			(layers "F.Cu" "F.Mask" "F.Paste")
			(roundrect_rratio 0.25)
			(net 105 "/FMC+ HSPC/GTX_TX6_C_P")
			(pintype "passive")
		)
	)
	(footprint "antmicro-footprints:C_0402_1005Metric"
		(layer "F.Cu")
		(at 168.7 151.2)
		(descr "Capacitor SMD 0402")
		(tags "capacitor SMD 0402")
		(property "Reference" "C189"
			(at -1.85 1.3 0)
			(layer "F.SilkS")
			(effects
				(font
					(size 0.7 0.7)
					(thickness 0.15)
				)
				(justify left bottom)
			)
		)
		(property "Value" "C_10u_0402"
			(at 0 1.4 0)
			(layer "F.Fab")
			(effects
				(font
					(size 0.7 0.7)
					(thickness 0.15)
				)
				(justify left bottom)
			)
		)
		(property "Description" "SMD Multilayer Ceramic Capacitor, 10 µF, 6.3 V, 0402 [1005 Metric], ± 20%, X5R, CC Series"
			(at 0 0 0)
			(layer "F.Fab")
			(hide yes)
			(effects
				(font
					(size 1.27 1.27)
					(thickness 0.15)
				)
			)
		)
		(property "Author" "Antmicro"
			(at 0 0 0)
			(layer "F.Fab")
			(hide yes)
			(effects
				(font
					(size 1 1)
					(thickness 0.15)
				)
			)
		)
		(property "Dielectric" ""
			(at 0 0 0)
			(layer "F.Fab")
			(hide yes)
			(effects
				(font
					(size 1 1)
					(thickness 0.15)
				)
			)
		)
		(property "License" "Apache-2.0"
			(at 0 0 0)
			(layer "F.Fab")
			(hide yes)
			(effects
				(font
					(size 1 1)
					(thickness 0.15)
				)
			)
		)
		(property "MPN" "CC0402MRX5R5BB106"
			(at 0 0 0)
			(layer "F.Fab")
			(hide yes)
			(effects
				(font
					(size 1 1)
					(thickness 0.15)
				)
			)
		)
		(property "Manufacturer" "YAGEO"
			(at 0 0 0)
			(layer "F.Fab")
			(hide yes)
			(effects
				(font
					(size 1 1)
					(thickness 0.15)
				)
			)
		)
		(property "Val" "10u"
			(at 0 0 0)
			(layer "F.Fab")
			(hide yes)
			(effects
				(font
					(size 1 1)
					(thickness 0.15)
				)
			)
		)
		(property "Voltage" ""
			(at 0 0 0)
			(layer "F.Fab")
			(hide yes)
			(effects
				(font
					(size 1 1)
					(thickness 0.15)
				)
			)
		)
		(sheetname "DRAM + SRAM")
		(sheetfile "ram.kicad_sch")
		(attr smd)
		(fp_rect
			(start -0.925 -0.47)
			(end 0.925 0.47)
			(stroke
				(width 0.05)
				(type default)
			)
			(fill no)
			(layer "F.CrtYd")
		)
		(fp_line
			(start -0.494 -0.25)
			(end 0.504 -0.25)
			(stroke
				(width 0.15)
				(type solid)
			)
			(layer "F.Fab")
		)
		(fp_line
			(start -0.494 0.248)
			(end -0.494 -0.25)
			(stroke
				(width 0.15)
				(type solid)
			)
			(layer "F.Fab")
		)
		(fp_line
			(start 0.504 -0.25)
			(end 0.504 0.248)
			(stroke
				(width 0.15)
				(type solid)
			)
			(layer "F.Fab")
		)
		(fp_line
			(start 0.504 0.248)
			(end -0.494 0.248)
			(stroke
				(width 0.15)
				(type solid)
			)
			(layer "F.Fab")
		)
		(pad "1" smd roundrect
			(at -0.48 0)
			(size 0.59 0.64)
			(layers "F.Cu" "F.Mask" "F.Paste")
			(roundrect_rratio 0.25)
			(net 1 "GND")
			(pintype "passive")
		)
		(pad "2" smd roundrect
			(at 0.48 0)
			(size 0.59 0.64)
			(layers "F.Cu" "F.Mask" "F.Paste")
			(roundrect_rratio 0.25)
			(net 25 "+1V35")
			(pintype "passive")
		)
	)
	(footprint "antmicro-footprints:R_0402_1005Metric"
		(layer "F.Cu")
		(at 225.1 115.2)
		(descr "Resistor SMD 0402")
		(tags "resistor SMD 0402")
		(property "Reference" "R103"
			(at -3.65 0.4 0)
			(layer "F.SilkS")
			(effects
				(font
					(size 0.7 0.7)
					(thickness 0.15)
				)
				(justify left bottom)
			)
		)
		(property "Value" "R_0R_0402"
			(at 0 1.4 0)
			(layer "F.Fab")
			(effects
				(font
					(size 0.7 0.7)
					(thickness 0.15)
				)
				(justify left bottom)
			)
		)
		(property "Description" "SMD Chip Resistor, Jumper, 0 ohm, 100 mW, 0402 [1005 Metric], Thick Film, General Purpose"
			(at 0 0 0)
			(layer "F.Fab")
			(hide yes)
			(effects
				(font
					(size 1.27 1.27)
					(thickness 0.15)
				)
			)
		)
		(property "Author" "Antmicro"
			(at 0 0 0)
			(layer "F.Fab")
			(hide yes)
			(effects
				(font
					(size 1 1)
					(thickness 0.15)
				)
			)
		)
		(property "Current" "1A"
			(at 0 0 0)
			(layer "F.Fab")
			(hide yes)
			(effects
				(font
					(size 1 1)
					(thickness 0.15)
				)
			)
		)
		(property "License" "Apache-2.0"
			(at 0 0 0)
			(layer "F.Fab")
			(hide yes)
			(effects
				(font
					(size 1 1)
					(thickness 0.15)
				)
			)
		)
		(property "MPN" "ERJ2GE0R00X"
			(at 0 0 0)
			(layer "F.Fab")
			(hide yes)
			(effects
				(font
					(size 1 1)
					(thickness 0.15)
				)
			)
		)
		(property "Manufacturer" "Panasonic"
			(at 0 0 0)
			(layer "F.Fab")
			(hide yes)
			(effects
				(font
					(size 1 1)
					(thickness 0.15)
				)
			)
		)
		(property "Tolerance" ""
			(at 0 0 0)
			(layer "F.Fab")
			(hide yes)
			(effects
				(font
					(size 1 1)
					(thickness 0.15)
				)
			)
		)
		(property "Val" "0R"
			(at 0 0 0)
			(layer "F.Fab")
			(hide yes)
			(effects
				(font
					(size 1 1)
					(thickness 0.15)
				)
			)
		)
		(sheetname "SPI Flash + SD Card")
		(sheetfile "spi-flash.kicad_sch")
		(attr smd)
		(fp_rect
			(start -0.925 -0.47)
			(end 0.925 0.47)
			(stroke
				(width 0.05)
				(type default)
			)
			(fill no)
			(layer "F.CrtYd")
		)
		(fp_rect
			(start -0.5 -0.25)
			(end 0.5 0.25)
			(stroke
				(width 0.15)
				(type solid)
			)
			(fill no)
			(layer "F.Fab")
		)
		(pad "1" smd roundrect
			(at -0.48 0)
			(size 0.59 0.64)
			(layers "F.Cu" "F.Mask" "F.Paste")
			(roundrect_rratio 0.25)
			(net 419 "/FPGA Bank 16 & 17/USR_FLASH_1.DQ2")
			(pintype "passive")
		)
		(pad "2" smd roundrect
			(at 0.48 0)
			(size 0.59 0.64)
			(layers "F.Cu" "F.Mask" "F.Paste")
			(roundrect_rratio 0.25)
			(net 910 "/SPI Flash + SD Card/USR_FLASH_1_DQ2")
			(pintype "passive")
		)
	)
	(footprint "antmicro-footprints:C_0402_1005Metric"
		(layer "F.Cu")
		(at 207.403752 97.5615 180)
		(descr "Capacitor SMD 0402")
		(tags "capacitor SMD 0402")
		(property "Reference" "C255"
			(at -1.096248 7.1615 0)
			(layer "F.SilkS")
			(effects
				(font
					(size 0.7 0.7)
					(thickness 0.15)
				)
				(justify right bottom)
			)
		)
		(property "Value" "C_10u_0402"
			(at 0 1.4 0)
			(layer "F.Fab")
			(effects
				(font
					(size 0.7 0.7)
					(thickness 0.15)
				)
				(justify right bottom)
			)
		)
		(property "Description" "SMD Multilayer Ceramic Capacitor, 10 µF, 6.3 V, 0402 [1005 Metric], ± 20%, X5R, CC Series"
			(at 0 0 180)
			(layer "F.Fab")
			(hide yes)
			(effects
				(font
					(size 1.27 1.27)
					(thickness 0.15)
				)
			)
		)
		(property "Author" "Antmicro"
			(at 414.807504 195.123 0)
			(layer "F.Fab")
			(hide yes)
			(effects
				(font
					(size 1 1)
					(thickness 0.15)
				)
			)
		)
		(property "Dielectric" ""
			(at 414.807504 195.123 0)
			(layer "F.Fab")
			(hide yes)
			(effects
				(font
					(size 1 1)
					(thickness 0.15)
				)
			)
		)
		(property "License" "Apache-2.0"
			(at 414.807504 195.123 0)
			(layer "F.Fab")
			(hide yes)
			(effects
				(font
					(size 1 1)
					(thickness 0.15)
				)
			)
		)
		(property "MPN" "CC0402MRX5R5BB106"
			(at 414.807504 195.123 0)
			(layer "F.Fab")
			(hide yes)
			(effects
				(font
					(size 1 1)
					(thickness 0.15)
				)
			)
		)
		(property "Manufacturer" "YAGEO"
			(at 414.807504 195.123 0)
			(layer "F.Fab")
			(hide yes)
			(effects
				(font
					(size 1 1)
					(thickness 0.15)
				)
			)
		)
		(property "Val" "10u"
			(at 414.807504 195.123 0)
			(layer "F.Fab")
			(hide yes)
			(effects
				(font
					(size 1 1)
					(thickness 0.15)
				)
			)
		)
		(property "Voltage" ""
			(at 414.807504 195.123 0)
			(layer "F.Fab")
			(hide yes)
			(effects
				(font
					(size 1 1)
					(thickness 0.15)
				)
			)
		)
		(sheetname "HDMI + Ethernet")
		(sheetfile "hdmi-ethernet.kicad_sch")
		(attr smd)
		(fp_rect
			(start -0.925 -0.47)
			(end 0.925 0.47)
			(stroke
				(width 0.05)
				(type default)
			)
			(fill no)
			(layer "F.CrtYd")
		)
		(fp_line
			(start 0.504 0.248)
			(end -0.494 0.248)
			(stroke
				(width 0.15)
				(type solid)
			)
			(layer "F.Fab")
		)
		(fp_line
			(start 0.504 -0.25)
			(end 0.504 0.248)
			(stroke
				(width 0.15)
				(type solid)
			)
			(layer "F.Fab")
		)
		(fp_line
			(start -0.494 0.248)
			(end -0.494 -0.25)
			(stroke
				(width 0.15)
				(type solid)
			)
			(layer "F.Fab")
		)
		(fp_line
			(start -0.494 -0.25)
			(end 0.504 -0.25)
			(stroke
				(width 0.15)
				(type solid)
			)
			(layer "F.Fab")
		)
		(pad "1" smd roundrect
			(at -0.48 0 180)
			(size 0.59 0.64)
			(layers "F.Cu" "F.Mask" "F.Paste")
			(roundrect_rratio 0.25)
			(net 1 "GND")
			(pintype "passive")
		)
		(pad "2" smd roundrect
			(at 0.48 0 180)
			(size 0.59 0.64)
			(layers "F.Cu" "F.Mask" "F.Paste")
			(roundrect_rratio 0.25)
			(net 717 "/HDMI + Ethernet/GBE_AVDDH")
			(pintype "passive")
		)
	)
	(footprint "antmicro-footprints:R_0603_1608Metric"
		(layer "F.Cu")
		(at 161.5 161.5 90)
		(descr "Resistor SMD 0603")
		(tags "resistor SMD 0603")
		(property "Reference" "R286"
			(at -1.48 1.42 90)
			(layer "F.SilkS")
			(effects
				(font
					(size 0.7 0.7)
					(thickness 0.15)
				)
				(justify left bottom)
			)
		)
		(property "Value" "R_0R_22.4A_0603"
			(at 0 1.6 90)
			(layer "F.Fab")
			(effects
				(font
					(size 0.7 0.7)
					(thickness 0.15)
				)
				(justify left bottom)
			)
		)
		(property "Description" "SMD Chip Resistor"
			(at 0 0 90)
			(layer "F.Fab")
			(hide yes)
			(effects
				(font
					(size 1.27 1.27)
					(thickness 0.15)
				)
			)
		)
		(property "Author" "Antmicro"
			(at 323 0 0)
			(layer "F.Fab")
			(hide yes)
			(effects
				(font
					(size 1 1)
					(thickness 0.15)
				)
			)
		)
		(property "License" "Apache-2.0"
			(at 323 0 0)
			(layer "F.Fab")
			(hide yes)
			(effects
				(font
					(size 1 1)
					(thickness 0.15)
				)
			)
		)
		(property "MPN" "PMR03EZPJ000"
			(at 323 0 0)
			(layer "F.Fab")
			(hide yes)
			(effects
				(font
					(size 1 1)
					(thickness 0.15)
				)
			)
		)
		(property "Manufacturer" "ROHM Semiconductor"
			(at 323 0 0)
			(layer "F.Fab")
			(hide yes)
			(effects
				(font
					(size 1 1)
					(thickness 0.15)
				)
			)
		)
		(property "Max. Curr." "22.4A"
			(at 323 0 0)
			(layer "F.Fab")
			(hide yes)
			(effects
				(font
					(size 1 1)
					(thickness 0.15)
				)
			)
		)
		(property "Tolerance" "template_tolerance"
			(at 323 0 0)
			(layer "F.Fab")
			(hide yes)
			(effects
				(font
					(size 1 1)
					(thickness 0.15)
				)
			)
		)
		(property "Val" "0R"
			(at 323 0 0)
			(layer "F.Fab")
			(hide yes)
			(effects
				(font
					(size 1 1)
					(thickness 0.15)
				)
			)
		)
		(sheetname "DC-DC Converters")
		(sheetfile "dc-dc.kicad_sch")
		(attr smd)
		(fp_line
			(start -0.15 -0.4)
			(end 0.15 -0.4)
			(stroke
				(width 0.15)
				(type solid)
			)
			(layer "F.SilkS")
		)
		(fp_line
			(start -0.15 0.4)
			(end 0.15 0.4)
			(stroke
				(width 0.15)
				(type solid)
			)
			(layer "F.SilkS")
		)
		(fp_rect
			(start -1.25 -0.65)
			(end 1.25 0.65)
			(stroke
				(width 0.05)
				(type solid)
			)
			(fill no)
			(layer "F.CrtYd")
		)
		(fp_rect
			(start -0.8 -0.4)
			(end 0.8 0.4)
			(stroke
				(width 0.15)
				(type solid)
			)
			(fill no)
			(layer "F.Fab")
		)
		(pad "1" smd roundrect
			(at -0.7 0 90)
			(size 0.8 1)
			(layers "F.Cu" "F.Mask" "F.Paste")
			(roundrect_rratio 0.2)
			(net 734 "/DC-DC Converters/1V8_local")
			(pintype "passive")
		)
		(pad "2" smd roundrect
			(at 0.7 0 90)
			(size 0.8 1)
			(layers "F.Cu" "F.Mask" "F.Paste")
			(roundrect_rratio 0.2)
			(net 26 "+1V8")
			(pintype "passive")
		)
	)
	(footprint "antmicro-footprints:C_0402_1005Metric"
		(layer "F.Cu")
		(at 247.099 118.904 180)
		(descr "Capacitor SMD 0402")
		(tags "capacitor SMD 0402")
		(property "Reference" "C396"
			(at 0.999 -1.196 180)
			(layer "F.SilkS")
			(effects
				(font
					(size 0.7 0.7)
					(thickness 0.15)
				)
				(justify left bottom)
			)
		)
		(property "Value" "C_100n_0402"
			(at 0 1.169 180)
			(layer "F.Fab")
			(effects
				(font
					(size 0.7 0.7)
					(thickness 0.15)
				)
				(justify left bottom)
			)
		)
		(property "Description" "SMD Multilayer Ceramic Capacitor, 0.1 µF, 50 V, 0402 [1005 Metric], ± 10%, X5R, GRM Series"
			(at 0 0 180)
			(layer "F.Fab")
			(hide yes)
			(effects
				(font
					(size 1.27 1.27)
					(thickness 0.15)
				)
			)
		)
		(property "Author" "Antmicro"
			(at 494.198 237.808 0)
			(layer "F.Fab")
			(hide yes)
			(effects
				(font
					(size 1 1)
					(thickness 0.15)
				)
			)
		)
		(property "Dielectric" "X5R"
			(at 494.198 237.808 0)
			(layer "F.Fab")
			(hide yes)
			(effects
				(font
					(size 1 1)
					(thickness 0.15)
				)
			)
		)
		(property "License" "Apache-2.0"
			(at 494.198 237.808 0)
			(layer "F.Fab")
			(hide yes)
			(effects
				(font
					(size 1 1)
					(thickness 0.15)
				)
			)
		)
		(property "MPN" "GRM155R61H104KE14D"
			(at 494.198 237.808 0)
			(layer "F.Fab")
			(hide yes)
			(effects
				(font
					(size 1 1)
					(thickness 0.15)
				)
			)
		)
		(property "Manufacturer" "Murata"
			(at 494.198 237.808 0)
			(layer "F.Fab")
			(hide yes)
			(effects
				(font
					(size 1 1)
					(thickness 0.15)
				)
			)
		)
		(property "Val" "100n"
			(at 494.198 237.808 0)
			(layer "F.Fab")
			(hide yes)
			(effects
				(font
					(size 1 1)
					(thickness 0.15)
				)
			)
		)
		(property "Voltage" "50V"
			(at 494.198 237.808 0)
			(layer "F.Fab")
			(hide yes)
			(effects
				(font
					(size 1 1)
					(thickness 0.15)
				)
			)
		)
		(sheetname "USB PHY")
		(sheetfile "usb-phy.kicad_sch")
		(attr smd)
		(fp_rect
			(start -0.925 -0.47)
			(end 0.925 0.47)
			(stroke
				(width 0.05)
				(type default)
			)
			(fill no)
			(layer "F.CrtYd")
		)
		(fp_line
			(start 0.504 0.248)
			(end -0.494 0.248)
			(stroke
				(width 0.15)
				(type solid)
			)
			(layer "F.Fab")
		)
		(fp_line
			(start 0.504 -0.25)
			(end 0.504 0.248)
			(stroke
				(width 0.15)
				(type solid)
			)
			(layer "F.Fab")
		)
		(fp_line
			(start -0.494 0.248)
			(end -0.494 -0.25)
			(stroke
				(width 0.15)
				(type solid)
			)
			(layer "F.Fab")
		)
		(fp_line
			(start -0.494 -0.25)
			(end 0.504 -0.25)
			(stroke
				(width 0.15)
				(type solid)
			)
			(layer "F.Fab")
		)
		(pad "1" smd roundrect
			(at -0.48 0 180)
			(size 0.59 0.64)
			(layers "F.Cu" "F.Mask" "F.Paste")
			(roundrect_rratio 0.25)
			(net 1 "GND")
			(pintype "passive")
		)
		(pad "2" smd roundrect
			(at 0.48 0 180)
			(size 0.59 0.64)
			(layers "F.Cu" "F.Mask" "F.Paste")
			(roundrect_rratio 0.25)
			(net 715 "/USB PHY/USB_USR_VBUS")
			(pintype "passive")
		)
	)
	(footprint "antmicro-footprints:WDFN-8-1EP_6x5mm_P1.27mm_EP3.4x4mm"
		(layer "F.Cu")
		(at 230.425 119.925)
		(property "Reference" "U12"
			(at -3.7 -3.2 0)
			(layer "F.SilkS")
			(effects
				(font
					(size 0.7 0.7)
					(thickness 0.15)
				)
				(justify left bottom)
			)
		)
		(property "Value" "MT25QL256ABA1EW7-0SIT"
			(at -10.1 4 0)
			(layer "F.Fab")
			(effects
				(font
					(size 0.7 0.7)
					(thickness 0.15)
				)
				(justify left bottom)
			)
		)
		(property "Description" "Flash Memory, Serial NOR, 256 Mbit, 32M x 8bit, SPI, MLP, 8 Pins"
			(at 0 0 0)
			(layer "F.Fab")
			(hide yes)
			(effects
				(font
					(size 1.27 1.27)
					(thickness 0.15)
				)
			)
		)
		(property "Author" "Antmicro"
			(at 0 0 0)
			(layer "F.Fab")
			(hide yes)
			(effects
				(font
					(size 1 1)
					(thickness 0.15)
				)
			)
		)
		(property "License" "Apache-2.0"
			(at 0 0 0)
			(layer "F.Fab")
			(hide yes)
			(effects
				(font
					(size 1 1)
					(thickness 0.15)
				)
			)
		)
		(property "MPN" "MT25QL256ABA1EW7-0SIT"
			(at 0 0 0)
			(layer "F.Fab")
			(hide yes)
			(effects
				(font
					(size 1 1)
					(thickness 0.15)
				)
			)
		)
		(property "Manufacturer" "Micron Technology"
			(at 0 0 0)
			(layer "F.Fab")
			(hide yes)
			(effects
				(font
					(size 1 1)
					(thickness 0.15)
				)
			)
		)
		(sheetname "SPI Flash + SD Card")
		(sheetfile "spi-flash.kicad_sch")
		(attr smd)
		(fp_line
			(start -3.801 2.6)
			(end 3.7 2.6)
			(stroke
				(width 0.15)
				(type solid)
			)
			(layer "F.SilkS")
		)
		(fp_line
			(start -2.301 -2.601)
			(end 3.7 -2.601)
			(stroke
				(width 0.15)
				(type solid)
			)
			(layer "F.SilkS")
		)
		(fp_circle
			(center -3.3 -2.8)
			(end -3.25 -2.8)
			(stroke
				(width 0.15)
				(type solid)
			)
			(fill yes)
			(layer "F.SilkS")
		)
		(fp_rect
			(start -3.5 -3)
			(end 3.499 2.999)
			(stroke
				(width 0.05)
				(type solid)
			)
			(fill no)
			(layer "F.CrtYd")
		)
		(fp_line
			(start -3 -1.5)
			(end -3 2.499)
			(stroke
				(width 0.15)
				(type solid)
			)
			(layer "F.Fab")
		)
		(fp_line
			(start -3 2.499)
			(end 2.999 2.499)
			(stroke
				(width 0.15)
				(type solid)
			)
			(layer "F.Fab")
		)
		(fp_line
			(start -2 -2.5)
			(end -3 -1.5)
			(stroke
				(width 0.15)
				(type solid)
			)
			(layer "F.Fab")
		)
		(fp_line
			(start 2.999 -2.5)
			(end -2 -2.5)
			(stroke
				(width 0.15)
				(type solid)
			)
			(layer "F.Fab")
		)
		(fp_line
			(start 2.999 2.499)
			(end 2.999 -2.5)
			(stroke
				(width 0.15)
				(type solid)
			)
			(layer "F.Fab")
		)
		(pad "" smd roundrect
			(at -0.802 -1)
			(size 1.37 1.61)
			(layers "F.Paste")
			(roundrect_rratio 0.182482)
		)
		(pad "" smd roundrect
			(at -0.802 0.998)
			(size 1.37 1.61)
			(layers "F.Paste")
			(roundrect_rratio 0.182482)
		)
		(pad "" smd roundrect
			(at 0.8 -1)
			(size 1.37 1.61)
			(layers "F.Paste")
			(roundrect_rratio 0.182482)
		)
		(pad "" smd roundrect
			(at 0.8 0.998)
			(size 1.37 1.61)
			(layers "F.Paste")
			(roundrect_rratio 0.182482)
		)
		(pad "1" smd rect
			(at -3 -1.905 90)
			(size 0.5 1.5)
			(layers "F.Cu" "F.Mask" "F.Paste")
			(net 894 "/SPI Flash + SD Card/SYSTEM_FLASH_~{CS}")
			(pinfunction "~{CS}")
			(pintype "passive")
		)
		(pad "2" smd roundrect
			(at -3 -0.635 90)
			(size 0.5 1.5)
			(layers "F.Cu" "F.Mask" "F.Paste")
			(roundrect_rratio 0.25)
			(net 897 "/SPI Flash + SD Card/SYSTEM_FLASH_DQ1")
			(pinfunction "DQ1")
			(pintype "passive")
		)
		(pad "3" smd roundrect
			(at -3 0.633 90)
			(size 0.5 1.5)
			(layers "F.Cu" "F.Mask" "F.Paste")
			(roundrect_rratio 0.25)
			(net 898 "/SPI Flash + SD Card/SYSTEM_FLASH_DQ2")
			(pinfunction "DQ2/~{W}")
			(pintype "passive")
		)
		(pad "4" smd roundrect
			(at -3 1.904 90)
			(size 0.5 1.5)
			(layers "F.Cu" "F.Mask" "F.Paste")
			(roundrect_rratio 0.25)
			(net 1 "GND")
			(pinfunction "GND")
			(pintype "passive")
		)
		(pad "5" smd roundrect
			(at 2.999 1.904 90)
			(size 0.5 1.5)
			(layers "F.Cu" "F.Mask" "F.Paste")
			(roundrect_rratio 0.25)
			(net 896 "/SPI Flash + SD Card/SYSTEM_FLASH_DQ0")
			(pinfunction "DQ0")
			(pintype "passive")
		)
		(pad "6" smd roundrect
			(at 2.999 0.633 90)
			(size 0.5 1.5)
			(layers "F.Cu" "F.Mask" "F.Paste")
			(roundrect_rratio 0.25)
			(net 895 "/SPI Flash + SD Card/SYSTEM_FLASH_CLK")
			(pinfunction "CLK")
			(pintype "passive")
		)
		(pad "7" smd roundrect
			(at 2.999 -0.635 90)
			(size 0.5 1.5)
			(layers "F.Cu" "F.Mask" "F.Paste")
			(roundrect_rratio 0.25)
			(net 899 "/SPI Flash + SD Card/SYSTEM_FLASH_DQ3")
			(pinfunction "DQ3/~{HOLD}")
			(pintype "passive")
		)
		(pad "8" smd roundrect
			(at 2.999 -1.905 90)
			(size 0.5 1.5)
			(layers "F.Cu" "F.Mask" "F.Paste")
			(roundrect_rratio 0.25)
			(net 24 "+3V3")
			(pinfunction "VCC")
			(pintype "passive")
		)
		(pad "9" smd rect
			(at 0 0)
			(size 3.4 4)
			(layers "F.Cu" "F.Mask")
			(net 1 "GND")
			(pinfunction "EP")
			(pintype "passive")
			(solder_paste_margin -0.1)
		)
	)
	(footprint "antmicro-footprints:R_0603_1608Metric"
		(layer "F.Cu")
		(at 169.1 172.8 90)
		(descr "Resistor SMD 0603")
		(tags "resistor SMD 0603")
		(property "Reference" "R292"
			(at 3.7 -2.35 90)
			(layer "F.SilkS")
			(effects
				(font
					(size 0.7 0.7)
					(thickness 0.15)
				)
				(justify left bottom)
			)
		)
		(property "Value" "R_0R_22.4A_0603"
			(at 0 1.6 90)
			(layer "F.Fab")
			(effects
				(font
					(size 0.7 0.7)
					(thickness 0.15)
				)
				(justify left bottom)
			)
		)
		(property "Description" "SMD Chip Resistor"
			(at 0 0 90)
			(layer "F.Fab")
			(hide yes)
			(effects
				(font
					(size 1.27 1.27)
					(thickness 0.15)
				)
			)
		)
		(property "Author" "Antmicro"
			(at 341.9 3.7 0)
			(layer "F.Fab")
			(hide yes)
			(effects
				(font
					(size 1 1)
					(thickness 0.15)
				)
			)
		)
		(property "License" "Apache-2.0"
			(at 341.9 3.7 0)
			(layer "F.Fab")
			(hide yes)
			(effects
				(font
					(size 1 1)
					(thickness 0.15)
				)
			)
		)
		(property "MPN" "PMR03EZPJ000"
			(at 341.9 3.7 0)
			(layer "F.Fab")
			(hide yes)
			(effects
				(font
					(size 1 1)
					(thickness 0.15)
				)
			)
		)
		(property "Manufacturer" "ROHM Semiconductor"
			(at 341.9 3.7 0)
			(layer "F.Fab")
			(hide yes)
			(effects
				(font
					(size 1 1)
					(thickness 0.15)
				)
			)
		)
		(property "Max. Curr." "22.4A"
			(at 341.9 3.7 0)
			(layer "F.Fab")
			(hide yes)
			(effects
				(font
					(size 1 1)
					(thickness 0.15)
				)
			)
		)
		(property "Tolerance" "template_tolerance"
			(at 341.9 3.7 0)
			(layer "F.Fab")
			(hide yes)
			(effects
				(font
					(size 1 1)
					(thickness 0.15)
				)
			)
		)
		(property "Val" "0R"
			(at 341.9 3.7 0)
			(layer "F.Fab")
			(hide yes)
			(effects
				(font
					(size 1 1)
					(thickness 0.15)
				)
			)
		)
		(sheetname "DC-DC Converters")
		(sheetfile "dc-dc.kicad_sch")
		(attr smd)
		(fp_line
			(start -0.15 -0.4)
			(end 0.15 -0.4)
			(stroke
				(width 0.15)
				(type solid)
			)
			(layer "F.SilkS")
		)
		(fp_line
			(start -0.15 0.4)
			(end 0.15 0.4)
			(stroke
				(width 0.15)
				(type solid)
			)
			(layer "F.SilkS")
		)
		(fp_rect
			(start -1.25 -0.65)
			(end 1.25 0.65)
			(stroke
				(width 0.05)
				(type solid)
			)
			(fill no)
			(layer "F.CrtYd")
		)
		(fp_rect
			(start -0.8 -0.4)
			(end 0.8 0.4)
			(stroke
				(width 0.15)
				(type solid)
			)
			(fill no)
			(layer "F.Fab")
		)
		(pad "1" smd roundrect
			(at -0.7 0 90)
			(size 0.8 1)
			(layers "F.Cu" "F.Mask" "F.Paste")
			(roundrect_rratio 0.2)
			(net 740 "/DC-DC Converters/1V35_local")
			(pintype "passive")
		)
		(pad "2" smd roundrect
			(at 0.7 0 90)
			(size 0.8 1)
			(layers "F.Cu" "F.Mask" "F.Paste")
			(roundrect_rratio 0.2)
			(net 25 "+1V35")
			(pintype "passive")
		)
	)
	(footprint "antmicro-footprints:C_0402_1005Metric"
		(layer "F.Cu")
		(at 202.6625 88.3365 -90)
		(descr "Capacitor SMD 0402")
		(tags "capacitor SMD 0402")
		(property "Reference" "C261"
			(at -0.8865 -0.3875 270)
			(layer "F.SilkS")
			(effects
				(font
					(size 0.7 0.7)
					(thickness 0.15)
				)
				(justify left bottom)
			)
		)
		(property "Value" "C_100n_0402"
			(at 0 1.169 270)
			(layer "F.Fab")
			(effects
				(font
					(size 0.7 0.7)
					(thickness 0.15)
				)
				(justify left bottom)
			)
		)
		(property "Description" "SMD Multilayer Ceramic Capacitor, 0.1 µF, 50 V, 0402 [1005 Metric], ± 10%, X5R, GRM Series"
			(at 0 0 270)
			(layer "F.Fab")
			(hide yes)
			(effects
				(font
					(size 1.27 1.27)
					(thickness 0.15)
				)
			)
		)
		(property "Author" "Antmicro"
			(at 114.326 290.999 0)
			(layer "F.Fab")
			(hide yes)
			(effects
				(font
					(size 1 1)
					(thickness 0.15)
				)
			)
		)
		(property "Dielectric" "X5R"
			(at 114.326 290.999 0)
			(layer "F.Fab")
			(hide yes)
			(effects
				(font
					(size 1 1)
					(thickness 0.15)
				)
			)
		)
		(property "License" "Apache-2.0"
			(at 114.326 290.999 0)
			(layer "F.Fab")
			(hide yes)
			(effects
				(font
					(size 1 1)
					(thickness 0.15)
				)
			)
		)
		(property "MPN" "GRM155R61H104KE14D"
			(at 114.326 290.999 0)
			(layer "F.Fab")
			(hide yes)
			(effects
				(font
					(size 1 1)
					(thickness 0.15)
				)
			)
		)
		(property "Manufacturer" "Murata"
			(at 114.326 290.999 0)
			(layer "F.Fab")
			(hide yes)
			(effects
				(font
					(size 1 1)
					(thickness 0.15)
				)
			)
		)
		(property "Val" "100n"
			(at 114.326 290.999 0)
			(layer "F.Fab")
			(hide yes)
			(effects
				(font
					(size 1 1)
					(thickness 0.15)
				)
			)
		)
		(property "Voltage" "50V"
			(at 114.326 290.999 0)
			(layer "F.Fab")
			(hide yes)
			(effects
				(font
					(size 1 1)
					(thickness 0.15)
				)
			)
		)
		(sheetname "HDMI + Ethernet")
		(sheetfile "hdmi-ethernet.kicad_sch")
		(attr smd)
		(fp_rect
			(start -0.925 -0.47)
			(end 0.925 0.47)
			(stroke
				(width 0.05)
				(type default)
			)
			(fill no)
			(layer "F.CrtYd")
		)
		(fp_line
			(start -0.494 0.248)
			(end -0.494 -0.25)
			(stroke
				(width 0.15)
				(type solid)
			)
			(layer "F.Fab")
		)
		(fp_line
			(start 0.504 0.248)
			(end -0.494 0.248)
			(stroke
				(width 0.15)
				(type solid)
			)
			(layer "F.Fab")
		)
		(fp_line
			(start -0.494 -0.25)
			(end 0.504 -0.25)
			(stroke
				(width 0.15)
				(type solid)
			)
			(layer "F.Fab")
		)
		(fp_line
			(start 0.504 -0.25)
			(end 0.504 0.248)
			(stroke
				(width 0.15)
				(type solid)
			)
			(layer "F.Fab")
		)
		(pad "1" smd roundrect
			(at -0.48 0 270)
			(size 0.59 0.64)
			(layers "F.Cu" "F.Mask" "F.Paste")
			(roundrect_rratio 0.25)
			(net 1 "GND")
			(pintype "passive")
		)
		(pad "2" smd roundrect
			(at 0.48 0 270)
			(size 0.59 0.64)
			(layers "F.Cu" "F.Mask" "F.Paste")
			(roundrect_rratio 0.25)
			(net 24 "+3V3")
			(pintype "passive")
		)
	)
	(footprint "antmicro-footprints:Heatsink_960-31-18-S-AB-0"
		(layer "F.Cu")
		(at 200.000001 130.000001 90)
		(property "Reference" "HS1"
			(at -16.649999 13.449999 180)
			(unlocked yes)
			(layer "F.SilkS")
			(effects
				(font
					(size 0.7 0.7)
					(thickness 0.15)
				)
				(justify left bottom)
			)
		)
		(property "Value" "Heatsink_960-31-18-S-AB-0"
			(at -7.7 0.94 90)
			(unlocked yes)
			(layer "F.Fab")
			(effects
				(font
					(size 0.7 0.7)
					(thickness 0.15)
				)
				(justify left bottom)
			)
		)
		(property "Description" "Heat Sink BGA Aluminum Top Mount"
			(at 0 0 90)
			(layer "F.Fab")
			(hide yes)
			(effects
				(font
					(size 1.27 1.27)
					(thickness 0.15)
				)
			)
		)
		(property "Author" "Antmicro"
			(at 330.000002 -70 0)
			(layer "F.Fab")
			(hide yes)
			(effects
				(font
					(size 1 1)
					(thickness 0.15)
				)
			)
		)
		(property "DNP" "DNP"
			(at 330.000002 -70 0)
			(layer "F.Fab")
			(hide yes)
			(effects
				(font
					(size 1 1)
					(thickness 0.15)
				)
			)
		)
		(property "License" "Apache-2.0"
			(at 330.000002 -70 0)
			(layer "F.Fab")
			(hide yes)
			(effects
				(font
					(size 1 1)
					(thickness 0.15)
				)
			)
		)
		(property "MPN" "960-31-18-S-AB-0"
			(at 330.000002 -70 0)
			(layer "F.Fab")
			(hide yes)
			(effects
				(font
					(size 1 1)
					(thickness 0.15)
				)
			)
		)
		(property "Manufacturer" "Wakefield-Vette"
			(at 330.000002 -70 0)
			(layer "F.Fab")
			(hide yes)
			(effects
				(font
					(size 1 1)
					(thickness 0.15)
				)
			)
		)
		(property "dnp" ""
			(at 330.000002 -70 0)
			(layer "F.Fab")
			(hide yes)
			(effects
				(font
					(size 1 1)
					(thickness 0.15)
				)
			)
		)
		(property "exclude_from_bom" ""
			(at 330.000002 -70 0)
			(layer "F.Fab")
			(hide yes)
			(effects
				(font
					(size 1 1)
					(thickness 0.15)
				)
			)
		)
		(sheetfile "k410t-devboard.kicad_sch")
		(attr exclude_from_pos_files exclude_from_bom)
		(fp_circle
			(center 19.17 -12.33)
			(end 21.72 -12.33)
			(stroke
				(width 0.05)
				(type solid)
			)
			(fill no)
			(layer "F.CrtYd")
		)
		(fp_circle
			(center -19.18 12.32)
			(end -16.64 12.32)
			(stroke
				(width 0.05)
				(type solid)
			)
			(fill no)
			(layer "F.CrtYd")
		)
		(fp_rect
			(start -22.6 -15.75)
			(end 22.6 15.75)
			(stroke
				(width 0.15)
				(type solid)
			)
			(fill no)
			(layer "F.Fab")
		)
		(pad "" np_thru_hole circle
			(at -19.176 12.32 90)
			(size 3.18 3.18)
			(drill 3.18)
			(layers "F&B.Cu" "*.Mask")
		)
		(pad "" np_thru_hole circle
			(at 19.184 -12.321 90)
			(size 3.18 3.18)
			(drill 3.18)
			(layers "F&B.Cu" "*.Mask")
		)
	)
	(footprint "antmicro-footprints:R_0402_1005Metric"
		(layer "F.Cu")
		(at 244.15 103.3)
		(descr "Resistor SMD 0402")
		(tags "resistor SMD 0402")
		(property "Reference" "R255"
			(at 0.8 0.35 0)
			(layer "F.SilkS")
			(effects
				(font
					(size 0.7 0.7)
					(thickness 0.15)
				)
				(justify left bottom)
			)
		)
		(property "Value" "R_0R_0402"
			(at 0 1.4 0)
			(layer "F.Fab")
			(effects
				(font
					(size 0.7 0.7)
					(thickness 0.15)
				)
				(justify left bottom)
			)
		)
		(property "Description" "SMD Chip Resistor, Jumper, 0 ohm, 100 mW, 0402 [1005 Metric], Thick Film, General Purpose"
			(at 0 0 0)
			(layer "F.Fab")
			(hide yes)
			(effects
				(font
					(size 1.27 1.27)
					(thickness 0.15)
				)
			)
		)
		(property "Author" "Antmicro"
			(at 0 0 0)
			(layer "F.Fab")
			(hide yes)
			(effects
				(font
					(size 1 1)
					(thickness 0.15)
				)
			)
		)
		(property "Current" "1A"
			(at 0 0 0)
			(layer "F.Fab")
			(hide yes)
			(effects
				(font
					(size 1 1)
					(thickness 0.15)
				)
			)
		)
		(property "License" "Apache-2.0"
			(at 0 0 0)
			(layer "F.Fab")
			(hide yes)
			(effects
				(font
					(size 1 1)
					(thickness 0.15)
				)
			)
		)
		(property "MPN" "ERJ2GE0R00X"
			(at 0 0 0)
			(layer "F.Fab")
			(hide yes)
			(effects
				(font
					(size 1 1)
					(thickness 0.15)
				)
			)
		)
		(property "Manufacturer" "Panasonic"
			(at 0 0 0)
			(layer "F.Fab")
			(hide yes)
			(effects
				(font
					(size 1 1)
					(thickness 0.15)
				)
			)
		)
		(property "Tolerance" ""
			(at 0 0 0)
			(layer "F.Fab")
			(hide yes)
			(effects
				(font
					(size 1 1)
					(thickness 0.15)
				)
			)
		)
		(property "Val" "0R"
			(at 0 0 0)
			(layer "F.Fab")
			(hide yes)
			(effects
				(font
					(size 1 1)
					(thickness 0.15)
				)
			)
		)
		(sheetname "HDMI + Ethernet")
		(sheetfile "hdmi-ethernet.kicad_sch")
		(attr smd)
		(fp_rect
			(start -0.925 -0.47)
			(end 0.925 0.47)
			(stroke
				(width 0.05)
				(type default)
			)
			(fill no)
			(layer "F.CrtYd")
		)
		(fp_rect
			(start -0.5 -0.25)
			(end 0.5 0.25)
			(stroke
				(width 0.15)
				(type solid)
			)
			(fill no)
			(layer "F.Fab")
		)
		(pad "1" smd roundrect
			(at -0.48 0)
			(size 0.59 0.64)
			(layers "F.Cu" "F.Mask" "F.Paste")
			(roundrect_rratio 0.25)
			(net 525 "/FPGA Bank 16 & 17/HDMI.D2_N")
			(pintype "passive")
		)
		(pad "2" smd roundrect
			(at 0.48 0)
			(size 0.59 0.64)
			(layers "F.Cu" "F.Mask" "F.Paste")
			(roundrect_rratio 0.25)
			(net 866 "/HDMI + Ethernet/HDMI_CONN_D2_N")
			(pintype "passive")
		)
	)
	(footprint "antmicro-footprints:Vishay_PowerPAK_1212-8_Single"
		(layer "F.Cu")
		(at 190.025 179.999)
		(descr "PowerPAK 1212-8 Single")
		(tags "Vishay PowerPAK 1212-8 Single")
		(property "Reference" "Q7"
			(at 2.925 1.901 90)
			(layer "F.SilkS")
			(effects
				(font
					(size 0.7 0.7)
					(thickness 0.15)
				)
				(justify left bottom)
			)
		)
		(property "Value" "SI7613DN-T1-GE3"
			(at -8 2.7 0)
			(layer "F.Fab")
			(effects
				(font
					(size 0.7 0.7)
					(thickness 0.15)
				)
				(justify left bottom)
			)
		)
		(property "Description" "Power MOSFET, P Channel, 20 V, 35 A, 0.0072 ohm, PowerPAK 1212, Surface Mount"
			(at 0 0 0)
			(layer "F.Fab")
			(hide yes)
			(effects
				(font
					(size 1.27 1.27)
					(thickness 0.15)
				)
			)
		)
		(property "Author" "Antmicro"
			(at 0 0 0)
			(layer "F.Fab")
			(hide yes)
			(effects
				(font
					(size 1 1)
					(thickness 0.15)
				)
			)
		)
		(property "License" "Apache-2.0"
			(at 0 0 0)
			(layer "F.Fab")
			(hide yes)
			(effects
				(font
					(size 1 1)
					(thickness 0.15)
				)
			)
		)
		(property "MPN" "SI7613DN-T1-GE3"
			(at 0 0 0)
			(layer "F.Fab")
			(hide yes)
			(effects
				(font
					(size 1 1)
					(thickness 0.15)
				)
			)
		)
		(property "Manufacturer" "Vishay"
			(at 0 0 0)
			(layer "F.Fab")
			(hide yes)
			(effects
				(font
					(size 1 1)
					(thickness 0.15)
				)
			)
		)
		(sheetname "Power supply")
		(sheetfile "power-supply.kicad_sch")
		(attr smd)
		(fp_line
			(start -1.651 -1.651)
			(end -1.651 -1.317)
			(stroke
				(width 0.15)
				(type solid)
			)
			(layer "F.SilkS")
		)
		(fp_line
			(start -1.651 -1.651)
			(end 1.648 -1.651)
			(stroke
				(width 0.15)
				(type solid)
			)
			(layer "F.SilkS")
		)
		(fp_line
			(start -1.635 1.3)
			(end -1.635 1.634)
			(stroke
				(width 0.15)
				(type solid)
			)
			(layer "F.SilkS")
		)
		(fp_line
			(start -1.635 1.634)
			(end 1.634 1.634)
			(stroke
				(width 0.15)
				(type solid)
			)
			(layer "F.SilkS")
		)
		(fp_line
			(start 1.634 1.3)
			(end 1.634 1.634)
			(stroke
				(width 0.15)
				(type solid)
			)
			(layer "F.SilkS")
		)
		(fp_line
			(start 1.648 -1.651)
			(end 1.648 -1.317)
			(stroke
				(width 0.15)
				(type solid)
			)
			(layer "F.SilkS")
		)
		(fp_circle
			(center -1.9 -1.4)
			(end -1.85 -1.4)
			(stroke
				(width 0.15)
				(type solid)
			)
			(fill yes)
			(layer "F.SilkS")
		)
		(fp_rect
			(start -2 -1.8)
			(end 2 1.798)
			(stroke
				(width 0.05)
				(type solid)
			)
			(fill no)
			(layer "F.CrtYd")
		)
		(fp_line
			(start -1.6425 -1.4175)
			(end -1.4175 -1.6425)
			(stroke
				(width 0.15)
				(type solid)
			)
			(layer "F.Fab")
		)
		(fp_rect
			(start -1.651 -1.651)
			(end 1.648 1.648)
			(stroke
				(width 0.15)
				(type solid)
			)
			(fill no)
			(layer "F.Fab")
		)
		(pad "1" smd rect
			(at -1.436 -0.99)
			(size 0.99 0.405)
			(layers "F.Cu" "F.Mask" "F.Paste")
			(net 702 "VDC")
			(pinfunction "S")
			(pintype "passive")
		)
		(pad "2" smd rect
			(at -1.436 -0.332)
			(size 0.99 0.405)
			(layers "F.Cu" "F.Mask" "F.Paste")
			(net 702 "VDC")
			(pinfunction "S")
			(pintype "passive")
		)
		(pad "3" smd rect
			(at -1.436 0.33)
			(size 0.99 0.405)
			(layers "F.Cu" "F.Mask" "F.Paste")
			(net 702 "VDC")
			(pinfunction "S")
			(pintype "passive")
		)
		(pad "4" smd rect
			(at -1.436 0.988)
			(size 0.99 0.405)
			(layers "F.Cu" "F.Mask" "F.Paste")
			(net 342 "Net-(Q7-G)")
			(pinfunction "G")
			(pintype "passive")
		)
		(pad "5" smd custom
			(at 0.557 0)
			(size 1.725 2.235)
			(layers "F.Cu" "F.Mask" "F.Paste")
			(net 956 "/DC-DC Converters/POE_DC")
			(pinfunction "D")
			(pintype "passive")
			(zone_connect 2)
			(options
				(clearance outline)
				(anchor rect)
			)
			(primitives
				(gr_poly
					(pts
						(xy 0.8625 0.1275) (xy 0.8625 -0.1275) (xy 1.3725 -0.1275) (xy 1.3725 -0.5325) (xy 0.8625 -0.5325)
						(xy 0.8625 -0.7875) (xy 1.3725 -0.7875) (xy 1.3725 -1.195) (xy 0.6125 -1.195) (xy 0.6125 1.195)
						(xy 1.3725 1.195) (xy 1.3725 0.7875) (xy 0.8625 0.7875) (xy 0.8625 0.5325) (xy 1.3725 0.5325)
						(xy 1.3725 0.1275)
					)
					(width 0)
					(fill yes)
				)
			)
		)
	)
	(footprint "antmicro-footprints:R_0402_1005Metric"
		(layer "F.Cu")
		(at 170.4 188.7)
		(descr "Resistor SMD 0402")
		(tags "resistor SMD 0402")
		(property "Reference" "R308"
			(at -1.2 -0.55 0)
			(layer "F.SilkS")
			(effects
				(font
					(size 0.7 0.7)
					(thickness 0.15)
				)
				(justify left bottom)
			)
		)
		(property "Value" "R_0R_0402"
			(at 0 1.4 0)
			(layer "F.Fab")
			(effects
				(font
					(size 0.7 0.7)
					(thickness 0.15)
				)
				(justify left bottom)
			)
		)
		(property "Description" "SMD Chip Resistor, Jumper, 0 ohm, 100 mW, 0402 [1005 Metric], Thick Film, General Purpose"
			(at 0 0 0)
			(layer "F.Fab")
			(hide yes)
			(effects
				(font
					(size 1.27 1.27)
					(thickness 0.15)
				)
			)
		)
		(property "Author" "Antmicro"
			(at 0 0 0)
			(layer "F.Fab")
			(hide yes)
			(effects
				(font
					(size 1 1)
					(thickness 0.15)
				)
			)
		)
		(property "Current" "1A"
			(at 0 0 0)
			(layer "F.Fab")
			(hide yes)
			(effects
				(font
					(size 1 1)
					(thickness 0.15)
				)
			)
		)
		(property "License" "Apache-2.0"
			(at 0 0 0)
			(layer "F.Fab")
			(hide yes)
			(effects
				(font
					(size 1 1)
					(thickness 0.15)
				)
			)
		)
		(property "MPN" "ERJ2GE0R00X"
			(at 0 0 0)
			(layer "F.Fab")
			(hide yes)
			(effects
				(font
					(size 1 1)
					(thickness 0.15)
				)
			)
		)
		(property "Manufacturer" "Panasonic"
			(at 0 0 0)
			(layer "F.Fab")
			(hide yes)
			(effects
				(font
					(size 1 1)
					(thickness 0.15)
				)
			)
		)
		(property "Tolerance" ""
			(at 0 0 0)
			(layer "F.Fab")
			(hide yes)
			(effects
				(font
					(size 1 1)
					(thickness 0.15)
				)
			)
		)
		(property "Val" "0R"
			(at 0 0 0)
			(layer "F.Fab")
			(hide yes)
			(effects
				(font
					(size 1 1)
					(thickness 0.15)
				)
			)
		)
		(sheetname "DC-DC Converters")
		(sheetfile "dc-dc.kicad_sch")
		(attr smd)
		(fp_rect
			(start -0.925 -0.47)
			(end 0.925 0.47)
			(stroke
				(width 0.05)
				(type default)
			)
			(fill no)
			(layer "F.CrtYd")
		)
		(fp_rect
			(start -0.5 -0.25)
			(end 0.5 0.25)
			(stroke
				(width 0.15)
				(type solid)
			)
			(fill no)
			(layer "F.Fab")
		)
		(pad "1" smd roundrect
			(at -0.48 0)
			(size 0.59 0.64)
			(layers "F.Cu" "F.Mask" "F.Paste")
			(roundrect_rratio 0.25)
			(net 14 "/DC-DC Converters/SEQ_EN")
			(pintype "passive")
		)
		(pad "2" smd roundrect
			(at 0.48 0)
			(size 0.59 0.64)
			(layers "F.Cu" "F.Mask" "F.Paste")
			(roundrect_rratio 0.25)
			(net 961 "/DC-DC Converters/ON{slash}OFF")
			(pintype "passive")
		)
	)
	(footprint "antmicro-footprints:UQFN-16-1.8x2.6mm_P0.4mm_Texas_RSV0016A"
		(layer "F.Cu")
		(at 233.7 148.4)
		(descr "https://www.ti.com/lit/ds/symlink/sn74avch4t245-ep.pdf?ts=1679484181203&ref_url=https%253A%252F%252Fwww.ti.com%252Fproduct%252FSN74AVCH4T245-EP%253Futm_source%253Dgoogle%2526utm_medium%253Dcpc%2526utm_campaign%253Dasc-int-null-prodfolderdynamic-cpc-pf-google-wwe_int%2526utm_content%253Dprodfolddynamic%2526ds_k%253DDYNAMIC%2BSEARCH%2BADS%2526DCM%253Dyes%2526gclid%253DCjwKCAjwzuqgBhAcEiwAdj5dRvR_WgyvqqhLxMx8zfbFv2a6tg33JIMv01Bn4M1kA4JzW1nDDW7OzhoCRbkQAvD_BwE%2526gclsrc%253Daw.ds")
		(property "Reference" "U25"
			(at -1.35 1.45 90)
			(layer "F.SilkS")
			(effects
				(font
					(size 0.7 0.7)
					(thickness 0.15)
				)
				(justify left bottom)
			)
		)
		(property "Value" "TUSB1106RSVR"
			(at -1.25 2.5 0)
			(layer "F.Fab")
			(effects
				(font
					(size 0.7 0.7)
					(thickness 0.15)
				)
				(justify left bottom)
			)
		)
		(property "Description" "1/1 Transceiver Half USB 2.0 16-UQFN"
			(at 0 0 0)
			(layer "F.Fab")
			(hide yes)
			(effects
				(font
					(size 1.27 1.27)
					(thickness 0.15)
				)
			)
		)
		(property "Author" "Antmicro"
			(at 0 0 0)
			(layer "F.Fab")
			(hide yes)
			(effects
				(font
					(size 1 1)
					(thickness 0.15)
				)
			)
		)
		(property "License" "Apache-2.0"
			(at 0 0 0)
			(layer "F.Fab")
			(hide yes)
			(effects
				(font
					(size 1 1)
					(thickness 0.15)
				)
			)
		)
		(property "MPN" "TUSB1106RSVR"
			(at 0 0 0)
			(layer "F.Fab")
			(hide yes)
			(effects
				(font
					(size 1 1)
					(thickness 0.15)
				)
			)
		)
		(property "Manufacturer" "Texas Instruments"
			(at 0 0 0)
			(layer "F.Fab")
			(hide yes)
			(effects
				(font
					(size 1 1)
					(thickness 0.15)
				)
			)
		)
		(sheetname "USB PHY")
		(sheetfile "usb-phy.kicad_sch")
		(attr smd)
		(fp_line
			(start -0.9 1.2995)
			(end -0.9 0.8)
			(stroke
				(width 0.15)
				(type solid)
			)
			(layer "F.SilkS")
		)
		(fp_line
			(start -0.8 -1.3)
			(end -0.9 -1.3)
			(stroke
				(width 0.15)
				(type solid)
			)
			(layer "F.SilkS")
		)
		(fp_line
			(start -0.8 1.2995)
			(end -0.9 1.2995)
			(stroke
				(width 0.15)
				(type solid)
			)
			(layer "F.SilkS")
		)
		(fp_line
			(start 0.8 -1.3)
			(end 0.9 -1.3)
			(stroke
				(width 0.15)
				(type solid)
			)
			(layer "F.SilkS")
		)
		(fp_line
			(start 0.8 1.3)
			(end 0.899 1.3)
			(stroke
				(width 0.15)
				(type solid)
			)
			(layer "F.SilkS")
		)
		(fp_line
			(start 0.9 -1.3)
			(end 0.9 -0.8005)
			(stroke
				(width 0.15)
				(type solid)
			)
			(layer "F.SilkS")
		)
		(fp_line
			(start 0.9 0.8)
			(end 0.899 1.3)
			(stroke
				(width 0.15)
				(type solid)
			)
			(layer "F.SilkS")
		)
		(fp_rect
			(start -1.25 -1.65)
			(end 1.25 1.65)
			(stroke
				(width 0.05)
				(type solid)
			)
			(fill no)
			(layer "F.CrtYd")
		)
		(fp_line
			(start -0.902 1.3)
			(end -0.902 -1.301)
			(stroke
				(width 0.15)
				(type solid)
			)
			(layer "F.Fab")
		)
		(fp_line
			(start 0.9 -1.301)
			(end -0.902 -1.301)
			(stroke
				(width 0.15)
				(type solid)
			)
			(layer "F.Fab")
		)
		(fp_line
			(start 0.9 1.3)
			(end -0.902 1.3)
			(stroke
				(width 0.15)
				(type solid)
			)
			(layer "F.Fab")
		)
		(fp_line
			(start 0.9 1.3)
			(end 0.9 -1.301)
			(stroke
				(width 0.15)
				(type solid)
			)
			(layer "F.Fab")
		)
		(fp_text user "."
			(at -1.45 -0.75 0)
			(layer "F.SilkS")
			(effects
				(font
					(size 0.7 0.7)
					(thickness 0.15)
				)
				(justify left bottom)
			)
		)
		(pad "1" smd roundrect
			(at -0.75 -0.6)
			(size 0.7 0.2)
			(layers "F.Cu" "F.Mask" "F.Paste")
			(roundrect_rratio 0.2272727273)
			(net 498 "/FPGA Bank 12 & 13/USB_USER.~{OE}")
			(pinfunction "~{OE}")
			(pintype "input")
		)
		(pad "2" smd roundrect
			(at -0.802 -0.202)
			(size 0.6 0.2)
			(layers "F.Cu" "F.Mask" "F.Paste")
			(roundrect_rratio 0.2272727273)
			(net 587 "/FPGA Bank 12 & 13/USB_USER.RCV")
			(pinfunction "RCV")
			(pintype "output")
		)
		(pad "3" smd roundrect
			(at -0.802 0.2)
			(size 0.6 0.2)
			(layers "F.Cu" "F.Mask" "F.Paste")
			(roundrect_rratio 0.2272727273)
			(net 584 "/FPGA Bank 12 & 13/USB_USER.VP")
			(pinfunction "VP")
			(pintype "output")
		)
		(pad "4" smd roundrect
			(at -0.802 0.598)
			(size 0.6 0.2)
			(layers "F.Cu" "F.Mask" "F.Paste")
			(roundrect_rratio 0.2272727273)
			(net 1397 "/FPGA Bank 12 & 13/USB_USER.VM")
			(pinfunction "VM")
			(pintype "output")
		)
		(pad "5" smd roundrect
			(at -0.6 1.199 90)
			(size 0.6 0.2)
			(layers "F.Cu" "F.Mask" "F.Paste")
			(roundrect_rratio 0.2272727273)
			(net 500 "/FPGA Bank 12 & 13/USB_USER.SUS")
			(pinfunction "SUSPND")
			(pintype "input")
		)
		(pad "6" smd roundrect
			(at -0.202 1.199 90)
			(size 0.6 0.2)
			(layers "F.Cu" "F.Mask" "F.Paste")
			(roundrect_rratio 0.2272727273)
			(net 1 "GND")
			(pinfunction "GND")
			(pintype "power_in")
		)
		(pad "7" smd roundrect
			(at 0.2 1.199 90)
			(size 0.6 0.2)
			(layers "F.Cu" "F.Mask" "F.Paste")
			(roundrect_rratio 0.2272727273)
			(net 26 "+1V8")
			(pinfunction "VCCIO")
			(pintype "power_in")
		)
		(pad "8" smd roundrect
			(at 0.598 1.199 90)
			(size 0.6 0.2)
			(layers "F.Cu" "F.Mask" "F.Paste")
			(roundrect_rratio 0.2272727273)
			(net 616 "/FPGA Bank 12 & 13/USB_USER.SPD")
			(pinfunction "SPEEED")
			(pintype "input")
		)
		(pad "9" smd roundrect
			(at 0.8 0.598)
			(size 0.6 0.2)
			(layers "F.Cu" "F.Mask" "F.Paste")
			(roundrect_rratio 0.2272727273)
			(net 927 "/USB PHY/USB_USR_D-")
			(pinfunction "D-")
			(pintype "bidirectional")
		)
		(pad "10" smd roundrect
			(at 0.8 0.2)
			(size 0.6 0.2)
			(layers "F.Cu" "F.Mask" "F.Paste")
			(roundrect_rratio 0.2272727273)
			(net 928 "/USB PHY/USB_USR_D+")
			(pinfunction "D+")
			(pintype "bidirectional")
		)
		(pad "11" smd roundrect
			(at 0.8 -0.202)
			(size 0.6 0.2)
			(layers "F.Cu" "F.Mask" "F.Paste")
			(roundrect_rratio 0.2272727273)
			(net 639 "/FPGA Bank 12 & 13/USB_USER.VPO")
			(pinfunction "VPO")
			(pintype "input")
		)
		(pad "12" smd roundrect
			(at 0.8 -0.6)
			(size 0.6 0.2)
			(layers "F.Cu" "F.Mask" "F.Paste")
			(roundrect_rratio 0.2272727273)
			(net 693 "/FPGA Bank 12 & 13/USB_USER.VMO")
			(pinfunction "VMO")
			(pintype "input")
		)
		(pad "13" smd roundrect
			(at 0.598 -1.2 90)
			(size 0.6 0.2)
			(layers "F.Cu" "F.Mask" "F.Paste")
			(roundrect_rratio 0.2272727273)
			(net 24 "+3V3")
			(pinfunction "VREG")
			(pintype "power_out")
		)
		(pad "14" smd roundrect
			(at 0.2 -1.2 90)
			(size 0.6 0.2)
			(layers "F.Cu" "F.Mask" "F.Paste")
			(roundrect_rratio 0.2272727273)
			(net 24 "+3V3")
			(pinfunction "VCC")
			(pintype "power_in")
		)
		(pad "15" smd roundrect
			(at -0.202 -1.2 90)
			(size 0.6 0.2)
			(layers "F.Cu" "F.Mask" "F.Paste")
			(roundrect_rratio 0.2272727273)
			(net 926 "/USB PHY/USB_USR_VPU")
			(pinfunction "VPU")
			(pintype "input")
		)
		(pad "16" smd roundrect
			(at -0.6 -1.2 90)
			(size 0.6 0.2)
			(layers "F.Cu" "F.Mask" "F.Paste")
			(roundrect_rratio 0.2272727273)
			(net 619 "/FPGA Bank 12 & 13/USB_USER.SCON")
			(pinfunction "SOFTCON")
			(pintype "input")
		)
	)
	(footprint "antmicro-footprints:C_0805_2012Metric"
		(layer "F.Cu")
		(at 189.5 161.949 -90)
		(descr "Capacitor SMD 0805")
		(tags "capacitor SMD 0805")
		(property "Reference" "C341"
			(at -1.399 2.1 90)
			(layer "F.SilkS")
			(effects
				(font
					(size 0.7 0.7)
					(thickness 0.15)
				)
				(justify right bottom)
			)
		)
		(property "Value" "C_22u_25V_0805"
			(at 0 1.947 90)
			(layer "F.Fab")
			(effects
				(font
					(size 0.7 0.7)
					(thickness 0.15)
				)
				(justify right bottom)
			)
		)
		(property "Description" "SMT Multilayer Ceramic Capacitor, 22uF, +/-20%, 25V, X5R, 0805 [2012 Metric]"
			(at 0 0 270)
			(layer "F.Fab")
			(hide yes)
			(effects
				(font
					(size 1.27 1.27)
					(thickness 0.15)
				)
			)
		)
		(property "Author" "Antmicro"
			(at 27.551 351.449 0)
			(layer "F.Fab")
			(hide yes)
			(effects
				(font
					(size 1 1)
					(thickness 0.15)
				)
			)
		)
		(property "Dielectric" "X5R"
			(at 27.551 351.449 0)
			(layer "F.Fab")
			(hide yes)
			(effects
				(font
					(size 1 1)
					(thickness 0.15)
				)
			)
		)
		(property "License" "Apache-2.0"
			(at 27.551 351.449 0)
			(layer "F.Fab")
			(hide yes)
			(effects
				(font
					(size 1 1)
					(thickness 0.15)
				)
			)
		)
		(property "MPN" "CL21A226MAYNNNE"
			(at 27.551 351.449 0)
			(layer "F.Fab")
			(hide yes)
			(effects
				(font
					(size 1 1)
					(thickness 0.15)
				)
			)
		)
		(property "Manufacturer" "Samsung Electro-Mechanics"
			(at 27.551 351.449 0)
			(layer "F.Fab")
			(hide yes)
			(effects
				(font
					(size 1 1)
					(thickness 0.15)
				)
			)
		)
		(property "Val" "22u"
			(at 27.551 351.449 0)
			(layer "F.Fab")
			(hide yes)
			(effects
				(font
					(size 1 1)
					(thickness 0.15)
				)
			)
		)
		(property "Voltage" "25V"
			(at 27.551 351.449 0)
			(layer "F.Fab")
			(hide yes)
			(effects
				(font
					(size 1 1)
					(thickness 0.15)
				)
			)
		)
		(sheetname "DC-DC Converters")
		(sheetfile "dc-dc.kicad_sch")
		(attr smd)
		(fp_line
			(start -0.3 0.7)
			(end 0.3 0.7)
			(stroke
				(width 0.15)
				(type solid)
			)
			(layer "F.SilkS")
		)
		(fp_line
			(start -0.3 -0.7)
			(end 0.3 -0.7)
			(stroke
				(width 0.15)
				(type solid)
			)
			(layer "F.SilkS")
		)
		(fp_rect
			(start 1.95 -0.9)
			(end -1.95 0.9)
			(stroke
				(width 0.05)
				(type default)
			)
			(fill no)
			(layer "F.CrtYd")
		)
		(fp_rect
			(start -0.95 -0.675)
			(end 0.95 0.675)
			(stroke
				(width 0.15)
				(type solid)
			)
			(fill no)
			(layer "F.Fab")
		)
		(pad "1" smd roundrect
			(at -1.1 0 270)
			(size 1.2 1.3)
			(layers "F.Cu" "F.Mask" "F.Paste")
			(roundrect_rratio 0.25)
			(net 1 "GND")
			(pintype "passive")
		)
		(pad "2" smd roundrect
			(at 1.1 0 270)
			(size 1.2 1.3)
			(layers "F.Cu" "F.Mask" "F.Paste")
			(roundrect_rratio 0.25)
			(net 702 "VDC")
			(pintype "passive")
		)
	)
	(footprint "antmicro-footprints:R_0402_1005Metric"
		(layer "F.Cu")
		(at 264.7 137.6 90)
		(descr "Resistor SMD 0402")
		(tags "resistor SMD 0402")
		(property "Reference" "R151"
			(at 32.3 -29.85 180)
			(layer "F.SilkS")
			(effects
				(font
					(size 0.7 0.7)
					(thickness 0.15)
				)
				(justify left bottom)
			)
		)
		(property "Value" "R_330R_0402"
			(at 0 1.4 90)
			(layer "F.Fab")
			(effects
				(font
					(size 0.7 0.7)
					(thickness 0.15)
				)
				(justify left bottom)
			)
		)
		(property "Description" "SMD Chip Resistor, 330 ohm, ± 1%, 62.5 mW, 0402 [1005 Metric], Thick Film, General Purpose"
			(at 0 0 90)
			(layer "F.Fab")
			(hide yes)
			(effects
				(font
					(size 1.27 1.27)
					(thickness 0.15)
				)
			)
		)
		(property "Author" "Antmicro"
			(at 402.3 -127.1 0)
			(layer "F.Fab")
			(hide yes)
			(effects
				(font
					(size 1 1)
					(thickness 0.15)
				)
			)
		)
		(property "License" "Apache-2.0"
			(at 402.3 -127.1 0)
			(layer "F.Fab")
			(hide yes)
			(effects
				(font
					(size 1 1)
					(thickness 0.15)
				)
			)
		)
		(property "MPN" "CR0402-FX-3300GLF"
			(at 402.3 -127.1 0)
			(layer "F.Fab")
			(hide yes)
			(effects
				(font
					(size 1 1)
					(thickness 0.15)
				)
			)
		)
		(property "Manufacturer" "Bourns"
			(at 402.3 -127.1 0)
			(layer "F.Fab")
			(hide yes)
			(effects
				(font
					(size 1 1)
					(thickness 0.15)
				)
			)
		)
		(property "Tolerance" "1%"
			(at 402.3 -127.1 0)
			(layer "F.Fab")
			(hide yes)
			(effects
				(font
					(size 1 1)
					(thickness 0.15)
				)
			)
		)
		(property "Val" "330R"
			(at 402.3 -127.1 0)
			(layer "F.Fab")
			(hide yes)
			(effects
				(font
					(size 1 1)
					(thickness 0.15)
				)
			)
		)
		(sheetname "USB PHY")
		(sheetfile "usb-phy.kicad_sch")
		(attr smd)
		(fp_rect
			(start -0.925 -0.47)
			(end 0.925 0.47)
			(stroke
				(width 0.05)
				(type default)
			)
			(fill no)
			(layer "F.CrtYd")
		)
		(fp_rect
			(start -0.5 -0.25)
			(end 0.5 0.25)
			(stroke
				(width 0.15)
				(type solid)
			)
			(fill no)
			(layer "F.Fab")
		)
		(pad "1" smd roundrect
			(at -0.48 0 90)
			(size 0.59 0.64)
			(layers "F.Cu" "F.Mask" "F.Paste")
			(roundrect_rratio 0.25)
			(net 791 "Net-(D27-A)")
			(pintype "passive")
		)
		(pad "2" smd roundrect
			(at 0.48 0 90)
			(size 0.59 0.64)
			(layers "F.Cu" "F.Mask" "F.Paste")
			(roundrect_rratio 0.25)
			(net 913 "/USB PHY/LED_RX0")
			(pintype "passive")
		)
	)
	(footprint "antmicro-footprints:C_0402_1005Metric"
		(layer "F.Cu")
		(at 173.570001 114.096251 180)
		(descr "Capacitor SMD 0402")
		(tags "capacitor SMD 0402")
		(property "Reference" "C303"
			(at -3.729999 -0.356249 0)
			(layer "F.SilkS")
			(effects
				(font
					(size 0.7 0.7)
					(thickness 0.15)
				)
				(justify right bottom)
			)
		)
		(property "Value" "C_100n_0402"
			(at 0 1.4 0)
			(layer "F.Fab")
			(effects
				(font
					(size 0.7 0.7)
					(thickness 0.15)
				)
				(justify right bottom)
			)
		)
		(property "Description" "SMD Multilayer Ceramic Capacitor, 0.1 µF, 50 V, 0402 [1005 Metric], ± 10%, X5R, GRM Series"
			(at 0 0 180)
			(layer "F.Fab")
			(hide yes)
			(effects
				(font
					(size 1.27 1.27)
					(thickness 0.15)
				)
			)
		)
		(property "Author" "Antmicro"
			(at 347.140002 228.192502 0)
			(layer "F.Fab")
			(hide yes)
			(effects
				(font
					(size 1 1)
					(thickness 0.15)
				)
			)
		)
		(property "Dielectric" "X5R"
			(at 347.140002 228.192502 0)
			(layer "F.Fab")
			(hide yes)
			(effects
				(font
					(size 1 1)
					(thickness 0.15)
				)
			)
		)
		(property "License" "Apache-2.0"
			(at 347.140002 228.192502 0)
			(layer "F.Fab")
			(hide yes)
			(effects
				(font
					(size 1 1)
					(thickness 0.15)
				)
			)
		)
		(property "MPN" "GRM155R61H104KE14D"
			(at 347.140002 228.192502 0)
			(layer "F.Fab")
			(hide yes)
			(effects
				(font
					(size 1 1)
					(thickness 0.15)
				)
			)
		)
		(property "Manufacturer" "Murata"
			(at 347.140002 228.192502 0)
			(layer "F.Fab")
			(hide yes)
			(effects
				(font
					(size 1 1)
					(thickness 0.15)
				)
			)
		)
		(property "Val" "100n"
			(at 347.140002 228.192502 0)
			(layer "F.Fab")
			(hide yes)
			(effects
				(font
					(size 1 1)
					(thickness 0.15)
				)
			)
		)
		(property "Voltage" "50V"
			(at 347.140002 228.192502 0)
			(layer "F.Fab")
			(hide yes)
			(effects
				(font
					(size 1 1)
					(thickness 0.15)
				)
			)
		)
		(sheetname "FMC+ HSPC")
		(sheetfile "fmc-hspc.kicad_sch")
		(attr smd)
		(fp_rect
			(start -0.925 -0.47)
			(end 0.925 0.47)
			(stroke
				(width 0.05)
				(type default)
			)
			(fill no)
			(layer "F.CrtYd")
		)
		(fp_line
			(start 0.504 0.248)
			(end -0.494 0.248)
			(stroke
				(width 0.15)
				(type solid)
			)
			(layer "F.Fab")
		)
		(fp_line
			(start 0.504 -0.25)
			(end 0.504 0.248)
			(stroke
				(width 0.15)
				(type solid)
			)
			(layer "F.Fab")
		)
		(fp_line
			(start -0.494 0.248)
			(end -0.494 -0.25)
			(stroke
				(width 0.15)
				(type solid)
			)
			(layer "F.Fab")
		)
		(fp_line
			(start -0.494 -0.25)
			(end 0.504 -0.25)
			(stroke
				(width 0.15)
				(type solid)
			)
			(layer "F.Fab")
		)
		(pad "1" smd roundrect
			(at -0.48 0 180)
			(size 0.59 0.64)
			(layers "F.Cu" "F.Mask" "F.Paste")
			(roundrect_rratio 0.25)
			(net 78 "/FMC+ HSPC/GTX116.TX1_N")
			(pintype "passive")
		)
		(pad "2" smd roundrect
			(at 0.48 0 180)
			(size 0.59 0.64)
			(layers "F.Cu" "F.Mask" "F.Paste")
			(roundrect_rratio 0.25)
			(net 76 "/FMC+ HSPC/GTX_TX2_C_N")
			(pintype "passive")
		)
	)
	(footprint "antmicro-footprints:R_0402_1005Metric"
		(layer "F.Cu")
		(at 254.445 133.835)
		(descr "Resistor SMD 0402")
		(tags "resistor SMD 0402")
		(property "Reference" "R159"
			(at -1.395 -3.935 0)
			(layer "F.SilkS")
			(effects
				(font
					(size 0.7 0.7)
					(thickness 0.15)
				)
				(justify left bottom)
			)
		)
		(property "Value" "R_10k_0402"
			(at 0 1.4 0)
			(layer "F.Fab")
			(effects
				(font
					(size 0.7 0.7)
					(thickness 0.15)
				)
				(justify left bottom)
			)
		)
		(property "Description" "SMD Chip Resistor, 10 kohm, ± 1%, 62.5 mW, 0402 [1005 Metric], Thick Film, General Purpose"
			(at 0 0 0)
			(layer "F.Fab")
			(hide yes)
			(effects
				(font
					(size 1.27 1.27)
					(thickness 0.15)
				)
			)
		)
		(property "Author" "Antmicro"
			(at 0 0 0)
			(layer "F.Fab")
			(hide yes)
			(effects
				(font
					(size 1 1)
					(thickness 0.15)
				)
			)
		)
		(property "License" "Apache-2.0"
			(at 0 0 0)
			(layer "F.Fab")
			(hide yes)
			(effects
				(font
					(size 1 1)
					(thickness 0.15)
				)
			)
		)
		(property "MPN" "CR0402-FX-1002GLF"
			(at 0 0 0)
			(layer "F.Fab")
			(hide yes)
			(effects
				(font
					(size 1 1)
					(thickness 0.15)
				)
			)
		)
		(property "Manufacturer" "Bourns"
			(at 0 0 0)
			(layer "F.Fab")
			(hide yes)
			(effects
				(font
					(size 1 1)
					(thickness 0.15)
				)
			)
		)
		(property "Tolerance" "1%"
			(at 0 0 0)
			(layer "F.Fab")
			(hide yes)
			(effects
				(font
					(size 1 1)
					(thickness 0.15)
				)
			)
		)
		(property "Val" "10k"
			(at 0 0 0)
			(layer "F.Fab")
			(hide yes)
			(effects
				(font
					(size 1 1)
					(thickness 0.15)
				)
			)
		)
		(sheetname "USB PHY")
		(sheetfile "usb-phy.kicad_sch")
		(attr smd)
		(fp_rect
			(start -0.925 -0.47)
			(end 0.925 0.47)
			(stroke
				(width 0.05)
				(type default)
			)
			(fill no)
			(layer "F.CrtYd")
		)
		(fp_rect
			(start -0.5 -0.25)
			(end 0.5 0.25)
			(stroke
				(width 0.15)
				(type solid)
			)
			(fill no)
			(layer "F.Fab")
		)
		(pad "1" smd roundrect
			(at -0.48 0)
			(size 0.59 0.64)
			(layers "F.Cu" "F.Mask" "F.Paste")
			(roundrect_rratio 0.25)
			(net 919 "/USB PHY/FTDI_RST")
			(pintype "passive")
		)
		(pad "2" smd roundrect
			(at 0.48 0)
			(size 0.59 0.64)
			(layers "F.Cu" "F.Mask" "F.Paste")
			(roundrect_rratio 0.25)
			(net 707 "/USB PHY/FTDI_3V3")
			(pintype "passive")
		)
	)
	(footprint "antmicro-footprints:C_0603_1608Metric"
		(layer "F.Cu")
		(at 186.525 184.373999 -90)
		(descr "Capacitor SMD 0603")
		(tags "capacitor 0603")
		(property "Reference" "C206"
			(at -1.073999 0.575 90)
			(layer "F.SilkS")
			(effects
				(font
					(size 0.7 0.7)
					(thickness 0.15)
				)
				(justify right bottom)
			)
		)
		(property "Value" "C_1u_25V_0603"
			(at 0 1.6 90)
			(layer "F.Fab")
			(effects
				(font
					(size 0.7 0.7)
					(thickness 0.15)
				)
				(justify right bottom)
			)
		)
		(property "Description" "SMD Multilayer Ceramic Capacitor, 1 µF, 25 V, 0603 [1608 Metric], ± 10%, X5R, CL"
			(at 0 0 270)
			(layer "F.Fab")
			(hide yes)
			(effects
				(font
					(size 1.27 1.27)
					(thickness 0.15)
				)
			)
		)
		(property "Author" "Antmicro"
			(at 2.151001 370.898999 0)
			(layer "F.Fab")
			(hide yes)
			(effects
				(font
					(size 1 1)
					(thickness 0.15)
				)
			)
		)
		(property "Dielectric" ""
			(at 2.151001 370.898999 0)
			(layer "F.Fab")
			(hide yes)
			(effects
				(font
					(size 1 1)
					(thickness 0.15)
				)
			)
		)
		(property "License" "Apache-2.0"
			(at 2.151001 370.898999 0)
			(layer "F.Fab")
			(hide yes)
			(effects
				(font
					(size 1 1)
					(thickness 0.15)
				)
			)
		)
		(property "MPN" "CL10A105KA8NNNC"
			(at 2.151001 370.898999 0)
			(layer "F.Fab")
			(hide yes)
			(effects
				(font
					(size 1 1)
					(thickness 0.15)
				)
			)
		)
		(property "Manufacturer" "Samsung Electro-Mechanics"
			(at 2.151001 370.898999 0)
			(layer "F.Fab")
			(hide yes)
			(effects
				(font
					(size 1 1)
					(thickness 0.15)
				)
			)
		)
		(property "Val" "1u"
			(at 2.151001 370.898999 0)
			(layer "F.Fab")
			(hide yes)
			(effects
				(font
					(size 1 1)
					(thickness 0.15)
				)
			)
		)
		(property "Voltage" "25V"
			(at 2.151001 370.898999 0)
			(layer "F.Fab")
			(hide yes)
			(effects
				(font
					(size 1 1)
					(thickness 0.15)
				)
			)
		)
		(sheetname "Power supply")
		(sheetfile "power-supply.kicad_sch")
		(attr smd)
		(fp_line
			(start -0.15 0.4)
			(end 0.15 0.4)
			(stroke
				(width 0.15)
				(type solid)
			)
			(layer "F.SilkS")
		)
		(fp_line
			(start -0.15 -0.4)
			(end 0.15 -0.4)
			(stroke
				(width 0.15)
				(type solid)
			)
			(layer "F.SilkS")
		)
		(fp_rect
			(start -1.25 -0.65)
			(end 1.25 0.65)
			(stroke
				(width 0.05)
				(type solid)
			)
			(fill no)
			(layer "F.CrtYd")
		)
		(fp_rect
			(start -0.8 -0.4)
			(end 0.8 0.4)
			(stroke
				(width 0.15)
				(type solid)
			)
			(fill no)
			(layer "F.Fab")
		)
		(pad "1" smd roundrect
			(at -0.7 0 270)
			(size 0.8 1)
			(layers "F.Cu" "F.Mask" "F.Paste")
			(roundrect_rratio 0.2)
			(net 1 "GND")
			(pintype "passive")
		)
		(pad "2" smd roundrect
			(at 0.7 0 270)
			(size 0.8 1)
			(layers "F.Cu" "F.Mask" "F.Paste")
			(roundrect_rratio 0.2)
			(net 702 "VDC")
			(pintype "passive")
		)
	)
	(footprint "antmicro-footprints:LED_0603_1608Metric_G"
		(layer "F.Cu")
		(at 266.6 135.4 180)
		(descr "LED SMD 0603 Green")
		(tags "LED SMD 0603 Green")
		(property "Reference" "D28"
			(at -0.85 -1.6 0)
			(layer "F.SilkS")
			(effects
				(font
					(size 0.7 0.7)
					(thickness 0.15)
				)
				(justify right bottom)
			)
		)
		(property "Value" "LED_G_0603_KP-1608CGCK"
			(at 0 1.6 0)
			(layer "F.Fab")
			(effects
				(font
					(size 0.7 0.7)
					(thickness 0.15)
				)
				(justify right bottom)
			)
		)
		(property "Description" "LED, Green, SMD, 0603, 20 mA, 2.1 V, 570 nm"
			(at 0 0 180)
			(layer "F.Fab")
			(hide yes)
			(effects
				(font
					(size 1.27 1.27)
					(thickness 0.15)
				)
			)
		)
		(property "Author" "Antmicro"
			(at 533.2 270.8 0)
			(layer "F.Fab")
			(hide yes)
			(effects
				(font
					(size 1 1)
					(thickness 0.15)
				)
			)
		)
		(property "Color" "Green"
			(at 533.2 270.8 0)
			(layer "F.Fab")
			(hide yes)
			(effects
				(font
					(size 1 1)
					(thickness 0.15)
				)
			)
		)
		(property "License" "Apache-2.0"
			(at 533.2 270.8 0)
			(layer "F.Fab")
			(hide yes)
			(effects
				(font
					(size 1 1)
					(thickness 0.15)
				)
			)
		)
		(property "MPN" "KP-1608CGCK"
			(at 533.2 270.8 0)
			(layer "F.Fab")
			(hide yes)
			(effects
				(font
					(size 1 1)
					(thickness 0.15)
				)
			)
		)
		(property "Manufacturer" "Kingbright"
			(at 533.2 270.8 0)
			(layer "F.Fab")
			(hide yes)
			(effects
				(font
					(size 1 1)
					(thickness 0.15)
				)
			)
		)
		(sheetname "USB PHY")
		(sheetfile "usb-phy.kicad_sch")
		(attr smd)
		(fp_line
			(start 0.22 0.35)
			(end -0.22 0.35)
			(stroke
				(width 0.15)
				(type solid)
			)
			(layer "F.SilkS")
		)
		(fp_line
			(start 0.22 -0.35)
			(end -0.22 -0.35)
			(stroke
				(width 0.15)
				(type solid)
			)
			(layer "F.SilkS")
		)
		(fp_line
			(start 0.105328 0.201008)
			(end 0.105328 -0.198992)
			(stroke
				(width 0.1)
				(type solid)
			)
			(layer "F.SilkS")
		)
		(fp_line
			(start 0.105328 0.201008)
			(end -0.094672 0.001008)
			(stroke
				(width 0.1)
				(type solid)
			)
			(layer "F.SilkS")
		)
		(fp_line
			(start 0.105328 0.001008)
			(end 0.24 0.001)
			(stroke
				(width 0.1)
				(type solid)
			)
			(layer "F.SilkS")
		)
		(fp_line
			(start -0.094672 0.201008)
			(end -0.094672 -0.198992)
			(stroke
				(width 0.1)
				(type solid)
			)
			(layer "F.SilkS")
		)
		(fp_line
			(start -0.094672 0.001008)
			(end 0.105328 -0.198992)
			(stroke
				(width 0.1)
				(type solid)
			)
			(layer "F.SilkS")
		)
		(fp_line
			(start -0.094672 0.001008)
			(end -0.24 0.001008)
			(stroke
				(width 0.1)
				(type solid)
			)
			(layer "F.SilkS")
		)
		(fp_line
			(start -1.18 -0.319)
			(end -1.18 0.321)
			(stroke
				(width 0.15)
				(type solid)
			)
			(layer "F.SilkS")
		)
		(fp_rect
			(start 1.25 0.65)
			(end -1.25 -0.65)
			(stroke
				(width 0.05)
				(type solid)
			)
			(fill no)
			(layer "F.CrtYd")
		)
		(fp_line
			(start 0.599 0)
			(end 0.201 0)
			(stroke
				(width 0.15)
				(type solid)
			)
			(layer "F.Fab")
		)
		(fp_line
			(start 0.201 0.2)
			(end 0.201 0)
			(stroke
				(width 0.15)
				(type solid)
			)
			(layer "F.Fab")
		)
		(fp_line
			(start 0.201 0)
			(end 0.201 -0.202)
			(stroke
				(width 0.15)
				(type solid)
			)
			(layer "F.Fab")
		)
		(fp_line
			(start 0.201 -0.202)
			(end -0.101 0)
			(stroke
				(width 0.15)
				(type solid)
			)
			(layer "F.Fab")
		)
		(fp_line
			(start -0.101 0)
			(end 0.201 0.2)
			(stroke
				(width 0.15)
				(type solid)
			)
			(layer "F.Fab")
		)
		(fp_line
			(start -0.199 0.2)
			(end -0.199 0.1)
			(stroke
				(width 0.15)
				(type solid)
			)
			(layer "F.Fab")
		)
		(fp_line
			(start -0.199 0)
			(end -0.597 0)
			(stroke
				(width 0.15)
				(type solid)
			)
			(layer "F.Fab")
		)
		(fp_line
			(start -0.199 -0.202)
			(end -0.199 0.1)
			(stroke
				(width 0.15)
				(type solid)
			)
			(layer "F.Fab")
		)
		(fp_rect
			(start 0.848 0.4)
			(end -0.85 -0.402)
			(stroke
				(width 0.15)
				(type solid)
			)
			(fill no)
			(layer "F.Fab")
		)
		(pad "1" smd roundrect
			(at -0.7 0)
			(size 0.8 1)
			(layers "F.Cu" "F.Mask" "F.Paste")
			(roundrect_rratio 0.2)
			(net 1 "GND")
			(pinfunction "C")
			(pintype "passive")
		)
		(pad "2" smd roundrect
			(at 0.7 0)
			(size 0.8 1)
			(layers "F.Cu" "F.Mask" "F.Paste")
			(roundrect_rratio 0.2)
			(net 792 "Net-(D28-A)")
			(pinfunction "A")
			(pintype "passive")
		)
	)
	(footprint "antmicro-footprints:C_0402_1005Metric"
		(layer "F.Cu")
		(at 243.3 136.1 90)
		(descr "Capacitor SMD 0402")
		(tags "capacitor SMD 0402")
		(property "Reference" "C237"
			(at -3.7 0.375 90)
			(layer "F.SilkS")
			(effects
				(font
					(size 0.7 0.7)
					(thickness 0.15)
				)
				(justify left bottom)
			)
		)
		(property "Value" "C_100n_0402"
			(at 0 1.169 90)
			(layer "F.Fab")
			(effects
				(font
					(size 0.7 0.7)
					(thickness 0.15)
				)
				(justify left bottom)
			)
		)
		(property "Description" "SMD Multilayer Ceramic Capacitor, 0.1 µF, 50 V, 0402 [1005 Metric], ± 10%, X5R, GRM Series"
			(at 0 0 90)
			(layer "F.Fab")
			(hide yes)
			(effects
				(font
					(size 1.27 1.27)
					(thickness 0.15)
				)
			)
		)
		(property "Author" "Antmicro"
			(at 379.4 -107.2 0)
			(layer "F.Fab")
			(hide yes)
			(effects
				(font
					(size 1 1)
					(thickness 0.15)
				)
			)
		)
		(property "Dielectric" "X5R"
			(at 379.4 -107.2 0)
			(layer "F.Fab")
			(hide yes)
			(effects
				(font
					(size 1 1)
					(thickness 0.15)
				)
			)
		)
		(property "License" "Apache-2.0"
			(at 379.4 -107.2 0)
			(layer "F.Fab")
			(hide yes)
			(effects
				(font
					(size 1 1)
					(thickness 0.15)
				)
			)
		)
		(property "MPN" "GRM155R61H104KE14D"
			(at 379.4 -107.2 0)
			(layer "F.Fab")
			(hide yes)
			(effects
				(font
					(size 1 1)
					(thickness 0.15)
				)
			)
		)
		(property "Manufacturer" "Murata"
			(at 379.4 -107.2 0)
			(layer "F.Fab")
			(hide yes)
			(effects
				(font
					(size 1 1)
					(thickness 0.15)
				)
			)
		)
		(property "Val" "100n"
			(at 379.4 -107.2 0)
			(layer "F.Fab")
			(hide yes)
			(effects
				(font
					(size 1 1)
					(thickness 0.15)
				)
			)
		)
		(property "Voltage" "50V"
			(at 379.4 -107.2 0)
			(layer "F.Fab")
			(hide yes)
			(effects
				(font
					(size 1 1)
					(thickness 0.15)
				)
			)
		)
		(sheetname "USB PHY")
		(sheetfile "usb-phy.kicad_sch")
		(attr smd)
		(fp_rect
			(start -0.925 -0.47)
			(end 0.925 0.47)
			(stroke
				(width 0.05)
				(type default)
			)
			(fill no)
			(layer "F.CrtYd")
		)
		(fp_line
			(start 0.504 -0.25)
			(end 0.504 0.248)
			(stroke
				(width 0.15)
				(type solid)
			)
			(layer "F.Fab")
		)
		(fp_line
			(start -0.494 -0.25)
			(end 0.504 -0.25)
			(stroke
				(width 0.15)
				(type solid)
			)
			(layer "F.Fab")
		)
		(fp_line
			(start 0.504 0.248)
			(end -0.494 0.248)
			(stroke
				(width 0.15)
				(type solid)
			)
			(layer "F.Fab")
		)
		(fp_line
			(start -0.494 0.248)
			(end -0.494 -0.25)
			(stroke
				(width 0.15)
				(type solid)
			)
			(layer "F.Fab")
		)
		(pad "1" smd roundrect
			(at -0.48 0 90)
			(size 0.59 0.64)
			(layers "F.Cu" "F.Mask" "F.Paste")
			(roundrect_rratio 0.25)
			(net 1 "GND")
			(pintype "passive")
		)
		(pad "2" smd roundrect
			(at 0.48 0 90)
			(size 0.59 0.64)
			(layers "F.Cu" "F.Mask" "F.Paste")
			(roundrect_rratio 0.25)
			(net 707 "/USB PHY/FTDI_3V3")
			(pintype "passive")
		)
	)
	(footprint "antmicro-footprints:R_0402_1005Metric"
		(layer "F.Cu")
		(at 219.2 136.2 180)
		(descr "Resistor SMD 0402")
		(tags "resistor SMD 0402")
		(property "Reference" "R335"
			(at 3.65 -0.4 180)
			(layer "F.SilkS")
			(effects
				(font
					(size 0.7 0.7)
					(thickness 0.15)
				)
				(justify left bottom)
			)
		)
		(property "Value" "R_22R_0402"
			(at 0 1.4 180)
			(layer "F.Fab")
			(effects
				(font
					(size 0.7 0.7)
					(thickness 0.15)
				)
				(justify left bottom)
			)
		)
		(property "Description" "SMD Chip Resistor, 22 ohm, ± 1%, 62.5 mW, 0402 [1005 Metric], Thick Film, General Purpose"
			(at 0 0 180)
			(layer "F.Fab")
			(hide yes)
			(effects
				(font
					(size 1.27 1.27)
					(thickness 0.15)
				)
			)
		)
		(property "Author" "Antmicro"
			(at 438.4 272.4 0)
			(layer "F.Fab")
			(hide yes)
			(effects
				(font
					(size 1 1)
					(thickness 0.15)
				)
			)
		)
		(property "License" "Apache-2.0"
			(at 438.4 272.4 0)
			(layer "F.Fab")
			(hide yes)
			(effects
				(font
					(size 1 1)
					(thickness 0.15)
				)
			)
		)
		(property "MPN" "CR0402-FX-22R0GLF"
			(at 438.4 272.4 0)
			(layer "F.Fab")
			(hide yes)
			(effects
				(font
					(size 1 1)
					(thickness 0.15)
				)
			)
		)
		(property "Manufacturer" "Bourns"
			(at 438.4 272.4 0)
			(layer "F.Fab")
			(hide yes)
			(effects
				(font
					(size 1 1)
					(thickness 0.15)
				)
			)
		)
		(property "Tolerance" "1%"
			(at 438.4 272.4 0)
			(layer "F.Fab")
			(hide yes)
			(effects
				(font
					(size 1 1)
					(thickness 0.15)
				)
			)
		)
		(property "Val" "22R"
			(at 438.4 272.4 0)
			(layer "F.Fab")
			(hide yes)
			(effects
				(font
					(size 1 1)
					(thickness 0.15)
				)
			)
		)
		(sheetname "Clocks")
		(sheetfile "clocks.kicad_sch")
		(attr smd)
		(fp_rect
			(start -0.925 -0.47)
			(end 0.925 0.47)
			(stroke
				(width 0.05)
				(type default)
			)
			(fill no)
			(layer "F.CrtYd")
		)
		(fp_rect
			(start -0.5 -0.25)
			(end 0.5 0.25)
			(stroke
				(width 0.15)
				(type solid)
			)
			(fill no)
			(layer "F.Fab")
		)
		(pad "1" smd roundrect
			(at -0.48 0 180)
			(size 0.59 0.64)
			(layers "F.Cu" "F.Mask" "F.Paste")
			(roundrect_rratio 0.25)
			(net 971 "/Clocks/PLL_Y0")
			(pintype "passive")
		)
		(pad "2" smd roundrect
			(at 0.48 0 180)
			(size 0.59 0.64)
			(layers "F.Cu" "F.Mask" "F.Paste")
			(roundrect_rratio 0.25)
			(net 1244 "/PLL.CLK0")
			(pintype "passive")
		)
	)
	(footprint "antmicro-footprints:R_0603_1608Metric"
		(layer "F.Cu")
		(at 177.5 162.5 180)
		(descr "Resistor SMD 0603")
		(tags "resistor SMD 0603")
		(property "Reference" "R290"
			(at -1.05 -0.35 180)
			(layer "F.SilkS")
			(effects
				(font
					(size 0.7 0.7)
					(thickness 0.15)
				)
				(justify left bottom)
			)
		)
		(property "Value" "R_0R_22.4A_0603"
			(at 0 1.6 180)
			(layer "F.Fab")
			(effects
				(font
					(size 0.7 0.7)
					(thickness 0.15)
				)
				(justify left bottom)
			)
		)
		(property "Description" "SMD Chip Resistor"
			(at 0 0 180)
			(layer "F.Fab")
			(hide yes)
			(effects
				(font
					(size 1.27 1.27)
					(thickness 0.15)
				)
			)
		)
		(property "Author" "Antmicro"
			(at 355 325 0)
			(layer "F.Fab")
			(hide yes)
			(effects
				(font
					(size 1 1)
					(thickness 0.15)
				)
			)
		)
		(property "License" "Apache-2.0"
			(at 355 325 0)
			(layer "F.Fab")
			(hide yes)
			(effects
				(font
					(size 1 1)
					(thickness 0.15)
				)
			)
		)
		(property "MPN" "PMR03EZPJ000"
			(at 355 325 0)
			(layer "F.Fab")
			(hide yes)
			(effects
				(font
					(size 1 1)
					(thickness 0.15)
				)
			)
		)
		(property "Manufacturer" "ROHM Semiconductor"
			(at 355 325 0)
			(layer "F.Fab")
			(hide yes)
			(effects
				(font
					(size 1 1)
					(thickness 0.15)
				)
			)
		)
		(property "Max. Curr." "22.4A"
			(at 355 325 0)
			(layer "F.Fab")
			(hide yes)
			(effects
				(font
					(size 1 1)
					(thickness 0.15)
				)
			)
		)
		(property "Tolerance" "template_tolerance"
			(at 355 325 0)
			(layer "F.Fab")
			(hide yes)
			(effects
				(font
					(size 1 1)
					(thickness 0.15)
				)
			)
		)
		(property "Val" "0R"
			(at 355 325 0)
			(layer "F.Fab")
			(hide yes)
			(effects
				(font
					(size 1 1)
					(thickness 0.15)
				)
			)
		)
		(sheetname "DC-DC Converters")
		(sheetfile "dc-dc.kicad_sch")
		(attr smd)
		(fp_line
			(start -0.15 0.4)
			(end 0.15 0.4)
			(stroke
				(width 0.15)
				(type solid)
			)
			(layer "F.SilkS")
		)
		(fp_line
			(start -0.15 -0.4)
			(end 0.15 -0.4)
			(stroke
				(width 0.15)
				(type solid)
			)
			(layer "F.SilkS")
		)
		(fp_rect
			(start -1.25 -0.65)
			(end 1.25 0.65)
			(stroke
				(width 0.05)
				(type solid)
			)
			(fill no)
			(layer "F.CrtYd")
		)
		(fp_rect
			(start -0.8 -0.4)
			(end 0.8 0.4)
			(stroke
				(width 0.15)
				(type solid)
			)
			(fill no)
			(layer "F.Fab")
		)
		(pad "1" smd roundrect
			(at -0.7 0 180)
			(size 0.8 1)
			(layers "F.Cu" "F.Mask" "F.Paste")
			(roundrect_rratio 0.2)
			(net 736 "/DC-DC Converters/3V3_local_2")
			(pintype "passive")
		)
		(pad "2" smd roundrect
			(at 0.7 0 180)
			(size 0.8 1)
			(layers "F.Cu" "F.Mask" "F.Paste")
			(roundrect_rratio 0.2)
			(net 24 "+3V3")
			(pintype "passive")
		)
	)
	(footprint "antmicro-footprints:C_0402_1005Metric"
		(layer "F.Cu")
		(at 225.5 130.7 90)
		(descr "Capacitor SMD 0402")
		(tags "capacitor SMD 0402")
		(property "Reference" "C180"
			(at -1.6 1.3 90)
			(layer "F.SilkS")
			(effects
				(font
					(size 0.7 0.7)
					(thickness 0.15)
				)
				(justify left bottom)
			)
		)
		(property "Value" "C_10u_0402"
			(at 0 1.4 90)
			(layer "F.Fab")
			(effects
				(font
					(size 0.7 0.7)
					(thickness 0.15)
				)
				(justify left bottom)
			)
		)
		(property "Description" "SMD Multilayer Ceramic Capacitor, 10 µF, 6.3 V, 0402 [1005 Metric], ± 20%, X5R, CC Series"
			(at 0 0 90)
			(layer "F.Fab")
			(hide yes)
			(effects
				(font
					(size 1.27 1.27)
					(thickness 0.15)
				)
			)
		)
		(property "Author" "Antmicro"
			(at 356.2 -94.8 0)
			(layer "F.Fab")
			(hide yes)
			(effects
				(font
					(size 1 1)
					(thickness 0.15)
				)
			)
		)
		(property "Dielectric" ""
			(at 356.2 -94.8 0)
			(layer "F.Fab")
			(hide yes)
			(effects
				(font
					(size 1 1)
					(thickness 0.15)
				)
			)
		)
		(property "License" "Apache-2.0"
			(at 356.2 -94.8 0)
			(layer "F.Fab")
			(hide yes)
			(effects
				(font
					(size 1 1)
					(thickness 0.15)
				)
			)
		)
		(property "MPN" "CC0402MRX5R5BB106"
			(at 356.2 -94.8 0)
			(layer "F.Fab")
			(hide yes)
			(effects
				(font
					(size 1 1)
					(thickness 0.15)
				)
			)
		)
		(property "Manufacturer" "YAGEO"
			(at 356.2 -94.8 0)
			(layer "F.Fab")
			(hide yes)
			(effects
				(font
					(size 1 1)
					(thickness 0.15)
				)
			)
		)
		(property "Val" "10u"
			(at 356.2 -94.8 0)
			(layer "F.Fab")
			(hide yes)
			(effects
				(font
					(size 1 1)
					(thickness 0.15)
				)
			)
		)
		(property "Voltage" ""
			(at 356.2 -94.8 0)
			(layer "F.Fab")
			(hide yes)
			(effects
				(font
					(size 1 1)
					(thickness 0.15)
				)
			)
		)
		(sheetname "DRAM + SRAM")
		(sheetfile "ram.kicad_sch")
		(attr smd)
		(fp_rect
			(start -0.925 -0.47)
			(end 0.925 0.47)
			(stroke
				(width 0.05)
				(type default)
			)
			(fill no)
			(layer "F.CrtYd")
		)
		(fp_line
			(start 0.504 -0.25)
			(end 0.504 0.248)
			(stroke
				(width 0.15)
				(type solid)
			)
			(layer "F.Fab")
		)
		(fp_line
			(start -0.494 -0.25)
			(end 0.504 -0.25)
			(stroke
				(width 0.15)
				(type solid)
			)
			(layer "F.Fab")
		)
		(fp_line
			(start 0.504 0.248)
			(end -0.494 0.248)
			(stroke
				(width 0.15)
				(type solid)
			)
			(layer "F.Fab")
		)
		(fp_line
			(start -0.494 0.248)
			(end -0.494 -0.25)
			(stroke
				(width 0.15)
				(type solid)
			)
			(layer "F.Fab")
		)
		(pad "1" smd roundrect
			(at -0.48 0 90)
			(size 0.59 0.64)
			(layers "F.Cu" "F.Mask" "F.Paste")
			(roundrect_rratio 0.25)
			(net 1 "GND")
			(pintype "passive")
		)
		(pad "2" smd roundrect
			(at 0.48 0 90)
			(size 0.59 0.64)
			(layers "F.Cu" "F.Mask" "F.Paste")
			(roundrect_rratio 0.25)
			(net 24 "+3V3")
			(pintype "passive")
		)
	)
	(footprint "antmicro-footprints:C_0805_2012Metric"
		(layer "F.Cu")
		(at 247.9 173.8 -90)
		(descr "Capacitor SMD 0805")
		(tags "capacitor SMD 0805")
		(property "Reference" "C194"
			(at 1.75 -0.35 90)
			(layer "F.SilkS")
			(effects
				(font
					(size 0.7 0.7)
					(thickness 0.15)
				)
				(justify right bottom)
			)
		)
		(property "Value" "C_100n_100V_0805"
			(at 0 1.947 90)
			(layer "F.Fab")
			(effects
				(font
					(size 0.7 0.7)
					(thickness 0.15)
				)
				(justify right bottom)
			)
		)
		(property "Description" "SMT Multilayer Ceramic Capacitor, 0.1 µF, 100 V, 0805 [2012 Metric], ± 10%, X7R, CL"
			(at 0 0 270)
			(layer "F.Fab")
			(hide yes)
			(effects
				(font
					(size 1.27 1.27)
					(thickness 0.15)
				)
			)
		)
		(property "Author" "Antmicro"
			(at 74.1 421.7 0)
			(layer "F.Fab")
			(hide yes)
			(effects
				(font
					(size 1 1)
					(thickness 0.15)
				)
			)
		)
		(property "Dielectric" "X7R"
			(at 74.1 421.7 0)
			(layer "F.Fab")
			(hide yes)
			(effects
				(font
					(size 1 1)
					(thickness 0.15)
				)
			)
		)
		(property "License" "Apache-2.0"
			(at 74.1 421.7 0)
			(layer "F.Fab")
			(hide yes)
			(effects
				(font
					(size 1 1)
					(thickness 0.15)
				)
			)
		)
		(property "MPN" "CL21B104KCFNNNE"
			(at 74.1 421.7 0)
			(layer "F.Fab")
			(hide yes)
			(effects
				(font
					(size 1 1)
					(thickness 0.15)
				)
			)
		)
		(property "Manufacturer" "Samsung Electro-Mechanics"
			(at 74.1 421.7 0)
			(layer "F.Fab")
			(hide yes)
			(effects
				(font
					(size 1 1)
					(thickness 0.15)
				)
			)
		)
		(property "Val" "100n"
			(at 74.1 421.7 0)
			(layer "F.Fab")
			(hide yes)
			(effects
				(font
					(size 1 1)
					(thickness 0.15)
				)
			)
		)
		(property "Voltage" "100V"
			(at 74.1 421.7 0)
			(layer "F.Fab")
			(hide yes)
			(effects
				(font
					(size 1 1)
					(thickness 0.15)
				)
			)
		)
		(sheetname "Power supply")
		(sheetfile "power-supply.kicad_sch")
		(attr smd)
		(fp_line
			(start -0.3 0.7)
			(end 0.3 0.7)
			(stroke
				(width 0.15)
				(type solid)
			)
			(layer "F.SilkS")
		)
		(fp_line
			(start -0.3 -0.7)
			(end 0.3 -0.7)
			(stroke
				(width 0.15)
				(type solid)
			)
			(layer "F.SilkS")
		)
		(fp_rect
			(start 1.95 -0.9)
			(end -1.95 0.9)
			(stroke
				(width 0.05)
				(type default)
			)
			(fill no)
			(layer "F.CrtYd")
		)
		(fp_rect
			(start -0.95 -0.675)
			(end 0.95 0.675)
			(stroke
				(width 0.15)
				(type solid)
			)
			(fill no)
			(layer "F.Fab")
		)
		(pad "1" smd roundrect
			(at -1.1 0 270)
			(size 1.2 1.3)
			(layers "F.Cu" "F.Mask" "F.Paste")
			(roundrect_rratio 0.25)
			(net 697 "/Power supply/VSS")
			(pintype "passive")
		)
		(pad "2" smd roundrect
			(at 1.1 0 270)
			(size 1.2 1.3)
			(layers "F.Cu" "F.Mask" "F.Paste")
			(roundrect_rratio 0.25)
			(net 698 "/Power supply/VDD")
			(pintype "passive")
		)
	)
	(footprint "antmicro-footprints:C_0603_1608Metric"
		(layer "F.Cu")
		(at 195.6 153.849)
		(descr "Capacitor SMD 0603")
		(tags "capacitor 0603")
		(property "Reference" "C363"
			(at -3.85 0.401 0)
			(layer "F.SilkS")
			(effects
				(font
					(size 0.7 0.7)
					(thickness 0.15)
				)
				(justify left bottom)
			)
		)
		(property "Value" "C_22u_0603"
			(at 0 1.6 0)
			(layer "F.Fab")
			(effects
				(font
					(size 0.7 0.7)
					(thickness 0.15)
				)
				(justify left bottom)
			)
		)
		(property "Description" "SMD Multilayer Ceramic Capacitor, 22 µF, 6.3 V, 0603 [1608 Metric], ± 20%, X5R, GRM Series"
			(at 0 0 0)
			(layer "F.Fab")
			(hide yes)
			(effects
				(font
					(size 1.27 1.27)
					(thickness 0.15)
				)
			)
		)
		(property "Author" "Antmicro"
			(at 0 0 0)
			(layer "F.Fab")
			(hide yes)
			(effects
				(font
					(size 1 1)
					(thickness 0.15)
				)
			)
		)
		(property "Dielectric" ""
			(at 0 0 0)
			(layer "F.Fab")
			(hide yes)
			(effects
				(font
					(size 1 1)
					(thickness 0.15)
				)
			)
		)
		(property "License" "Apache-2.0"
			(at 0 0 0)
			(layer "F.Fab")
			(hide yes)
			(effects
				(font
					(size 1 1)
					(thickness 0.15)
				)
			)
		)
		(property "MPN" "GRM188R60J226MEA0D"
			(at 0 0 0)
			(layer "F.Fab")
			(hide yes)
			(effects
				(font
					(size 1 1)
					(thickness 0.15)
				)
			)
		)
		(property "Manufacturer" "Murata"
			(at 0 0 0)
			(layer "F.Fab")
			(hide yes)
			(effects
				(font
					(size 1 1)
					(thickness 0.15)
				)
			)
		)
		(property "Val" "22u"
			(at 0 0 0)
			(layer "F.Fab")
			(hide yes)
			(effects
				(font
					(size 1 1)
					(thickness 0.15)
				)
			)
		)
		(property "Voltage" ""
			(at 0 0 0)
			(layer "F.Fab")
			(hide yes)
			(effects
				(font
					(size 1 1)
					(thickness 0.15)
				)
			)
		)
		(sheetname "DC-DC Converters")
		(sheetfile "dc-dc.kicad_sch")
		(attr smd)
		(fp_line
			(start -0.15 -0.4)
			(end 0.15 -0.4)
			(stroke
				(width 0.15)
				(type solid)
			)
			(layer "F.SilkS")
		)
		(fp_line
			(start -0.15 0.4)
			(end 0.15 0.4)
			(stroke
				(width 0.15)
				(type solid)
			)
			(layer "F.SilkS")
		)
		(fp_rect
			(start -1.25 -0.65)
			(end 1.25 0.65)
			(stroke
				(width 0.05)
				(type solid)
			)
			(fill no)
			(layer "F.CrtYd")
		)
		(fp_rect
			(start -0.8 -0.4)
			(end 0.8 0.4)
			(stroke
				(width 0.15)
				(type solid)
			)
			(fill no)
			(layer "F.Fab")
		)
		(pad "1" smd roundrect
			(at -0.7 0)
			(size 0.8 1)
			(layers "F.Cu" "F.Mask" "F.Paste")
			(roundrect_rratio 0.2)
			(net 1 "GND")
			(pintype "passive")
		)
		(pad "2" smd roundrect
			(at 0.7 0)
			(size 0.8 1)
			(layers "F.Cu" "F.Mask" "F.Paste")
			(roundrect_rratio 0.2)
			(net 751 "/DC-DC Converters/1V0_REG")
			(pintype "passive")
		)
	)
	(footprint "antmicro-footprints:USB-A_Receptacle_WE_614004184726"
		(layer "F.Cu")
		(at 262.375 104.1 90)
		(descr "USB-A (USB TYPE-A) USB 2.0 Receptacle Connector 4 Position Through Hole, Right Angle")
		(property "Reference" "J12"
			(at 5.55 -1.375 180)
			(layer "F.SilkS")
			(effects
				(font
					(size 0.7 0.7)
					(thickness 0.15)
				)
				(justify left bottom)
			)
		)
		(property "Value" "USB-A_WE_614004184726"
			(at 3.7 8.2 180)
			(layer "F.Fab")
			(effects
				(font
					(size 0.7 0.7)
					(thickness 0.15)
				)
				(justify left bottom)
			)
		)
		(property "Description" "USB-A (USB TYPE-A) USB 2.0 Receptacle Connector 4 Position Through Hole, Right Angle"
			(at 0 0 90)
			(layer "F.Fab")
			(hide yes)
			(effects
				(font
					(size 1.27 1.27)
					(thickness 0.15)
				)
			)
		)
		(property "Author" "Antmicro"
			(at 366.475 -158.275 0)
			(layer "F.Fab")
			(hide yes)
			(effects
				(font
					(size 1 1)
					(thickness 0.15)
				)
			)
		)
		(property "License" "Apache-2.0"
			(at 366.475 -158.275 0)
			(layer "F.Fab")
			(hide yes)
			(effects
				(font
					(size 1 1)
					(thickness 0.15)
				)
			)
		)
		(property "MPN" "614004184726"
			(at 366.475 -158.275 0)
			(layer "F.Fab")
			(hide yes)
			(effects
				(font
					(size 1 1)
					(thickness 0.15)
				)
			)
		)
		(property "Manufacturer" "Würth Elektronik"
			(at 366.475 -158.275 0)
			(layer "F.Fab")
			(hide yes)
			(effects
				(font
					(size 1 1)
					(thickness 0.15)
				)
			)
		)
		(sheetname "USB PHY")
		(sheetfile "usb-phy.kicad_sch")
		(attr through_hole)
		(fp_line
			(start 5.31 -1.25)
			(end 5.31 0.498)
			(stroke
				(width 0.15)
				(type solid)
			)
			(layer "F.SilkS")
		)
		(fp_line
			(start -1.111 -1.25)
			(end 5.31 -1.25)
			(stroke
				(width 0.15)
				(type solid)
			)
			(layer "F.SilkS")
		)
		(fp_line
			(start -1.111 0.498)
			(end -1.111 -1.25)
			(stroke
				(width 0.15)
				(type solid)
			)
			(layer "F.SilkS")
		)
		(fp_line
			(start -1.111 4.498)
			(end -1.111 9.499)
			(stroke
				(width 0.15)
				(type solid)
			)
			(layer "F.SilkS")
		)
		(fp_line
			(start 5.31 9.499)
			(end 5.31 4.498)
			(stroke
				(width 0.15)
				(type solid)
			)
			(layer "F.SilkS")
		)
		(fp_line
			(start -1.111 9.499)
			(end 5.31 9.499)
			(stroke
				(width 0.15)
				(type solid)
			)
			(layer "F.SilkS")
		)
		(fp_circle
			(center -0.45 -1.527)
			(end -0.4 -1.527)
			(stroke
				(width 0.15)
				(type solid)
			)
			(fill yes)
			(layer "F.SilkS")
		)
		(fp_rect
			(start -1.55 -1.577)
			(end 5.76 10.425)
			(stroke
				(width 0.05)
				(type solid)
			)
			(fill no)
			(layer "F.CrtYd")
		)
		(fp_line
			(start 5.31 -1.25)
			(end -1.111 -1.25)
			(stroke
				(width 0.15)
				(type solid)
			)
			(layer "F.Fab")
		)
		(fp_line
			(start -1.111 -1.25)
			(end -1.111 9.499)
			(stroke
				(width 0.15)
				(type solid)
			)
			(layer "F.Fab")
		)
		(fp_line
			(start -1.121 -1.01)
			(end -0.88 -1.25)
			(stroke
				(width 0.15)
				(type solid)
			)
			(layer "F.Fab")
		)
		(fp_line
			(start 5.31 9.499)
			(end 5.31 -1.25)
			(stroke
				(width 0.15)
				(type solid)
			)
			(layer "F.Fab")
		)
		(fp_line
			(start -1.111 9.499)
			(end 5.31 9.499)
			(stroke
				(width 0.15)
				(type solid)
			)
			(layer "F.Fab")
		)
		(pad "1" thru_hole circle
			(at 0 0 90)
			(size 1.25 1.25)
			(drill 0.92)
			(layers "*.Cu" "*.Mask")
			(remove_unused_layers no)
			(net 705 "/USB PHY/USB_HOST_VBUS")
			(pinfunction "VBUS")
			(pintype "passive")
		)
		(pad "2" thru_hole circle
			(at 1.4 0 90)
			(size 1.25 1.25)
			(drill 0.92)
			(layers "*.Cu" "*.Mask")
			(remove_unused_layers no)
			(net 835 "/USB PHY/USB_HOST_CONN_D-")
			(pinfunction "D-")
			(pintype "bidirectional")
		)
		(pad "3" thru_hole circle
			(at 2.798 0 90)
			(size 1.25 1.25)
			(drill 0.92)
			(layers "*.Cu" "*.Mask")
			(remove_unused_layers no)
			(net 836 "/USB PHY/USB_HOST_CONN_D+")
			(pinfunction "D+")
			(pintype "bidirectional")
		)
		(pad "4" thru_hole circle
			(at 4.2 0 90)
			(size 1.25 1.25)
			(drill 0.92)
			(layers "*.Cu" "*.Mask")
			(remove_unused_layers no)
			(net 1 "GND")
			(pinfunction "GND")
			(pintype "power_in")
		)
		(pad "SH" thru_hole roundrect
			(at -0.651 2.499 90)
			(size 1.8 3.3)
			(drill oval 1.2 2.5)
			(layers "*.Cu" "*.Mask")
			(remove_unused_layers no)
			(roundrect_rratio 0.25)
			(net 1 "GND")
			(pinfunction "SH")
			(pintype "passive")
		)
		(pad "SH" thru_hole roundrect
			(at 2.1 5.599 90)
			(size 1.5 2)
			(drill oval 1 1.5)
			(layers "*.Cu" "*.Mask")
			(remove_unused_layers no)
			(roundrect_rratio 0.25)
			(net 1 "GND")
			(pinfunction "SH")
			(pintype "passive")
		)
		(pad "SH" thru_hole roundrect
			(at 4.849 2.499 90)
			(size 1.8 3.3)
			(drill oval 1.2 2.5)
			(layers "*.Cu" "*.Mask")
			(remove_unused_layers no)
			(roundrect_rratio 0.25)
			(net 1 "GND")
			(pinfunction "SH")
			(pintype "passive")
		)
	)
	(footprint "antmicro-footprints:R_0402_1005Metric"
		(layer "F.Cu")
		(at 250.399 99.5 90)
		(descr "Resistor SMD 0402")
		(tags "resistor SMD 0402")
		(property "Reference" "R346"
			(at -3 -0.449 90)
			(layer "F.SilkS")
			(effects
				(font
					(size 0.7 0.7)
					(thickness 0.15)
				)
				(justify left bottom)
			)
		)
		(property "Value" "R_12k_0402"
			(at 0 1.4 90)
			(layer "F.Fab")
			(effects
				(font
					(size 0.7 0.7)
					(thickness 0.15)
				)
				(justify left bottom)
			)
		)
		(property "Description" "SMD Chip Resistor, 12 kohm, ± 1%, 62.5 mW, 0402 [1005 Metric], Thick Film, General Purpose"
			(at 0 0 90)
			(layer "F.Fab")
			(hide yes)
			(effects
				(font
					(size 1.27 1.27)
					(thickness 0.15)
				)
			)
		)
		(property "Author" "Antmicro"
			(at 349.899 -150.899 0)
			(layer "F.Fab")
			(hide yes)
			(effects
				(font
					(size 1 1)
					(thickness 0.15)
				)
			)
		)
		(property "License" "Apache-2.0"
			(at 349.899 -150.899 0)
			(layer "F.Fab")
			(hide yes)
			(effects
				(font
					(size 1 1)
					(thickness 0.15)
				)
			)
		)
		(property "MPN" "CR0402-FX-1202GLF"
			(at 349.899 -150.899 0)
			(layer "F.Fab")
			(hide yes)
			(effects
				(font
					(size 1 1)
					(thickness 0.15)
				)
			)
		)
		(property "Manufacturer" "Bourns"
			(at 349.899 -150.899 0)
			(layer "F.Fab")
			(hide yes)
			(effects
				(font
					(size 1 1)
					(thickness 0.15)
				)
			)
		)
		(property "Tolerance" "1%"
			(at 349.899 -150.899 0)
			(layer "F.Fab")
			(hide yes)
			(effects
				(font
					(size 1 1)
					(thickness 0.15)
				)
			)
		)
		(property "Val" "12k"
			(at 349.899 -150.899 0)
			(layer "F.Fab")
			(hide yes)
			(effects
				(font
					(size 1 1)
					(thickness 0.15)
				)
			)
		)
		(sheetname "USB PHY")
		(sheetfile "usb-phy.kicad_sch")
		(attr smd)
		(fp_rect
			(start -0.925 -0.47)
			(end 0.925 0.47)
			(stroke
				(width 0.05)
				(type default)
			)
			(fill no)
			(layer "F.CrtYd")
		)
		(fp_rect
			(start -0.5 -0.25)
			(end 0.5 0.25)
			(stroke
				(width 0.15)
				(type solid)
			)
			(fill no)
			(layer "F.Fab")
		)
		(pad "1" smd roundrect
			(at -0.48 0 90)
			(size 0.59 0.64)
			(layers "F.Cu" "F.Mask" "F.Paste")
			(roundrect_rratio 0.25)
			(net 1 "GND")
			(pintype "passive")
		)
		(pad "2" smd roundrect
			(at 0.48 0 90)
			(size 0.59 0.64)
			(layers "F.Cu" "F.Mask" "F.Paste")
			(roundrect_rratio 0.25)
			(net 382 "Net-(U30-ISET)")
			(pintype "passive")
		)
	)
	(footprint "antmicro-footprints:R_0402_1005Metric"
		(layer "F.Cu")
		(at 213.9 154.71 -90)
		(descr "Resistor SMD 0402")
		(tags "resistor SMD 0402")
		(property "Reference" "R81"
			(at -0.96 0.4 270)
			(layer "F.SilkS")
			(effects
				(font
					(size 0.7 0.7)
					(thickness 0.15)
				)
				(justify left bottom)
			)
		)
		(property "Value" "R_0R_0402"
			(at 0 1.4 270)
			(layer "F.Fab")
			(effects
				(font
					(size 0.7 0.7)
					(thickness 0.15)
				)
				(justify left bottom)
			)
		)
		(property "Description" "SMD Chip Resistor, Jumper, 0 ohm, 100 mW, 0402 [1005 Metric], Thick Film, General Purpose"
			(at 0 0 270)
			(layer "F.Fab")
			(hide yes)
			(effects
				(font
					(size 1.27 1.27)
					(thickness 0.15)
				)
			)
		)
		(property "Author" "Antmicro"
			(at 59.19 368.61 0)
			(layer "F.Fab")
			(hide yes)
			(effects
				(font
					(size 1 1)
					(thickness 0.15)
				)
			)
		)
		(property "Current" "1A"
			(at 59.19 368.61 0)
			(layer "F.Fab")
			(hide yes)
			(effects
				(font
					(size 1 1)
					(thickness 0.15)
				)
			)
		)
		(property "License" "Apache-2.0"
			(at 59.19 368.61 0)
			(layer "F.Fab")
			(hide yes)
			(effects
				(font
					(size 1 1)
					(thickness 0.15)
				)
			)
		)
		(property "MPN" "ERJ2GE0R00X"
			(at 59.19 368.61 0)
			(layer "F.Fab")
			(hide yes)
			(effects
				(font
					(size 1 1)
					(thickness 0.15)
				)
			)
		)
		(property "Manufacturer" "Panasonic"
			(at 59.19 368.61 0)
			(layer "F.Fab")
			(hide yes)
			(effects
				(font
					(size 1 1)
					(thickness 0.15)
				)
			)
		)
		(property "Tolerance" ""
			(at 59.19 368.61 0)
			(layer "F.Fab")
			(hide yes)
			(effects
				(font
					(size 1 1)
					(thickness 0.15)
				)
			)
		)
		(property "Val" "0R"
			(at 59.19 368.61 0)
			(layer "F.Fab")
			(hide yes)
			(effects
				(font
					(size 1 1)
					(thickness 0.15)
				)
			)
		)
		(sheetname "SPI Flash + SD Card")
		(sheetfile "spi-flash.kicad_sch")
		(attr smd)
		(fp_rect
			(start -0.925 -0.47)
			(end 0.925 0.47)
			(stroke
				(width 0.05)
				(type default)
			)
			(fill no)
			(layer "F.CrtYd")
		)
		(fp_rect
			(start -0.5 -0.25)
			(end 0.5 0.25)
			(stroke
				(width 0.15)
				(type solid)
			)
			(fill no)
			(layer "F.Fab")
		)
		(pad "1" smd roundrect
			(at -0.48 0 270)
			(size 0.59 0.64)
			(layers "F.Cu" "F.Mask" "F.Paste")
			(roundrect_rratio 0.25)
			(net 408 "/FPGA Bank 33 & 34/USR_FLASH_0.CLK")
			(pintype "passive")
		)
		(pad "2" smd roundrect
			(at 0.48 0 270)
			(size 0.59 0.64)
			(layers "F.Cu" "F.Mask" "F.Paste")
			(roundrect_rratio 0.25)
			(net 901 "/SPI Flash + SD Card/USR_FLASH_0_CLK")
			(pintype "passive")
		)
	)
	(footprint "antmicro-footprints:C_0402_1005Metric"
		(layer "F.Cu")
		(at 233.7 150.9)
		(descr "Capacitor SMD 0402")
		(tags "capacitor SMD 0402")
		(property "Reference" "C246"
			(at -1.85 1.2 0)
			(layer "F.SilkS")
			(effects
				(font
					(size 0.7 0.7)
					(thickness 0.15)
				)
				(justify left bottom)
			)
		)
		(property "Value" "C_100n_0402"
			(at 0 1.169 0)
			(layer "F.Fab")
			(effects
				(font
					(size 0.7 0.7)
					(thickness 0.15)
				)
				(justify left bottom)
			)
		)
		(property "Description" "SMD Multilayer Ceramic Capacitor, 0.1 µF, 50 V, 0402 [1005 Metric], ± 10%, X5R, GRM Series"
			(at 0 0 0)
			(layer "F.Fab")
			(hide yes)
			(effects
				(font
					(size 1.27 1.27)
					(thickness 0.15)
				)
			)
		)
		(property "Author" "Antmicro"
			(at 0 0 0)
			(layer "F.Fab")
			(hide yes)
			(effects
				(font
					(size 1 1)
					(thickness 0.15)
				)
			)
		)
		(property "Dielectric" "X5R"
			(at 0 0 0)
			(layer "F.Fab")
			(hide yes)
			(effects
				(font
					(size 1 1)
					(thickness 0.15)
				)
			)
		)
		(property "License" "Apache-2.0"
			(at 0 0 0)
			(layer "F.Fab")
			(hide yes)
			(effects
				(font
					(size 1 1)
					(thickness 0.15)
				)
			)
		)
		(property "MPN" "GRM155R61H104KE14D"
			(at 0 0 0)
			(layer "F.Fab")
			(hide yes)
			(effects
				(font
					(size 1 1)
					(thickness 0.15)
				)
			)
		)
		(property "Manufacturer" "Murata"
			(at 0 0 0)
			(layer "F.Fab")
			(hide yes)
			(effects
				(font
					(size 1 1)
					(thickness 0.15)
				)
			)
		)
		(property "Val" "100n"
			(at 0 0 0)
			(layer "F.Fab")
			(hide yes)
			(effects
				(font
					(size 1 1)
					(thickness 0.15)
				)
			)
		)
		(property "Voltage" "50V"
			(at 0 0 0)
			(layer "F.Fab")
			(hide yes)
			(effects
				(font
					(size 1 1)
					(thickness 0.15)
				)
			)
		)
		(sheetname "USB PHY")
		(sheetfile "usb-phy.kicad_sch")
		(attr smd)
		(fp_rect
			(start -0.925 -0.47)
			(end 0.925 0.47)
			(stroke
				(width 0.05)
				(type default)
			)
			(fill no)
			(layer "F.CrtYd")
		)
		(fp_line
			(start -0.494 -0.25)
			(end 0.504 -0.25)
			(stroke
				(width 0.15)
				(type solid)
			)
			(layer "F.Fab")
		)
		(fp_line
			(start -0.494 0.248)
			(end -0.494 -0.25)
			(stroke
				(width 0.15)
				(type solid)
			)
			(layer "F.Fab")
		)
		(fp_line
			(start 0.504 -0.25)
			(end 0.504 0.248)
			(stroke
				(width 0.15)
				(type solid)
			)
			(layer "F.Fab")
		)
		(fp_line
			(start 0.504 0.248)
			(end -0.494 0.248)
			(stroke
				(width 0.15)
				(type solid)
			)
			(layer "F.Fab")
		)
		(pad "1" smd roundrect
			(at -0.48 0)
			(size 0.59 0.64)
			(layers "F.Cu" "F.Mask" "F.Paste")
			(roundrect_rratio 0.25)
			(net 1 "GND")
			(pintype "passive")
		)
		(pad "2" smd roundrect
			(at 0.48 0)
			(size 0.59 0.64)
			(layers "F.Cu" "F.Mask" "F.Paste")
			(roundrect_rratio 0.25)
			(net 26 "+1V8")
			(pintype "passive")
		)
	)
	(footprint "antmicro-footprints:C_0402_1005Metric"
		(layer "F.Cu")
		(at 198.951 104.199 -90)
		(descr "Capacitor SMD 0402")
		(tags "capacitor SMD 0402")
		(property "Reference" "C220"
			(at -3.599 -0.349 270)
			(layer "F.SilkS")
			(effects
				(font
					(size 0.7 0.7)
					(thickness 0.15)
				)
				(justify right bottom)
			)
		)
		(property "Value" "C_22p_0402"
			(at 0 1.4 90)
			(layer "F.Fab")
			(effects
				(font
					(size 0.7 0.7)
					(thickness 0.15)
				)
				(justify right bottom)
			)
		)
		(property "Description" "SMD Multilayer Ceramic Capacitor, 22 pF, 50 V, 0402 [1005 Metric], ± 5%, C0G / NP0, CC Series"
			(at 0 0 270)
			(layer "F.Fab")
			(hide yes)
			(effects
				(font
					(size 1.27 1.27)
					(thickness 0.15)
				)
			)
		)
		(property "Author" "Antmicro"
			(at 94.752 303.15 0)
			(layer "F.Fab")
			(hide yes)
			(effects
				(font
					(size 1 1)
					(thickness 0.15)
				)
			)
		)
		(property "Dielectric" ""
			(at 94.752 303.15 0)
			(layer "F.Fab")
			(hide yes)
			(effects
				(font
					(size 1 1)
					(thickness 0.15)
				)
			)
		)
		(property "License" "Apache-2.0"
			(at 94.752 303.15 0)
			(layer "F.Fab")
			(hide yes)
			(effects
				(font
					(size 1 1)
					(thickness 0.15)
				)
			)
		)
		(property "MPN" "CC0402JRNPO9BN220"
			(at 94.752 303.15 0)
			(layer "F.Fab")
			(hide yes)
			(effects
				(font
					(size 1 1)
					(thickness 0.15)
				)
			)
		)
		(property "Manufacturer" "YAGEO"
			(at 94.752 303.15 0)
			(layer "F.Fab")
			(hide yes)
			(effects
				(font
					(size 1 1)
					(thickness 0.15)
				)
			)
		)
		(property "Val" "22p"
			(at 94.752 303.15 0)
			(layer "F.Fab")
			(hide yes)
			(effects
				(font
					(size 1 1)
					(thickness 0.15)
				)
			)
		)
		(property "Voltage" ""
			(at 94.752 303.15 0)
			(layer "F.Fab")
			(hide yes)
			(effects
				(font
					(size 1 1)
					(thickness 0.15)
				)
			)
		)
		(sheetname "USB PHY")
		(sheetfile "usb-phy.kicad_sch")
		(attr smd)
		(fp_rect
			(start -0.925 -0.47)
			(end 0.925 0.47)
			(stroke
				(width 0.05)
				(type default)
			)
			(fill no)
			(layer "F.CrtYd")
		)
		(fp_line
			(start -0.494 0.248)
			(end -0.494 -0.25)
			(stroke
				(width 0.15)
				(type solid)
			)
			(layer "F.Fab")
		)
		(fp_line
			(start 0.504 0.248)
			(end -0.494 0.248)
			(stroke
				(width 0.15)
				(type solid)
			)
			(layer "F.Fab")
		)
		(fp_line
			(start -0.494 -0.25)
			(end 0.504 -0.25)
			(stroke
				(width 0.15)
				(type solid)
			)
			(layer "F.Fab")
		)
		(fp_line
			(start 0.504 -0.25)
			(end 0.504 0.248)
			(stroke
				(width 0.15)
				(type solid)
			)
			(layer "F.Fab")
		)
		(pad "1" smd roundrect
			(at -0.48 0 270)
			(size 0.59 0.64)
			(layers "F.Cu" "F.Mask" "F.Paste")
			(roundrect_rratio 0.25)
			(net 1 "GND")
			(pintype "passive")
		)
		(pad "2" smd roundrect
			(at 0.48 0 270)
			(size 0.59 0.64)
			(layers "F.Cu" "F.Mask" "F.Paste")
			(roundrect_rratio 0.25)
			(net 706 "/USB PHY/USB_HOST_XI")
			(pintype "passive")
		)
	)
	(footprint "antmicro-footprints:C_0402_1005Metric"
		(layer "F.Cu")
		(at 254.445 137.935 180)
		(descr "Capacitor SMD 0402")
		(tags "capacitor SMD 0402")
		(property "Reference" "C239"
			(at 1.4 4.9 180)
			(layer "F.SilkS")
			(effects
				(font
					(size 0.7 0.7)
					(thickness 0.15)
				)
				(justify left bottom)
			)
		)
		(property "Value" "C_100n_0402"
			(at 0 1.169 180)
			(layer "F.Fab")
			(effects
				(font
					(size 0.7 0.7)
					(thickness 0.15)
				)
				(justify left bottom)
			)
		)
		(property "Description" "SMD Multilayer Ceramic Capacitor, 0.1 µF, 50 V, 0402 [1005 Metric], ± 10%, X5R, GRM Series"
			(at 0 0 180)
			(layer "F.Fab")
			(hide yes)
			(effects
				(font
					(size 1.27 1.27)
					(thickness 0.15)
				)
			)
		)
		(property "Author" "Antmicro"
			(at 508.89 275.87 0)
			(layer "F.Fab")
			(hide yes)
			(effects
				(font
					(size 1 1)
					(thickness 0.15)
				)
			)
		)
		(property "Dielectric" "X5R"
			(at 508.89 275.87 0)
			(layer "F.Fab")
			(hide yes)
			(effects
				(font
					(size 1 1)
					(thickness 0.15)
				)
			)
		)
		(property "License" "Apache-2.0"
			(at 508.89 275.87 0)
			(layer "F.Fab")
			(hide yes)
			(effects
				(font
					(size 1 1)
					(thickness 0.15)
				)
			)
		)
		(property "MPN" "GRM155R61H104KE14D"
			(at 508.89 275.87 0)
			(layer "F.Fab")
			(hide yes)
			(effects
				(font
					(size 1 1)
					(thickness 0.15)
				)
			)
		)
		(property "Manufacturer" "Murata"
			(at 508.89 275.87 0)
			(layer "F.Fab")
			(hide yes)
			(effects
				(font
					(size 1 1)
					(thickness 0.15)
				)
			)
		)
		(property "Val" "100n"
			(at 508.89 275.87 0)
			(layer "F.Fab")
			(hide yes)
			(effects
				(font
					(size 1 1)
					(thickness 0.15)
				)
			)
		)
		(property "Voltage" "50V"
			(at 508.89 275.87 0)
			(layer "F.Fab")
			(hide yes)
			(effects
				(font
					(size 1 1)
					(thickness 0.15)
				)
			)
		)
		(sheetname "USB PHY")
		(sheetfile "usb-phy.kicad_sch")
		(attr smd)
		(fp_rect
			(start -0.925 -0.47)
			(end 0.925 0.47)
			(stroke
				(width 0.05)
				(type default)
			)
			(fill no)
			(layer "F.CrtYd")
		)
		(fp_line
			(start 0.504 0.248)
			(end -0.494 0.248)
			(stroke
				(width 0.15)
				(type solid)
			)
			(layer "F.Fab")
		)
		(fp_line
			(start 0.504 -0.25)
			(end 0.504 0.248)
			(stroke
				(width 0.15)
				(type solid)
			)
			(layer "F.Fab")
		)
		(fp_line
			(start -0.494 0.248)
			(end -0.494 -0.25)
			(stroke
				(width 0.15)
				(type solid)
			)
			(layer "F.Fab")
		)
		(fp_line
			(start -0.494 -0.25)
			(end 0.504 -0.25)
			(stroke
				(width 0.15)
				(type solid)
			)
			(layer "F.Fab")
		)
		(pad "1" smd roundrect
			(at -0.48 0 180)
			(size 0.59 0.64)
			(layers "F.Cu" "F.Mask" "F.Paste")
			(roundrect_rratio 0.25)
			(net 1 "GND")
			(pintype "passive")
		)
		(pad "2" smd roundrect
			(at 0.48 0 180)
			(size 0.59 0.64)
			(layers "F.Cu" "F.Mask" "F.Paste")
			(roundrect_rratio 0.25)
			(net 714 "/USB PHY/FTDI_VPHY")
			(pintype "passive")
		)
	)
	(footprint "antmicro-footprints:R_0402_1005Metric"
		(layer "F.Cu")
		(at 218.8 165.7)
		(descr "Resistor SMD 0402")
		(tags "resistor SMD 0402")
		(property "Reference" "R8"
			(at -2.25 0.4 0)
			(layer "F.SilkS")
			(effects
				(font
					(size 0.7 0.7)
					(thickness 0.15)
				)
				(justify left bottom)
			)
		)
		(property "Value" "R_10k_0402"
			(at 0 1.4 0)
			(layer "F.Fab")
			(effects
				(font
					(size 0.7 0.7)
					(thickness 0.15)
				)
				(justify left bottom)
			)
		)
		(property "Description" "SMD Chip Resistor, 10 kohm, ± 1%, 62.5 mW, 0402 [1005 Metric], Thick Film, General Purpose"
			(at 0 0 0)
			(layer "F.Fab")
			(hide yes)
			(effects
				(font
					(size 1.27 1.27)
					(thickness 0.15)
				)
			)
		)
		(property "Author" "Antmicro"
			(at 0 0 0)
			(layer "F.Fab")
			(hide yes)
			(effects
				(font
					(size 1 1)
					(thickness 0.15)
				)
			)
		)
		(property "License" "Apache-2.0"
			(at 0 0 0)
			(layer "F.Fab")
			(hide yes)
			(effects
				(font
					(size 1 1)
					(thickness 0.15)
				)
			)
		)
		(property "MPN" "CR0402-FX-1002GLF"
			(at 0 0 0)
			(layer "F.Fab")
			(hide yes)
			(effects
				(font
					(size 1 1)
					(thickness 0.15)
				)
			)
		)
		(property "Manufacturer" "Bourns"
			(at 0 0 0)
			(layer "F.Fab")
			(hide yes)
			(effects
				(font
					(size 1 1)
					(thickness 0.15)
				)
			)
		)
		(property "Tolerance" "1%"
			(at 0 0 0)
			(layer "F.Fab")
			(hide yes)
			(effects
				(font
					(size 1 1)
					(thickness 0.15)
				)
			)
		)
		(property "Val" "10k"
			(at 0 0 0)
			(layer "F.Fab")
			(hide yes)
			(effects
				(font
					(size 1 1)
					(thickness 0.15)
				)
			)
		)
		(sheetname "FPGA Config")
		(sheetfile "fpga-config.kicad_sch")
		(attr smd)
		(fp_rect
			(start -0.925 -0.47)
			(end 0.925 0.47)
			(stroke
				(width 0.05)
				(type default)
			)
			(fill no)
			(layer "F.CrtYd")
		)
		(fp_rect
			(start -0.5 -0.25)
			(end 0.5 0.25)
			(stroke
				(width 0.15)
				(type solid)
			)
			(fill no)
			(layer "F.Fab")
		)
		(pad "1" smd roundrect
			(at -0.48 0)
			(size 0.59 0.64)
			(layers "F.Cu" "F.Mask" "F.Paste")
			(roundrect_rratio 0.25)
			(net 345 "Net-(U3-STBY)")
			(pintype "passive")
		)
		(pad "2" smd roundrect
			(at 0.48 0)
			(size 0.59 0.64)
			(layers "F.Cu" "F.Mask" "F.Paste")
			(roundrect_rratio 0.25)
			(net 24 "+3V3")
			(pintype "passive")
		)
	)
	(footprint "antmicro-footprints:R_Array_4x0201_Panasonic_EXB18V"
		(layer "F.Cu")
		(at 251.9 144.302)
		(property "Reference" "R281"
			(at -17.35 -39.002 0)
			(layer "F.SilkS")
			(effects
				(font
					(size 0.7 0.7)
					(thickness 0.15)
				)
				(justify right bottom)
			)
		)
		(property "Value" "R_4x33R_0201_array"
			(at -1.1 1.8 0)
			(layer "F.Fab")
			(effects
				(font
					(size 0.7 0.7)
					(thickness 0.15)
				)
				(justify left bottom)
			)
		)
		(property "Description" "Fixed Network Resistor, 33 ohm, Isolated, 4 Resistors, 0502 [1406 Metric], Flat, ± 5%"
			(at 0 0 0)
			(layer "F.Fab")
			(hide yes)
			(effects
				(font
					(size 1.27 1.27)
					(thickness 0.15)
				)
			)
		)
		(property "Author" "Antmicro"
			(at 0 0 0)
			(layer "F.Fab")
			(hide yes)
			(effects
				(font
					(size 1 1)
					(thickness 0.15)
				)
			)
		)
		(property "License" "Apache-2.0"
			(at 0 0 0)
			(layer "F.Fab")
			(hide yes)
			(effects
				(font
					(size 1 1)
					(thickness 0.15)
				)
			)
		)
		(property "MPN" "EXB-18V330JX"
			(at 0 0 0)
			(layer "F.Fab")
			(hide yes)
			(effects
				(font
					(size 1 1)
					(thickness 0.15)
				)
			)
		)
		(property "Manufacturer" "Panasonic"
			(at 0 0 0)
			(layer "F.Fab")
			(hide yes)
			(effects
				(font
					(size 1 1)
					(thickness 0.15)
				)
			)
		)
		(property "Val" "R_4x33R_0201"
			(at 0 0 0)
			(layer "F.Fab")
			(hide yes)
			(effects
				(font
					(size 1 1)
					(thickness 0.15)
				)
			)
		)
		(sheetname "Supervisior MCU")
		(sheetfile "supervisor-mcu.kicad_sch")
		(attr smd)
		(fp_line
			(start -0.8 -0.45)
			(end -0.8 0.45)
			(stroke
				(width 0.12)
				(type solid)
			)
			(layer "F.SilkS")
		)
		(fp_line
			(start 0.8 -0.45)
			(end 0.8 0.45)
			(stroke
				(width 0.12)
				(type solid)
			)
			(layer "F.SilkS")
		)
		(fp_rect
			(start -0.898 -0.66)
			(end 0.898 0.65)
			(stroke
				(width 0.05)
				(type solid)
			)
			(fill no)
			(layer "F.CrtYd")
		)
		(pad "1" smd roundrect
			(at -0.6 0.298)
			(size 0.2 0.4)
			(layers "F.Cu" "F.Mask" "F.Paste")
			(roundrect_rratio 0.25)
			(net 1085 "/Supervisior MCU/PGOOD_VCCINT")
			(pinfunction "R1.1")
			(pintype "passive")
		)
		(pad "2" smd roundrect
			(at -0.202 0.298)
			(size 0.2 0.4)
			(layers "F.Cu" "F.Mask" "F.Paste")
			(roundrect_rratio 0.25)
			(net 1107 "/Supervisior MCU/USB_C_PD_RST")
			(pinfunction "R2.1")
			(pintype "passive")
		)
		(pad "3" smd roundrect
			(at 0.2 0.298)
			(size 0.2 0.4)
			(layers "F.Cu" "F.Mask" "F.Paste")
			(roundrect_rratio 0.25)
			(net 955 "/Supervisior MCU/FPGA_COPI")
			(pinfunction "R3.1")
			(pintype "passive")
		)
		(pad "4" smd roundrect
			(at 0.598 0.298)
			(size 0.2 0.4)
			(layers "F.Cu" "F.Mask" "F.Paste")
			(roundrect_rratio 0.25)
			(net 1100 "/Supervisior MCU/USB_WR")
			(pinfunction "R4.1")
			(pintype "passive")
		)
		(pad "5" smd roundrect
			(at 0.598 -0.3)
			(size 0.2 0.4)
			(layers "F.Cu" "F.Mask" "F.Paste")
			(roundrect_rratio 0.25)
			(net 1388 "/SUP_MCU.WR")
			(pinfunction "R4.2")
			(pintype "passive")
		)
		(pad "6" smd roundrect
			(at 0.2 -0.3)
			(size 0.2 0.4)
			(layers "F.Cu" "F.Mask" "F.Paste")
			(roundrect_rratio 0.25)
			(net 1327 "/SUP_MCU.FPGA_MOSI")
			(pinfunction "R3.2")
			(pintype "passive")
		)
		(pad "7" smd roundrect
			(at -0.202 -0.3)
			(size 0.2 0.4)
			(layers "F.Cu" "F.Mask" "F.Paste")
			(roundrect_rratio 0.25)
			(net 1349 "/SUP_MCU.PD_RST")
			(pinfunction "R2.2")
			(pintype "passive")
		)
		(pad "8" smd roundrect
			(at -0.6 -0.3)
			(size 0.2 0.4)
			(layers "F.Cu" "F.Mask" "F.Paste")
			(roundrect_rratio 0.25)
			(net 1389 "/SUP_MCU.PG_VCCINT")
			(pinfunction "R1.2")
			(pintype "passive")
		)
	)
	(footprint "antmicro-footprints:C_0402_1005Metric"
		(layer "F.Cu")
		(at 240.3 133.3 180)
		(descr "Capacitor SMD 0402")
		(tags "capacitor SMD 0402")
		(property "Reference" "C248"
			(at -3.3 3.125 180)
			(layer "F.SilkS")
			(effects
				(font
					(size 0.7 0.7)
					(thickness 0.15)
				)
				(justify left bottom)
			)
		)
		(property "Value" "C_100n_0402"
			(at 0 1.169 180)
			(layer "F.Fab")
			(effects
				(font
					(size 0.7 0.7)
					(thickness 0.15)
				)
				(justify left bottom)
			)
		)
		(property "Description" "SMD Multilayer Ceramic Capacitor, 0.1 µF, 50 V, 0402 [1005 Metric], ± 10%, X5R, GRM Series"
			(at 0 0 180)
			(layer "F.Fab")
			(hide yes)
			(effects
				(font
					(size 1.27 1.27)
					(thickness 0.15)
				)
			)
		)
		(property "Author" "Antmicro"
			(at 480.6 266.6 0)
			(layer "F.Fab")
			(hide yes)
			(effects
				(font
					(size 1 1)
					(thickness 0.15)
				)
			)
		)
		(property "Dielectric" "X5R"
			(at 480.6 266.6 0)
			(layer "F.Fab")
			(hide yes)
			(effects
				(font
					(size 1 1)
					(thickness 0.15)
				)
			)
		)
		(property "License" "Apache-2.0"
			(at 480.6 266.6 0)
			(layer "F.Fab")
			(hide yes)
			(effects
				(font
					(size 1 1)
					(thickness 0.15)
				)
			)
		)
		(property "MPN" "GRM155R61H104KE14D"
			(at 480.6 266.6 0)
			(layer "F.Fab")
			(hide yes)
			(effects
				(font
					(size 1 1)
					(thickness 0.15)
				)
			)
		)
		(property "Manufacturer" "Murata"
			(at 480.6 266.6 0)
			(layer "F.Fab")
			(hide yes)
			(effects
				(font
					(size 1 1)
					(thickness 0.15)
				)
			)
		)
		(property "Val" "100n"
			(at 480.6 266.6 0)
			(layer "F.Fab")
			(hide yes)
			(effects
				(font
					(size 1 1)
					(thickness 0.15)
				)
			)
		)
		(property "Voltage" "50V"
			(at 480.6 266.6 0)
			(layer "F.Fab")
			(hide yes)
			(effects
				(font
					(size 1 1)
					(thickness 0.15)
				)
			)
		)
		(sheetname "USB PHY")
		(sheetfile "usb-phy.kicad_sch")
		(attr smd)
		(fp_rect
			(start -0.925 -0.47)
			(end 0.925 0.47)
			(stroke
				(width 0.05)
				(type default)
			)
			(fill no)
			(layer "F.CrtYd")
		)
		(fp_line
			(start 0.504 0.248)
			(end -0.494 0.248)
			(stroke
				(width 0.15)
				(type solid)
			)
			(layer "F.Fab")
		)
		(fp_line
			(start 0.504 -0.25)
			(end 0.504 0.248)
			(stroke
				(width 0.15)
				(type solid)
			)
			(layer "F.Fab")
		)
		(fp_line
			(start -0.494 0.248)
			(end -0.494 -0.25)
			(stroke
				(width 0.15)
				(type solid)
			)
			(layer "F.Fab")
		)
		(fp_line
			(start -0.494 -0.25)
			(end 0.504 -0.25)
			(stroke
				(width 0.15)
				(type solid)
			)
			(layer "F.Fab")
		)
		(pad "1" smd roundrect
			(at -0.48 0 180)
			(size 0.59 0.64)
			(layers "F.Cu" "F.Mask" "F.Paste")
			(roundrect_rratio 0.25)
			(net 1 "GND")
			(pintype "passive")
		)
		(pad "2" smd roundrect
			(at 0.48 0 180)
			(size 0.59 0.64)
			(layers "F.Cu" "F.Mask" "F.Paste")
			(roundrect_rratio 0.25)
			(net 707 "/USB PHY/FTDI_3V3")
			(pintype "passive")
		)
	)
	(footprint "antmicro-footprints:C_0603_1608Metric"
		(layer "F.Cu")
		(at 181.25 172.7 -90)
		(descr "Capacitor SMD 0603")
		(tags "capacitor 0603")
		(property "Reference" "C332"
			(at 1 -0.125 90)
			(unlocked yes)
			(layer "F.SilkS")
			(effects
				(font
					(size 0.7 0.7)
					(thickness 0.15)
				)
				(justify right bottom)
			)
		)
		(property "Value" "C_22u_0603"
			(at 0 1.6 90)
			(layer "F.Fab")
			(effects
				(font
					(size 0.7 0.7)
					(thickness 0.15)
				)
				(justify right bottom)
			)
		)
		(property "Description" "SMD Multilayer Ceramic Capacitor, 22 µF, 6.3 V, 0603 [1608 Metric], ± 20%, X5R, GRM Series"
			(at 0 0 270)
			(layer "F.Fab")
			(hide yes)
			(effects
				(font
					(size 1.27 1.27)
					(thickness 0.15)
				)
			)
		)
		(property "Author" "Antmicro"
			(at 8.55 353.95 0)
			(layer "F.Fab")
			(hide yes)
			(effects
				(font
					(size 1 1)
					(thickness 0.15)
				)
			)
		)
		(property "Dielectric" ""
			(at 8.55 353.95 0)
			(layer "F.Fab")
			(hide yes)
			(effects
				(font
					(size 1 1)
					(thickness 0.15)
				)
			)
		)
		(property "License" "Apache-2.0"
			(at 8.55 353.95 0)
			(layer "F.Fab")
			(hide yes)
			(effects
				(font
					(size 1 1)
					(thickness 0.15)
				)
			)
		)
		(property "MPN" "GRM188R60J226MEA0D"
			(at 8.55 353.95 0)
			(layer "F.Fab")
			(hide yes)
			(effects
				(font
					(size 1 1)
					(thickness 0.15)
				)
			)
		)
		(property "Manufacturer" "Murata"
			(at 8.55 353.95 0)
			(layer "F.Fab")
			(hide yes)
			(effects
				(font
					(size 1 1)
					(thickness 0.15)
				)
			)
		)
		(property "Val" "22u"
			(at 8.55 353.95 0)
			(layer "F.Fab")
			(hide yes)
			(effects
				(font
					(size 1 1)
					(thickness 0.15)
				)
			)
		)
		(property "Voltage" ""
			(at 8.55 353.95 0)
			(layer "F.Fab")
			(hide yes)
			(effects
				(font
					(size 1 1)
					(thickness 0.15)
				)
			)
		)
		(sheetname "DC-DC Converters")
		(sheetfile "dc-dc.kicad_sch")
		(attr smd)
		(fp_line
			(start -0.15 0.4)
			(end 0.15 0.4)
			(stroke
				(width 0.15)
				(type solid)
			)
			(layer "F.SilkS")
		)
		(fp_line
			(start -0.15 -0.4)
			(end 0.15 -0.4)
			(stroke
				(width 0.15)
				(type solid)
			)
			(layer "F.SilkS")
		)
		(fp_rect
			(start -1.25 -0.65)
			(end 1.25 0.65)
			(stroke
				(width 0.05)
				(type solid)
			)
			(fill no)
			(layer "F.CrtYd")
		)
		(fp_rect
			(start -0.8 -0.4)
			(end 0.8 0.4)
			(stroke
				(width 0.15)
				(type solid)
			)
			(fill no)
			(layer "F.Fab")
		)
		(pad "1" smd roundrect
			(at -0.7 0 270)
			(size 0.8 1)
			(layers "F.Cu" "F.Mask" "F.Paste")
			(roundrect_rratio 0.2)
			(net 1 "GND")
			(pintype "passive")
		)
		(pad "2" smd roundrect
			(at 0.7 0 270)
			(size 0.8 1)
			(layers "F.Cu" "F.Mask" "F.Paste")
			(roundrect_rratio 0.2)
			(net 739 "/DC-DC Converters/5V_local")
			(pintype "passive")
		)
	)
	(footprint "antmicro-footprints:C_0402_1005Metric"
		(layer "F.Cu")
		(at 222.4 155.1 90)
		(descr "Capacitor SMD 0402")
		(tags "capacitor SMD 0402")
		(property "Reference" "C274"
			(at -1.55 1.25 90)
			(layer "F.SilkS")
			(effects
				(font
					(size 0.7 0.7)
					(thickness 0.15)
				)
				(justify left bottom)
			)
		)
		(property "Value" "C_10u_0402"
			(at 0 1.4 90)
			(layer "F.Fab")
			(effects
				(font
					(size 0.7 0.7)
					(thickness 0.15)
				)
				(justify left bottom)
			)
		)
		(property "Description" "SMD Multilayer Ceramic Capacitor, 10 µF, 6.3 V, 0402 [1005 Metric], ± 20%, X5R, CC Series"
			(at 0 0 90)
			(layer "F.Fab")
			(hide yes)
			(effects
				(font
					(size 1.27 1.27)
					(thickness 0.15)
				)
			)
		)
		(property "Author" "Antmicro"
			(at 377.5 -67.3 0)
			(layer "F.Fab")
			(hide yes)
			(effects
				(font
					(size 1 1)
					(thickness 0.15)
				)
			)
		)
		(property "Dielectric" ""
			(at 377.5 -67.3 0)
			(layer "F.Fab")
			(hide yes)
			(effects
				(font
					(size 1 1)
					(thickness 0.15)
				)
			)
		)
		(property "License" "Apache-2.0"
			(at 377.5 -67.3 0)
			(layer "F.Fab")
			(hide yes)
			(effects
				(font
					(size 1 1)
					(thickness 0.15)
				)
			)
		)
		(property "MPN" "CC0402MRX5R5BB106"
			(at 377.5 -67.3 0)
			(layer "F.Fab")
			(hide yes)
			(effects
				(font
					(size 1 1)
					(thickness 0.15)
				)
			)
		)
		(property "Manufacturer" "YAGEO"
			(at 377.5 -67.3 0)
			(layer "F.Fab")
			(hide yes)
			(effects
				(font
					(size 1 1)
					(thickness 0.15)
				)
			)
		)
		(property "Val" "10u"
			(at 377.5 -67.3 0)
			(layer "F.Fab")
			(hide yes)
			(effects
				(font
					(size 1 1)
					(thickness 0.15)
				)
			)
		)
		(property "Voltage" ""
			(at 377.5 -67.3 0)
			(layer "F.Fab")
			(hide yes)
			(effects
				(font
					(size 1 1)
					(thickness 0.15)
				)
			)
		)
		(sheetname "HDMI + Ethernet")
		(sheetfile "hdmi-ethernet.kicad_sch")
		(attr smd)
		(fp_rect
			(start -0.925 -0.47)
			(end 0.925 0.47)
			(stroke
				(width 0.05)
				(type default)
			)
			(fill no)
			(layer "F.CrtYd")
		)
		(fp_line
			(start 0.504 -0.25)
			(end 0.504 0.248)
			(stroke
				(width 0.15)
				(type solid)
			)
			(layer "F.Fab")
		)
		(fp_line
			(start -0.494 -0.25)
			(end 0.504 -0.25)
			(stroke
				(width 0.15)
				(type solid)
			)
			(layer "F.Fab")
		)
		(fp_line
			(start 0.504 0.248)
			(end -0.494 0.248)
			(stroke
				(width 0.15)
				(type solid)
			)
			(layer "F.Fab")
		)
		(fp_line
			(start -0.494 0.248)
			(end -0.494 -0.25)
			(stroke
				(width 0.15)
				(type solid)
			)
			(layer "F.Fab")
		)
		(pad "1" smd roundrect
			(at -0.48 0 90)
			(size 0.59 0.64)
			(layers "F.Cu" "F.Mask" "F.Paste")
			(roundrect_rratio 0.25)
			(net 1 "GND")
			(pintype "passive")
		)
		(pad "2" smd roundrect
			(at 0.48 0 90)
			(size 0.59 0.64)
			(layers "F.Cu" "F.Mask" "F.Paste")
			(roundrect_rratio 0.25)
			(net 721 "/HDMI + Ethernet/ETH_3V3")
			(pintype "passive")
		)
	)
	(footprint "antmicro-footprints:FB_0603_1608Metric"
		(layer "F.Cu")
		(at 201.85 103.868 90)
		(property "Reference" "FB10"
			(at -9.132 5.15 90)
			(layer "F.SilkS")
			(effects
				(font
					(size 0.7 0.7)
					(thickness 0.15)
				)
				(justify left bottom)
			)
		)
		(property "Value" "FB_120Z_2A_Murata-BLM18PG_0603"
			(at 0 1.7 90)
			(layer "F.Fab")
			(effects
				(font
					(size 0.7 0.7)
					(thickness 0.15)
				)
				(justify left bottom)
			)
		)
		(property "Description" "Ferrite Bead, 0603 [1608 Metric], 120 ohm, 2 A, BLM18P, 0.05 ohm, ± 25%, DC power line"
			(at 0 0 90)
			(layer "F.Fab")
			(hide yes)
			(effects
				(font
					(size 1.27 1.27)
					(thickness 0.15)
				)
			)
		)
		(property "Author" "Antmicro"
			(at 305.718 -97.982 0)
			(layer "F.Fab")
			(hide yes)
			(effects
				(font
					(size 1 1)
					(thickness 0.15)
				)
			)
		)
		(property "Current" ""
			(at 305.718 -97.982 0)
			(layer "F.Fab")
			(hide yes)
			(effects
				(font
					(size 1 1)
					(thickness 0.15)
				)
			)
		)
		(property "License" "Apache-2.0"
			(at 305.718 -97.982 0)
			(layer "F.Fab")
			(hide yes)
			(effects
				(font
					(size 1 1)
					(thickness 0.15)
				)
			)
		)
		(property "MPN" "BLM18PG121SN1D"
			(at 305.718 -97.982 0)
			(layer "F.Fab")
			(hide yes)
			(effects
				(font
					(size 1 1)
					(thickness 0.15)
				)
			)
		)
		(property "Manufacturer" "Murata"
			(at 305.718 -97.982 0)
			(layer "F.Fab")
			(hide yes)
			(effects
				(font
					(size 1 1)
					(thickness 0.15)
				)
			)
		)
		(property "Val" "120Z/2A"
			(at 305.718 -97.982 0)
			(layer "F.Fab")
			(hide yes)
			(effects
				(font
					(size 1 1)
					(thickness 0.15)
				)
			)
		)
		(sheetname "HDMI + Ethernet")
		(sheetfile "hdmi-ethernet.kicad_sch")
		(attr smd)
		(fp_line
			(start -0.15 -0.4)
			(end 0.15 -0.4)
			(stroke
				(width 0.15)
				(type solid)
			)
			(layer "F.SilkS")
		)
		(fp_line
			(start -0.15 0.4)
			(end 0.15 0.4)
			(stroke
				(width 0.15)
				(type solid)
			)
			(layer "F.SilkS")
		)
		(fp_rect
			(start -1.25 -0.65)
			(end 1.25 0.65)
			(stroke
				(width 0.05)
				(type solid)
			)
			(fill no)
			(layer "F.CrtYd")
		)
		(fp_line
			(start 0.8 -0.408)
			(end -0.803 -0.408)
			(stroke
				(width 0.15)
				(type solid)
			)
			(layer "F.Fab")
		)
		(fp_line
			(start 0.8 -0.408)
			(end 0.8 0.406)
			(stroke
				(width 0.15)
				(type solid)
			)
			(layer "F.Fab")
		)
		(fp_line
			(start 0.8 0.406)
			(end -0.803 0.406)
			(stroke
				(width 0.15)
				(type solid)
			)
			(layer "F.Fab")
		)
		(fp_line
			(start -0.803 0.406)
			(end -0.803 -0.408)
			(stroke
				(width 0.15)
				(type solid)
			)
			(layer "F.Fab")
		)
		(pad "1" smd roundrect
			(at -0.7 0 90)
			(size 0.8 1)
			(layers "F.Cu" "F.Mask" "F.Paste")
			(roundrect_rratio 0.2)
			(net 727 "+1V2")
			(pintype "passive")
		)
		(pad "2" smd roundrect
			(at 0.7 0 90)
			(size 0.8 1)
			(layers "F.Cu" "F.Mask" "F.Paste")
			(roundrect_rratio 0.2)
			(net 728 "/HDMI + Ethernet/GBE_AVDDL{slash}PLL")
			(pintype "passive")
		)
	)
	(footprint "antmicro-footprints:ASP-184329-01_mounting_holes"
		(layer "F.Cu")
		(at 162.000001 106.000001 90)
		(property "Reference" "J18"
			(at 28.280001 4.299999 180)
			(layer "F.SilkS")
			(effects
				(font
					(size 0.7 0.7)
					(thickness 0.15)
				)
				(justify left bottom)
			)
		)
		(property "Value" "ASP-184329-01_mounting_holes"
			(at -8.4 0.2 90)
			(layer "F.Fab")
			(effects
				(font
					(size 0.7 0.7)
					(thickness 0.15)
				)
				(justify left bottom)
			)
		)
		(property "Description" "Mezzanine Connector, Array, Female, 1.27 mm, 14 Rows, 560 Contacts, Surface Mount"
			(at 0 0 90)
			(layer "F.Fab")
			(hide yes)
			(effects
				(font
					(size 1.27 1.27)
					(thickness 0.15)
				)
			)
		)
		(property "Author" "Antmicro"
			(at 268.000002 -56 0)
			(layer "F.Fab")
			(hide yes)
			(effects
				(font
					(size 1 1)
					(thickness 0.15)
				)
			)
		)
		(property "License" "Apache-2.0"
			(at 268.000002 -56 0)
			(layer "F.Fab")
			(hide yes)
			(effects
				(font
					(size 1 1)
					(thickness 0.15)
				)
			)
		)
		(property "MPN" "ASP-184329-01"
			(at 268.000002 -56 0)
			(layer "F.Fab")
			(hide yes)
			(effects
				(font
					(size 1 1)
					(thickness 0.15)
				)
			)
		)
		(property "Manufacturer" "Samtec"
			(at 268.000002 -56 0)
			(layer "F.Fab")
			(hide yes)
			(effects
				(font
					(size 1 1)
					(thickness 0.15)
				)
			)
		)
		(sheetname "FMC+ HSPC")
		(sheetfile "fmc-hspc.kicad_sch")
		(attr smd)
		(fp_line
			(start 27.815 -9.18)
			(end 27.815 -2.847)
			(stroke
				(width 0.15)
				(type solid)
			)
			(layer "F.SilkS")
		)
		(fp_line
			(start -28.825 -9.18)
			(end 27.815 -9.18)
			(stroke
				(width 0.15)
				(type solid)
			)
			(layer "F.SilkS")
		)
		(fp_line
			(start 28.655 -2.847)
			(end 28.655 2.845)
			(stroke
				(width 0.15)
				(type solid)
			)
			(layer "F.SilkS")
		)
		(fp_line
			(start 27.815 -2.847)
			(end 28.655 -2.847)
			(stroke
				(width 0.15)
				(type solid)
			)
			(layer "F.SilkS")
		)
		(fp_line
			(start 27.815 3.983)
			(end 27.815 9.179)
			(stroke
				(width 0.15)
				(type solid)
			)
			(layer "F.SilkS")
		)
		(fp_line
			(start 27.815 9.179)
			(end -28.825 9.179)
			(stroke
				(width 0.15)
				(type solid)
			)
			(layer "F.SilkS")
		)
		(fp_line
			(start -28.825 9.179)
			(end -28.825 -9.18)
			(stroke
				(width 0.15)
				(type solid)
			)
			(layer "F.SilkS")
		)
		(fp_circle
			(center 24.765 -8.257)
			(end 24.987 -8.257)
			(stroke
				(width 0.445)
				(type solid)
			)
			(fill no)
			(layer "F.Paste")
		)
		(fp_circle
			(center 23.495 -8.257)
			(end 23.716 -8.257)
			(stroke
				(width 0.445)
				(type solid)
			)
			(fill no)
			(layer "F.Paste")
		)
		(fp_circle
			(center 22.225 -8.257)
			(end 22.446 -8.257)
			(stroke
				(width 0.445)
				(type solid)
			)
			(fill no)
			(layer "F.Paste")
		)
		(fp_circle
			(center 20.954 -8.257)
			(end 21.176 -8.257)
			(stroke
				(width 0.445)
				(type solid)
			)
			(fill no)
			(layer "F.Paste")
		)
		(fp_circle
			(center 19.684 -8.257)
			(end 19.906 -8.257)
			(stroke
				(width 0.445)
				(type solid)
			)
			(fill no)
			(layer "F.Paste")
		)
		(fp_circle
			(center 18.414 -8.257)
			(end 18.637 -8.257)
			(stroke
				(width 0.445)
				(type solid)
			)
			(fill no)
			(layer "F.Paste")
		)
		(fp_circle
			(center 17.144 -8.257)
			(end 17.367 -8.257)
			(stroke
				(width 0.445)
				(type solid)
			)
			(fill no)
			(layer "F.Paste")
		)
		(fp_circle
			(center 15.874 -8.257)
			(end 16.097 -8.257)
			(stroke
				(width 0.445)
				(type solid)
			)
			(fill no)
			(layer "F.Paste")
		)
		(fp_circle
			(center 14.605 -8.257)
			(end 14.826 -8.257)
			(stroke
				(width 0.445)
				(type solid)
			)
			(fill no)
			(layer "F.Paste")
		)
		(fp_circle
			(center 13.335 -8.257)
			(end 13.557 -8.257)
			(stroke
				(width 0.445)
				(type solid)
			)
			(fill no)
			(layer "F.Paste")
		)
		(fp_circle
			(center 12.063 -8.257)
			(end 12.287 -8.257)
			(stroke
				(width 0.445)
				(type solid)
			)
			(fill no)
			(layer "F.Paste")
		)
		(fp_circle
			(center 10.794 -8.257)
			(end 11.016 -8.257)
			(stroke
				(width 0.445)
				(type solid)
			)
			(fill no)
			(layer "F.Paste")
		)
		(fp_circle
			(center 9.525 -8.257)
			(end 9.746 -8.257)
			(stroke
				(width 0.445)
				(type solid)
			)
			(fill no)
			(layer "F.Paste")
		)
		(fp_circle
			(center 8.255 -8.257)
			(end 8.477 -8.257)
			(stroke
				(width 0.445)
				(type solid)
			)
			(fill no)
			(layer "F.Paste")
		)
		(fp_circle
			(center 6.985 -8.257)
			(end 7.206 -8.257)
			(stroke
				(width 0.445)
				(type solid)
			)
			(fill no)
			(layer "F.Paste")
		)
		(fp_circle
			(center 5.714 -8.257)
			(end 5.937 -8.257)
			(stroke
				(width 0.445)
				(type solid)
			)
			(fill no)
			(layer "F.Paste")
		)
		(fp_circle
			(center 4.445 -8.257)
			(end 4.666 -8.257)
			(stroke
				(width 0.445)
				(type solid)
			)
			(fill no)
			(layer "F.Paste")
		)
		(fp_circle
			(center 3.173 -8.257)
			(end 3.397 -8.257)
			(stroke
				(width 0.445)
				(type solid)
			)
			(fill no)
			(layer "F.Paste")
		)
		(fp_circle
			(center 1.904 -8.257)
			(end 2.127 -8.257)
			(stroke
				(width 0.445)
				(type solid)
			)
			(fill no)
			(layer "F.Paste")
		)
		(fp_circle
			(center 0.633 -8.257)
			(end 0.856 -8.257)
			(stroke
				(width 0.445)
				(type solid)
			)
			(fill no)
			(layer "F.Paste")
		)
		(fp_circle
			(center -0.635 -8.257)
			(end -0.414 -8.257)
			(stroke
				(width 0.445)
				(type solid)
			)
			(fill no)
			(layer "F.Paste")
		)
		(fp_circle
			(center -1.905 -8.257)
			(end -1.684 -8.257)
			(stroke
				(width 0.445)
				(type solid)
			)
			(fill no)
			(layer "F.Paste")
		)
		(fp_circle
			(center -3.176 -8.257)
			(end -2.953 -8.257)
			(stroke
				(width 0.445)
				(type solid)
			)
			(fill no)
			(layer "F.Paste")
		)
		(fp_circle
			(center -4.446 -8.257)
			(end -4.223 -8.257)
			(stroke
				(width 0.445)
				(type solid)
			)
			(fill no)
			(layer "F.Paste")
		)
		(fp_circle
			(center -5.715 -8.257)
			(end -5.494 -8.257)
			(stroke
				(width 0.445)
				(type solid)
			)
			(fill no)
			(layer "F.Paste")
		)
		(fp_circle
			(center -6.986 -8.257)
			(end -6.763 -8.257)
			(stroke
				(width 0.445)
				(type solid)
			)
			(fill no)
			(layer "F.Paste")
		)
		(fp_circle
			(center -8.257 -8.257)
			(end -8.033 -8.257)
			(stroke
				(width 0.445)
				(type solid)
			)
			(fill no)
			(layer "F.Paste")
		)
		(fp_circle
			(center -9.526 -8.257)
			(end -9.304 -8.257)
			(stroke
				(width 0.445)
				(type solid)
			)
			(fill no)
			(layer "F.Paste")
		)
		(fp_circle
			(center -10.795 -8.257)
			(end -10.574 -8.257)
			(stroke
				(width 0.445)
				(type solid)
			)
			(fill no)
			(layer "F.Paste")
		)
		(fp_circle
			(center -12.065 -8.257)
			(end -11.843 -8.257)
			(stroke
				(width 0.445)
				(type solid)
			)
			(fill no)
			(layer "F.Paste")
		)
		(fp_circle
			(center -13.337 -8.257)
			(end -13.113 -8.257)
			(stroke
				(width 0.445)
				(type solid)
			)
			(fill no)
			(layer "F.Paste")
		)
		(fp_circle
			(center -14.606 -8.257)
			(end -14.384 -8.257)
			(stroke
				(width 0.445)
				(type solid)
			)
			(fill no)
			(layer "F.Paste")
		)
		(fp_circle
			(center -15.875 -8.257)
			(end -15.654 -8.257)
			(stroke
				(width 0.445)
				(type solid)
			)
			(fill no)
			(layer "F.Paste")
		)
		(fp_circle
			(center -17.145 -8.257)
			(end -16.924 -8.257)
			(stroke
				(width 0.445)
				(type solid)
			)
			(fill no)
			(layer "F.Paste")
		)
		(fp_circle
			(center -18.415 -8.257)
			(end -18.194 -8.257)
			(stroke
				(width 0.445)
				(type solid)
			)
			(fill no)
			(layer "F.Paste")
		)
		(fp_circle
			(center -19.685 -8.257)
			(end -19.464 -8.257)
			(stroke
				(width 0.445)
				(type solid)
			)
			(fill no)
			(layer "F.Paste")
		)
		(fp_circle
			(center -20.956 -8.257)
			(end -20.734 -8.257)
			(stroke
				(width 0.445)
				(type solid)
			)
			(fill no)
			(layer "F.Paste")
		)
		(fp_circle
			(center -22.226 -8.257)
			(end -22.003 -8.257)
			(stroke
				(width 0.445)
				(type solid)
			)
			(fill no)
			(layer "F.Paste")
		)
		(fp_circle
			(center -23.497 -8.257)
			(end -23.273 -8.257)
			(stroke
				(width 0.445)
				(type solid)
			)
			(fill no)
			(layer "F.Paste")
		)
		(fp_circle
			(center -24.767 -8.257)
			(end -24.543 -8.257)
			(stroke
				(width 0.445)
				(type solid)
			)
			(fill no)
			(layer "F.Paste")
		)
		(fp_circle
			(center 24.765 -6.986)
			(end 24.987 -6.986)
			(stroke
				(width 0.445)
				(type solid)
			)
			(fill no)
			(layer "F.Paste")
		)
		(fp_circle
			(center 23.495 -6.986)
			(end 23.716 -6.986)
			(stroke
				(width 0.445)
				(type solid)
			)
			(fill no)
			(layer "F.Paste")
		)
		(fp_circle
			(center 22.225 -6.986)
			(end 22.446 -6.986)
			(stroke
				(width 0.445)
				(type solid)
			)
			(fill no)
			(layer "F.Paste")
		)
		(fp_circle
			(center 20.954 -6.986)
			(end 21.176 -6.986)
			(stroke
				(width 0.445)
				(type solid)
			)
			(fill no)
			(layer "F.Paste")
		)
		(fp_circle
			(center 19.684 -6.986)
			(end 19.906 -6.986)
			(stroke
				(width 0.445)
				(type solid)
			)
			(fill no)
			(layer "F.Paste")
		)
		(fp_circle
			(center 18.414 -6.986)
			(end 18.637 -6.986)
			(stroke
				(width 0.445)
				(type solid)
			)
			(fill no)
			(layer "F.Paste")
		)
		(fp_circle
			(center 17.144 -6.986)
			(end 17.367 -6.986)
			(stroke
				(width 0.445)
				(type solid)
			)
			(fill no)
			(layer "F.Paste")
		)
		(fp_circle
			(center 15.874 -6.986)
			(end 16.097 -6.986)
			(stroke
				(width 0.445)
				(type solid)
			)
			(fill no)
			(layer "F.Paste")
		)
		(fp_circle
			(center 14.605 -6.986)
			(end 14.826 -6.986)
			(stroke
				(width 0.445)
				(type solid)
			)
			(fill no)
			(layer "F.Paste")
		)
		(fp_circle
			(center 13.335 -6.986)
			(end 13.557 -6.986)
			(stroke
				(width 0.445)
				(type solid)
			)
			(fill no)
			(layer "F.Paste")
		)
		(fp_circle
			(center 12.063 -6.986)
			(end 12.287 -6.986)
			(stroke
				(width 0.445)
				(type solid)
			)
			(fill no)
			(layer "F.Paste")
		)
		(fp_circle
			(center 10.794 -6.986)
			(end 11.016 -6.986)
			(stroke
				(width 0.445)
				(type solid)
			)
			(fill no)
			(layer "F.Paste")
		)
		(fp_circle
			(center 9.525 -6.986)
			(end 9.746 -6.986)
			(stroke
				(width 0.445)
				(type solid)
			)
			(fill no)
			(layer "F.Paste")
		)
		(fp_circle
			(center 8.255 -6.986)
			(end 8.477 -6.986)
			(stroke
				(width 0.445)
				(type solid)
			)
			(fill no)
			(layer "F.Paste")
		)
		(fp_circle
			(center 6.985 -6.986)
			(end 7.206 -6.986)
			(stroke
				(width 0.445)
				(type solid)
			)
			(fill no)
			(layer "F.Paste")
		)
		(fp_circle
			(center 5.714 -6.986)
			(end 5.937 -6.986)
			(stroke
				(width 0.445)
				(type solid)
			)
			(fill no)
			(layer "F.Paste")
		)
		(fp_circle
			(center 4.445 -6.986)
			(end 4.666 -6.986)
			(stroke
				(width 0.445)
				(type solid)
			)
			(fill no)
			(layer "F.Paste")
		)
		(fp_circle
			(center 3.173 -6.986)
			(end 3.397 -6.986)
			(stroke
				(width 0.445)
				(type solid)
			)
			(fill no)
			(layer "F.Paste")
		)
		(fp_circle
			(center 1.904 -6.986)
			(end 2.127 -6.986)
			(stroke
				(width 0.445)
				(type solid)
			)
			(fill no)
			(layer "F.Paste")
		)
		(fp_circle
			(center 0.633 -6.986)
			(end 0.856 -6.986)
			(stroke
				(width 0.445)
				(type solid)
			)
			(fill no)
			(layer "F.Paste")
		)
		(fp_circle
			(center -0.635 -6.986)
			(end -0.414 -6.986)
			(stroke
				(width 0.445)
				(type solid)
			)
			(fill no)
			(layer "F.Paste")
		)
		(fp_circle
			(center -1.905 -6.986)
			(end -1.684 -6.986)
			(stroke
				(width 0.445)
				(type solid)
			)
			(fill no)
			(layer "F.Paste")
		)
		(fp_circle
			(center -3.176 -6.986)
			(end -2.953 -6.986)
			(stroke
				(width 0.445)
				(type solid)
			)
			(fill no)
			(layer "F.Paste")
		)
		(fp_circle
			(center -4.446 -6.986)
			(end -4.223 -6.986)
			(stroke
				(width 0.445)
				(type solid)
			)
			(fill no)
			(layer "F.Paste")
		)
		(fp_circle
			(center -5.715 -6.986)
			(end -5.494 -6.986)
			(stroke
				(width 0.445)
				(type solid)
			)
			(fill no)
			(layer "F.Paste")
		)
		(fp_circle
			(center -6.986 -6.986)
			(end -6.763 -6.986)
			(stroke
				(width 0.445)
				(type solid)
			)
			(fill no)
			(layer "F.Paste")
		)
		(fp_circle
			(center -8.257 -6.986)
			(end -8.033 -6.986)
			(stroke
				(width 0.445)
				(type solid)
			)
			(fill no)
			(layer "F.Paste")
		)
		(fp_circle
			(center -9.526 -6.986)
			(end -9.304 -6.986)
			(stroke
				(width 0.445)
				(type solid)
			)
			(fill no)
			(layer "F.Paste")
		)
		(fp_circle
			(center -10.795 -6.986)
			(end -10.574 -6.986)
			(stroke
				(width 0.445)
				(type solid)
			)
			(fill no)
			(layer "F.Paste")
		)
		(fp_circle
			(center -12.065 -6.986)
			(end -11.843 -6.986)
			(stroke
				(width 0.445)
				(type solid)
			)
			(fill no)
			(layer "F.Paste")
		)
		(fp_circle
			(center -13.337 -6.986)
			(end -13.113 -6.986)
			(stroke
				(width 0.445)
				(type solid)
			)
			(fill no)
			(layer "F.Paste")
		)
		(fp_circle
			(center -14.606 -6.986)
			(end -14.384 -6.986)
			(stroke
				(width 0.445)
				(type solid)
			)
			(fill no)
			(layer "F.Paste")
		)
		(fp_circle
			(center -15.875 -6.986)
			(end -15.654 -6.986)
			(stroke
				(width 0.445)
				(type solid)
			)
			(fill no)
			(layer "F.Paste")
		)
		(fp_circle
			(center -17.145 -6.986)
			(end -16.924 -6.986)
			(stroke
				(width 0.445)
				(type solid)
			)
			(fill no)
			(layer "F.Paste")
		)
		(fp_circle
			(center -18.415 -6.986)
			(end -18.194 -6.986)
			(stroke
				(width 0.445)
				(type solid)
			)
			(fill no)
			(layer "F.Paste")
		)
		(fp_circle
			(center -19.685 -6.986)
			(end -19.464 -6.986)
			(stroke
				(width 0.445)
				(type solid)
			)
			(fill no)
			(layer "F.Paste")
		)
		(fp_circle
			(center -20.956 -6.986)
			(end -20.734 -6.986)
			(stroke
				(width 0.445)
				(type solid)
			)
			(fill no)
			(layer "F.Paste")
		)
		(fp_circle
			(center -22.226 -6.986)
			(end -22.003 -6.986)
			(stroke
				(width 0.445)
				(type solid)
			)
			(fill no)
			(layer "F.Paste")
		)
		(fp_circle
			(center -23.497 -6.986)
			(end -23.273 -6.986)
			(stroke
				(width 0.445)
				(type solid)
			)
			(fill no)
			(layer "F.Paste")
		)
		(fp_circle
			(center -24.767 -6.986)
			(end -24.543 -6.986)
			(stroke
				(width 0.445)
				(type solid)
			)
			(fill no)
			(layer "F.Paste")
		)
		(fp_circle
			(center 24.765 -5.715)
			(end 24.987 -5.715)
			(stroke
				(width 0.445)
				(type solid)
			)
			(fill no)
			(layer "F.Paste")
		)
		(fp_circle
			(center 23.495 -5.715)
			(end 23.716 -5.715)
			(stroke
				(width 0.445)
				(type solid)
			)
			(fill no)
			(layer "F.Paste")
		)
		(fp_circle
			(center 22.225 -5.715)
			(end 22.446 -5.715)
			(stroke
				(width 0.445)
				(type solid)
			)
			(fill no)
			(layer "F.Paste")
		)
		(fp_circle
			(center 20.954 -5.715)
			(end 21.176 -5.715)
			(stroke
				(width 0.445)
				(type solid)
			)
			(fill no)
			(layer "F.Paste")
		)
		(fp_circle
			(center 19.684 -5.715)
			(end 19.906 -5.715)
			(stroke
				(width 0.445)
				(type solid)
			)
			(fill no)
			(layer "F.Paste")
		)
		(fp_circle
			(center 18.414 -5.715)
			(end 18.637 -5.715)
			(stroke
				(width 0.445)
				(type solid)
			)
			(fill no)
			(layer "F.Paste")
		)
		(fp_circle
			(center 17.144 -5.715)
			(end 17.367 -5.715)
			(stroke
				(width 0.445)
				(type solid)
			)
			(fill no)
			(layer "F.Paste")
		)
		(fp_circle
			(center 15.874 -5.715)
			(end 16.097 -5.715)
			(stroke
				(width 0.445)
				(type solid)
			)
			(fill no)
			(layer "F.Paste")
		)
		(fp_circle
			(center 14.605 -5.715)
			(end 14.826 -5.715)
			(stroke
				(width 0.445)
				(type solid)
			)
			(fill no)
			(layer "F.Paste")
		)
		(fp_circle
			(center 13.335 -5.715)
			(end 13.557 -5.715)
			(stroke
				(width 0.445)
				(type solid)
			)
			(fill no)
			(layer "F.Paste")
		)
		(fp_circle
			(center 12.063 -5.715)
			(end 12.287 -5.715)
			(stroke
				(width 0.445)
				(type solid)
			)
			(fill no)
			(layer "F.Paste")
		)
		(fp_circle
			(center 10.794 -5.715)
			(end 11.016 -5.715)
			(stroke
				(width 0.445)
				(type solid)
			)
			(fill no)
			(layer "F.Paste")
		)
		(fp_circle
			(center 9.525 -5.715)
			(end 9.746 -5.715)
			(stroke
				(width 0.445)
				(type solid)
			)
			(fill no)
			(layer "F.Paste")
		)
		(fp_circle
			(center 8.255 -5.715)
			(end 8.477 -5.715)
			(stroke
				(width 0.445)
				(type solid)
			)
			(fill no)
			(layer "F.Paste")
		)
		(fp_circle
			(center 6.985 -5.715)
			(end 7.206 -5.715)
			(stroke
				(width 0.445)
				(type solid)
			)
			(fill no)
			(layer "F.Paste")
		)
		(fp_circle
			(center 5.714 -5.715)
			(end 5.937 -5.715)
			(stroke
				(width 0.445)
				(type solid)
			)
			(fill no)
			(layer "F.Paste")
		)
		(fp_circle
			(center 4.445 -5.715)
			(end 4.666 -5.715)
			(stroke
				(width 0.445)
				(type solid)
			)
			(fill no)
			(layer "F.Paste")
		)
		(fp_circle
			(center 3.173 -5.715)
			(end 3.397 -5.715)
			(stroke
				(width 0.445)
				(type solid)
			)
			(fill no)
			(layer "F.Paste")
		)
		(fp_circle
			(center 1.904 -5.715)
			(end 2.127 -5.715)
			(stroke
				(width 0.445)
				(type solid)
			)
			(fill no)
			(layer "F.Paste")
		)
		(fp_circle
			(center 0.633 -5.715)
			(end 0.856 -5.715)
			(stroke
				(width 0.445)
				(type solid)
			)
			(fill no)
			(layer "F.Paste")
		)
		(fp_circle
			(center -0.635 -5.715)
			(end -0.414 -5.715)
			(stroke
				(width 0.445)
				(type solid)
			)
			(fill no)
			(layer "F.Paste")
		)
		(fp_circle
			(center -1.905 -5.715)
			(end -1.684 -5.715)
			(stroke
				(width 0.445)
				(type solid)
			)
			(fill no)
			(layer "F.Paste")
		)
		(fp_circle
			(center -3.176 -5.715)
			(end -2.953 -5.715)
			(stroke
				(width 0.445)
				(type solid)
			)
			(fill no)
			(layer "F.Paste")
		)
		(fp_circle
			(center -4.446 -5.715)
			(end -4.223 -5.715)
			(stroke
				(width 0.445)
				(type solid)
			)
			(fill no)
			(layer "F.Paste")
		)
		(fp_circle
			(center -5.715 -5.715)
			(end -5.494 -5.715)
			(stroke
				(width 0.445)
				(type solid)
			)
			(fill no)
			(layer "F.Paste")
		)
		(fp_circle
			(center -6.986 -5.715)
			(end -6.763 -5.715)
			(stroke
				(width 0.445)
				(type solid)
			)
			(fill no)
			(layer "F.Paste")
		)
		(fp_circle
			(center -8.257 -5.715)
			(end -8.033 -5.715)
			(stroke
				(width 0.445)
				(type solid)
			)
			(fill no)
			(layer "F.Paste")
		)
		(fp_circle
			(center -9.526 -5.715)
			(end -9.304 -5.715)
			(stroke
				(width 0.445)
				(type solid)
			)
			(fill no)
			(layer "F.Paste")
		)
		(fp_circle
			(center -10.795 -5.715)
			(end -10.574 -5.715)
			(stroke
				(width 0.445)
				(type solid)
			)
			(fill no)
			(layer "F.Paste")
		)
		(fp_circle
			(center -12.065 -5.715)
			(end -11.843 -5.715)
			(stroke
				(width 0.445)
				(type solid)
			)
			(fill no)
			(layer "F.Paste")
		)
		(fp_circle
			(center -13.337 -5.715)
			(end -13.113 -5.715)
			(stroke
				(width 0.445)
				(type solid)
			)
			(fill no)
			(layer "F.Paste")
		)
		(fp_circle
			(center -14.606 -5.715)
			(end -14.384 -5.715)
			(stroke
				(width 0.445)
				(type solid)
			)
			(fill no)
			(layer "F.Paste")
		)
		(fp_circle
			(center -15.875 -5.715)
			(end -15.654 -5.715)
			(stroke
				(width 0.445)
				(type solid)
			)
			(fill no)
			(layer "F.Paste")
		)
		(fp_circle
			(center -17.145 -5.715)
			(end -16.924 -5.715)
			(stroke
				(width 0.445)
				(type solid)
			)
			(fill no)
			(layer "F.Paste")
		)
		(fp_circle
			(center -18.415 -5.715)
			(end -18.194 -5.715)
			(stroke
				(width 0.445)
				(type solid)
			)
			(fill no)
			(layer "F.Paste")
		)
		(fp_circle
			(center -19.685 -5.715)
			(end -19.464 -5.715)
			(stroke
				(width 0.445)
				(type solid)
			)
			(fill no)
			(layer "F.Paste")
		)
		(fp_circle
			(center -20.956 -5.715)
			(end -20.734 -5.715)
			(stroke
				(width 0.445)
				(type solid)
			)
			(fill no)
			(layer "F.Paste")
		)
		(fp_circle
			(center -22.226 -5.715)
			(end -22.003 -5.715)
			(stroke
				(width 0.445)
				(type solid)
			)
			(fill no)
			(layer "F.Paste")
		)
		(fp_circle
			(center -23.497 -5.715)
			(end -23.273 -5.715)
			(stroke
				(width 0.445)
				(type solid)
			)
			(fill no)
			(layer "F.Paste")
		)
		(fp_circle
			(center -24.767 -5.715)
			(end -24.543 -5.715)
			(stroke
				(width 0.445)
				(type solid)
			)
			(fill no)
			(layer "F.Paste")
		)
		(fp_circle
			(center 24.765 -4.446)
			(end 24.987 -4.446)
			(stroke
				(width 0.445)
				(type solid)
			)
			(fill no)
			(layer "F.Paste")
		)
		(fp_circle
			(center 23.495 -4.446)
			(end 23.716 -4.446)
			(stroke
				(width 0.445)
				(type solid)
			)
			(fill no)
			(layer "F.Paste")
		)
		(fp_circle
			(center 22.225 -4.446)
			(end 22.446 -4.446)
			(stroke
				(width 0.445)
				(type solid)
			)
			(fill no)
			(layer "F.Paste")
		)
		(fp_circle
			(center 20.954 -4.446)
			(end 21.176 -4.446)
			(stroke
				(width 0.445)
				(type solid)
			)
			(fill no)
			(layer "F.Paste")
		)
		(fp_circle
			(center 19.684 -4.446)
			(end 19.906 -4.446)
			(stroke
				(width 0.445)
				(type solid)
			)
			(fill no)
			(layer "F.Paste")
		)
		(fp_circle
			(center 18.414 -4.446)
			(end 18.637 -4.446)
			(stroke
				(width 0.445)
				(type solid)
			)
			(fill no)
			(layer "F.Paste")
		)
		(fp_circle
			(center 17.144 -4.446)
			(end 17.367 -4.446)
			(stroke
				(width 0.445)
				(type solid)
			)
			(fill no)
			(layer "F.Paste")
		)
		(fp_circle
			(center 15.874 -4.446)
			(end 16.097 -4.446)
			(stroke
				(width 0.445)
				(type solid)
			)
			(fill no)
			(layer "F.Paste")
		)
		(fp_circle
			(center 14.605 -4.446)
			(end 14.826 -4.446)
			(stroke
				(width 0.445)
				(type solid)
			)
			(fill no)
			(layer "F.Paste")
		)
		(fp_circle
			(center 13.335 -4.446)
			(end 13.557 -4.446)
			(stroke
				(width 0.445)
				(type solid)
			)
			(fill no)
			(layer "F.Paste")
		)
		(fp_circle
			(center 12.063 -4.446)
			(end 12.287 -4.446)
			(stroke
				(width 0.445)
				(type solid)
			)
			(fill no)
			(layer "F.Paste")
		)
		(fp_circle
			(center 10.794 -4.446)
			(end 11.016 -4.446)
			(stroke
				(width 0.445)
				(type solid)
			)
			(fill no)
			(layer "F.Paste")
		)
		(fp_circle
			(center 9.525 -4.446)
			(end 9.746 -4.446)
			(stroke
				(width 0.445)
				(type solid)
			)
			(fill no)
			(layer "F.Paste")
		)
		(fp_circle
			(center 8.255 -4.446)
			(end 8.477 -4.446)
			(stroke
				(width 0.445)
				(type solid)
			)
			(fill no)
			(layer "F.Paste")
		)
		(fp_circle
			(center 6.985 -4.446)
			(end 7.206 -4.446)
			(stroke
				(width 0.445)
				(type solid)
			)
			(fill no)
			(layer "F.Paste")
		)
		(fp_circle
			(center 5.714 -4.446)
			(end 5.937 -4.446)
			(stroke
				(width 0.445)
				(type solid)
			)
			(fill no)
			(layer "F.Paste")
		)
		(fp_circle
			(center 4.445 -4.446)
			(end 4.666 -4.446)
			(stroke
				(width 0.445)
				(type solid)
			)
			(fill no)
			(layer "F.Paste")
		)
		(fp_circle
			(center 3.173 -4.446)
			(end 3.397 -4.446)
			(stroke
				(width 0.445)
				(type solid)
			)
			(fill no)
			(layer "F.Paste")
		)
		(fp_circle
			(center 1.904 -4.446)
			(end 2.127 -4.446)
			(stroke
				(width 0.445)
				(type solid)
			)
			(fill no)
			(layer "F.Paste")
		)
		(fp_circle
			(center 0.633 -4.446)
			(end 0.856 -4.446)
			(stroke
				(width 0.445)
				(type solid)
			)
			(fill no)
			(layer "F.Paste")
		)
		(fp_circle
			(center -0.635 -4.446)
			(end -0.414 -4.446)
			(stroke
				(width 0.445)
				(type solid)
			)
			(fill no)
			(layer "F.Paste")
		)
		(fp_circle
			(center -1.905 -4.446)
			(end -1.684 -4.446)
			(stroke
				(width 0.445)
				(type solid)
			)
			(fill no)
			(layer "F.Paste")
		)
		(fp_circle
			(center -3.176 -4.446)
			(end -2.953 -4.446)
			(stroke
				(width 0.445)
				(type solid)
			)
			(fill no)
			(layer "F.Paste")
		)
		(fp_circle
			(center -4.446 -4.446)
			(end -4.223 -4.446)
			(stroke
				(width 0.445)
				(type solid)
			)
			(fill no)
			(layer "F.Paste")
		)
		(fp_circle
			(center -5.715 -4.446)
			(end -5.494 -4.446)
			(stroke
				(width 0.445)
				(type solid)
			)
			(fill no)
			(layer "F.Paste")
		)
		(fp_circle
			(center -6.986 -4.446)
			(end -6.763 -4.446)
			(stroke
				(width 0.445)
				(type solid)
			)
			(fill no)
			(layer "F.Paste")
		)
		(fp_circle
			(center -8.257 -4.446)
			(end -8.033 -4.446)
			(stroke
				(width 0.445)
				(type solid)
			)
			(fill no)
			(layer "F.Paste")
		)
		(fp_circle
			(center -9.526 -4.446)
			(end -9.304 -4.446)
			(stroke
				(width 0.445)
				(type solid)
			)
			(fill no)
			(layer "F.Paste")
		)
		(fp_circle
			(center -10.795 -4.446)
			(end -10.574 -4.446)
			(stroke
				(width 0.445)
				(type solid)
			)
			(fill no)
			(layer "F.Paste")
		)
		(fp_circle
			(center -12.065 -4.446)
			(end -11.843 -4.446)
			(stroke
				(width 0.445)
				(type solid)
			)
			(fill no)
			(layer "F.Paste")
		)
		(fp_circle
			(center -13.337 -4.446)
			(end -13.113 -4.446)
			(stroke
				(width 0.445)
				(type solid)
			)
			(fill no)
			(layer "F.Paste")
		)
		(fp_circle
			(center -14.606 -4.446)
			(end -14.384 -4.446)
			(stroke
				(width 0.445)
				(type solid)
			)
			(fill no)
			(layer "F.Paste")
		)
		(fp_circle
			(center -15.875 -4.446)
			(end -15.654 -4.446)
			(stroke
				(width 0.445)
				(type solid)
			)
			(fill no)
			(layer "F.Paste")
		)
		(fp_circle
			(center -17.145 -4.446)
			(end -16.924 -4.446)
			(stroke
				(width 0.445)
				(type solid)
			)
			(fill no)
			(layer "F.Paste")
		)
		(fp_circle
			(center -18.415 -4.446)
			(end -18.194 -4.446)
			(stroke
				(width 0.445)
				(type solid)
			)
			(fill no)
			(layer "F.Paste")
		)
		(fp_circle
			(center -19.685 -4.446)
			(end -19.464 -4.446)
			(stroke
				(width 0.445)
				(type solid)
			)
			(fill no)
			(layer "F.Paste")
		)
		(fp_circle
			(center -20.956 -4.446)
			(end -20.734 -4.446)
			(stroke
				(width 0.445)
				(type solid)
			)
			(fill no)
			(layer "F.Paste")
		)
		(fp_circle
			(center -22.226 -4.446)
			(end -22.003 -4.446)
			(stroke
				(width 0.445)
				(type solid)
			)
			(fill no)
			(layer "F.Paste")
		)
		(fp_circle
			(center -23.497 -4.446)
			(end -23.273 -4.446)
			(stroke
				(width 0.445)
				(type solid)
			)
			(fill no)
			(layer "F.Paste")
		)
		(fp_circle
			(center -24.767 -4.446)
			(end -24.543 -4.446)
			(stroke
				(width 0.445)
				(type solid)
			)
			(fill no)
			(layer "F.Paste")
		)
		(fp_circle
			(center 24.765 -3.176)
			(end 24.987 -3.176)
			(stroke
				(width 0.445)
				(type solid)
			)
			(fill no)
			(layer "F.Paste")
		)
		(fp_circle
			(center 23.495 -3.176)
			(end 23.716 -3.176)
			(stroke
				(width 0.445)
				(type solid)
			)
			(fill no)
			(layer "F.Paste")
		)
		(fp_circle
			(center 22.225 -3.176)
			(end 22.446 -3.176)
			(stroke
				(width 0.445)
				(type solid)
			)
			(fill no)
			(layer "F.Paste")
		)
		(fp_circle
			(center 20.954 -3.176)
			(end 21.176 -3.176)
			(stroke
				(width 0.445)
				(type solid)
			)
			(fill no)
			(layer "F.Paste")
		)
		(fp_circle
			(center 19.684 -3.176)
			(end 19.906 -3.176)
			(stroke
				(width 0.445)
				(type solid)
			)
			(fill no)
			(layer "F.Paste")
		)
		(fp_circle
			(center 18.414 -3.176)
			(end 18.637 -3.176)
			(stroke
				(width 0.445)
				(type solid)
			)
			(fill no)
			(layer "F.Paste")
		)
		(fp_circle
			(center 17.144 -3.176)
			(end 17.367 -3.176)
			(stroke
				(width 0.445)
				(type solid)
			)
			(fill no)
			(layer "F.Paste")
		)
		(fp_circle
			(center 15.874 -3.176)
			(end 16.097 -3.176)
			(stroke
				(width 0.445)
				(type solid)
			)
			(fill no)
			(layer "F.Paste")
		)
		(fp_circle
			(center 14.605 -3.176)
			(end 14.826 -3.176)
			(stroke
				(width 0.445)
				(type solid)
			)
			(fill no)
			(layer "F.Paste")
		)
		(fp_circle
			(center 13.335 -3.176)
			(end 13.557 -3.176)
			(stroke
				(width 0.445)
				(type solid)
			)
			(fill no)
			(layer "F.Paste")
		)
		(fp_circle
			(center 12.063 -3.176)
			(end 12.287 -3.176)
			(stroke
				(width 0.445)
				(type solid)
			)
			(fill no)
			(layer "F.Paste")
		)
		(fp_circle
			(center 10.794 -3.176)
			(end 11.016 -3.176)
			(stroke
				(width 0.445)
				(type solid)
			)
			(fill no)
			(layer "F.Paste")
		)
		(fp_circle
			(center 9.525 -3.176)
			(end 9.746 -3.176)
			(stroke
				(width 0.445)
				(type solid)
			)
			(fill no)
			(layer "F.Paste")
		)
		(fp_circle
			(center 8.255 -3.176)
			(end 8.477 -3.176)
			(stroke
				(width 0.445)
				(type solid)
			)
			(fill no)
			(layer "F.Paste")
		)
		(fp_circle
			(center 6.985 -3.176)
			(end 7.206 -3.176)
			(stroke
				(width 0.445)
				(type solid)
			)
			(fill no)
			(layer "F.Paste")
		)
		(fp_circle
			(center 5.714 -3.176)
			(end 5.937 -3.176)
			(stroke
				(width 0.445)
				(type solid)
			)
			(fill no)
			(layer "F.Paste")
		)
		(fp_circle
			(center 4.445 -3.176)
			(end 4.666 -3.176)
			(stroke
				(width 0.445)
				(type solid)
			)
			(fill no)
			(layer "F.Paste")
		)
		(fp_circle
			(center 3.173 -3.176)
			(end 3.397 -3.176)
			(stroke
				(width 0.445)
				(type solid)
			)
			(fill no)
			(layer "F.Paste")
		)
		(fp_circle
			(center 1.904 -3.176)
			(end 2.127 -3.176)
			(stroke
				(width 0.445)
				(type solid)
			)
			(fill no)
			(layer "F.Paste")
		)
		(fp_circle
			(center 0.633 -3.176)
			(end 0.856 -3.176)
			(stroke
				(width 0.445)
				(type solid)
			)
			(fill no)
			(layer "F.Paste")
		)
		(fp_circle
			(center -0.635 -3.176)
			(end -0.414 -3.176)
			(stroke
				(width 0.445)
				(type solid)
			)
			(fill no)
			(layer "F.Paste")
		)
		(fp_circle
			(center -1.905 -3.176)
			(end -1.684 -3.176)
			(stroke
				(width 0.445)
				(type solid)
			)
			(fill no)
			(layer "F.Paste")
		)
		(fp_circle
			(center -3.176 -3.176)
			(end -2.953 -3.176)
			(stroke
				(width 0.445)
				(type solid)
			)
			(fill no)
			(layer "F.Paste")
		)
		(fp_circle
			(center -4.446 -3.176)
			(end -4.223 -3.176)
			(stroke
				(width 0.445)
				(type solid)
			)
			(fill no)
			(layer "F.Paste")
		)
		(fp_circle
			(center -5.715 -3.176)
			(end -5.494 -3.176)
			(stroke
				(width 0.445)
				(type solid)
			)
			(fill no)
			(layer "F.Paste")
		)
		(fp_circle
			(center -6.986 -3.176)
			(end -6.763 -3.176)
			(stroke
				(width 0.445)
				(type solid)
			)
			(fill no)
			(layer "F.Paste")
		)
		(fp_circle
			(center -8.257 -3.176)
			(end -8.033 -3.176)
			(stroke
				(width 0.445)
				(type solid)
			)
			(fill no)
			(layer "F.Paste")
		)
		(fp_circle
			(center -9.526 -3.176)
			(end -9.304 -3.176)
			(stroke
				(width 0.445)
				(type solid)
			)
			(fill no)
			(layer "F.Paste")
		)
		(fp_circle
			(center -10.795 -3.176)
			(end -10.574 -3.176)
			(stroke
				(width 0.445)
				(type solid)
			)
			(fill no)
			(layer "F.Paste")
		)
		(fp_circle
			(center -12.065 -3.176)
			(end -11.843 -3.176)
			(stroke
				(width 0.445)
				(type solid)
			)
			(fill no)
			(layer "F.Paste")
		)
		(fp_circle
			(center -13.337 -3.176)
			(end -13.113 -3.176)
			(stroke
				(width 0.445)
				(type solid)
			)
			(fill no)
			(layer "F.Paste")
		)
		(fp_circle
			(center -14.606 -3.176)
			(end -14.384 -3.176)
			(stroke
				(width 0.445)
				(type solid)
			)
			(fill no)
			(layer "F.Paste")
		)
		(fp_circle
			(center -15.875 -3.176)
			(end -15.654 -3.176)
			(stroke
				(width 0.445)
				(type solid)
			)
			(fill no)
			(layer "F.Paste")
		)
		(fp_circle
			(center -17.145 -3.176)
			(end -16.924 -3.176)
			(stroke
				(width 0.445)
				(type solid)
			)
			(fill no)
			(layer "F.Paste")
		)
		(fp_circle
			(center -18.415 -3.176)
			(end -18.194 -3.176)
			(stroke
				(width 0.445)
				(type solid)
			)
			(fill no)
			(layer "F.Paste")
		)
		(fp_circle
			(center -19.685 -3.176)
			(end -19.464 -3.176)
			(stroke
				(width 0.445)
				(type solid)
			)
			(fill no)
			(layer "F.Paste")
		)
		(fp_circle
			(center -20.956 -3.176)
			(end -20.734 -3.176)
			(stroke
				(width 0.445)
				(type solid)
			)
			(fill no)
			(layer "F.Paste")
		)
		(fp_circle
			(center -22.226 -3.176)
			(end -22.003 -3.176)
			(stroke
				(width 0.445)
				(type solid)
			)
			(fill no)
			(layer "F.Paste")
		)
		(fp_circle
			(center -23.497 -3.176)
			(end -23.273 -3.176)
			(stroke
				(width 0.445)
				(type solid)
			)
			(fill no)
			(layer "F.Paste")
		)
		(fp_circle
			(center -24.767 -3.176)
			(end -24.543 -3.176)
			(stroke
				(width 0.445)
				(type solid)
			)
			(fill no)
			(layer "F.Paste")
		)
		(fp_circle
			(center 24.765 -1.905)
			(end 24.987 -1.905)
			(stroke
				(width 0.445)
				(type solid)
			)
			(fill no)
			(layer "F.Paste")
		)
		(fp_circle
			(center 23.495 -1.905)
			(end 23.716 -1.905)
			(stroke
				(width 0.445)
				(type solid)
			)
			(fill no)
			(layer "F.Paste")
		)
		(fp_circle
			(center 22.225 -1.905)
			(end 22.446 -1.905)
			(stroke
				(width 0.445)
				(type solid)
			)
			(fill no)
			(layer "F.Paste")
		)
		(fp_circle
			(center 20.954 -1.905)
			(end 21.176 -1.905)
			(stroke
				(width 0.445)
				(type solid)
			)
			(fill no)
			(layer "F.Paste")
		)
		(fp_circle
			(center 19.684 -1.905)
			(end 19.906 -1.905)
			(stroke
				(width 0.445)
				(type solid)
			)
			(fill no)
			(layer "F.Paste")
		)
		(fp_circle
			(center 18.414 -1.905)
			(end 18.637 -1.905)
			(stroke
				(width 0.445)
				(type solid)
			)
			(fill no)
			(layer "F.Paste")
		)
		(fp_circle
			(center 17.144 -1.905)
			(end 17.367 -1.905)
			(stroke
				(width 0.445)
				(type solid)
			)
			(fill no)
			(layer "F.Paste")
		)
		(fp_circle
			(center 15.874 -1.905)
			(end 16.097 -1.905)
			(stroke
				(width 0.445)
				(type solid)
			)
			(fill no)
			(layer "F.Paste")
		)
		(fp_circle
			(center 14.605 -1.905)
			(end 14.826 -1.905)
			(stroke
				(width 0.445)
				(type solid)
			)
			(fill no)
			(layer "F.Paste")
		)
		(fp_circle
			(center 13.335 -1.905)
			(end 13.557 -1.905)
			(stroke
				(width 0.445)
				(type solid)
			)
			(fill no)
			(layer "F.Paste")
		)
		(fp_circle
			(center 12.063 -1.905)
			(end 12.287 -1.905)
			(stroke
				(width 0.445)
				(type solid)
			)
			(fill no)
			(layer "F.Paste")
		)
		(fp_circle
			(center 10.794 -1.905)
			(end 11.016 -1.905)
			(stroke
				(width 0.445)
				(type solid)
			)
			(fill no)
			(layer "F.Paste")
		)
		(fp_circle
			(center 9.525 -1.905)
			(end 9.746 -1.905)
			(stroke
				(width 0.445)
				(type solid)
			)
			(fill no)
			(layer "F.Paste")
		)
		(fp_circle
			(center 8.255 -1.905)
			(end 8.477 -1.905)
			(stroke
				(width 0.445)
				(type solid)
			)
			(fill no)
			(layer "F.Paste")
		)
		(fp_circle
			(center 6.985 -1.905)
			(end 7.206 -1.905)
			(stroke
				(width 0.445)
				(type solid)
			)
			(fill no)
			(layer "F.Paste")
		)
		(fp_circle
			(center 5.714 -1.905)
			(end 5.937 -1.905)
			(stroke
				(width 0.445)
				(type solid)
			)
			(fill no)
			(layer "F.Paste")
		)
		(fp_circle
			(center 4.445 -1.905)
			(end 4.666 -1.905)
			(stroke
				(width 0.445)
				(type solid)
			)
			(fill no)
			(layer "F.Paste")
		)
		(fp_circle
			(center 3.173 -1.905)
			(end 3.397 -1.905)
			(stroke
				(width 0.445)
				(type solid)
			)
			(fill no)
			(layer "F.Paste")
		)
		(fp_circle
			(center 1.904 -1.905)
			(end 2.127 -1.905)
			(stroke
				(width 0.445)
				(type solid)
			)
			(fill no)
			(layer "F.Paste")
		)
		(fp_circle
			(center 0.633 -1.905)
			(end 0.856 -1.905)
			(stroke
				(width 0.445)
				(type solid)
			)
			(fill no)
			(layer "F.Paste")
		)
		(fp_circle
			(center -0.635 -1.905)
			(end -0.414 -1.905)
			(stroke
				(width 0.445)
				(type solid)
			)
			(fill no)
			(layer "F.Paste")
		)
		(fp_circle
			(center -1.905 -1.905)
			(end -1.684 -1.905)
			(stroke
				(width 0.445)
				(type solid)
			)
			(fill no)
			(layer "F.Paste")
		)
		(fp_circle
			(center -3.176 -1.905)
			(end -2.953 -1.905)
			(stroke
				(width 0.445)
				(type solid)
			)
			(fill no)
			(layer "F.Paste")
		)
		(fp_circle
			(center -4.446 -1.905)
			(end -4.223 -1.905)
			(stroke
				(width 0.445)
				(type solid)
			)
			(fill no)
			(layer "F.Paste")
		)
		(fp_circle
			(center -5.715 -1.905)
			(end -5.494 -1.905)
			(stroke
				(width 0.445)
				(type solid)
			)
			(fill no)
			(layer "F.Paste")
		)
		(fp_circle
			(center -6.986 -1.905)
			(end -6.763 -1.905)
			(stroke
				(width 0.445)
				(type solid)
			)
			(fill no)
			(layer "F.Paste")
		)
		(fp_circle
			(center -8.257 -1.905)
			(end -8.033 -1.905)
			(stroke
				(width 0.445)
				(type solid)
			)
			(fill no)
			(layer "F.Paste")
		)
		(fp_circle
			(center -9.526 -1.905)
			(end -9.304 -1.905)
			(stroke
				(width 0.445)
				(type solid)
			)
			(fill no)
			(layer "F.Paste")
		)
		(fp_circle
			(center -10.795 -1.905)
			(end -10.574 -1.905)
			(stroke
				(width 0.445)
				(type solid)
			)
			(fill no)
			(layer "F.Paste")
		)
		(fp_circle
			(center -12.065 -1.905)
			(end -11.843 -1.905)
			(stroke
				(width 0.445)
				(type solid)
			)
			(fill no)
			(layer "F.Paste")
		)
		(fp_circle
			(center -13.337 -1.905)
			(end -13.113 -1.905)
			(stroke
				(width 0.445)
				(type solid)
			)
			(fill no)
			(layer "F.Paste")
		)
		(fp_circle
			(center -14.606 -1.905)
			(end -14.384 -1.905)
			(stroke
				(width 0.445)
				(type solid)
			)
			(fill no)
			(layer "F.Paste")
		)
		(fp_circle
			(center -15.875 -1.905)
			(end -15.654 -1.905)
			(stroke
				(width 0.445)
				(type solid)
			)
			(fill no)
			(layer "F.Paste")
		)
		(fp_circle
			(center -17.145 -1.905)
			(end -16.924 -1.905)
			(stroke
				(width 0.445)
				(type solid)
			)
			(fill no)
			(layer "F.Paste")
		)
		(fp_circle
			(center -18.415 -1.905)
			(end -18.194 -1.905)
			(stroke
				(width 0.445)
				(type solid)
			)
			(fill no)
			(layer "F.Paste")
		)
		(fp_circle
			(center -19.685 -1.905)
			(end -19.464 -1.905)
			(stroke
				(width 0.445)
				(type solid)
			)
			(fill no)
			(layer "F.Paste")
		)
		(fp_circle
			(center -20.956 -1.905)
			(end -20.734 -1.905)
			(stroke
				(width 0.445)
				(type solid)
			)
			(fill no)
			(layer "F.Paste")
		)
		(fp_circle
			(center -22.226 -1.905)
			(end -22.003 -1.905)
			(stroke
				(width 0.445)
				(type solid)
			)
			(fill no)
			(layer "F.Paste")
		)
		(fp_circle
			(center -23.497 -1.905)
			(end -23.273 -1.905)
			(stroke
				(width 0.445)
				(type solid)
			)
			(fill no)
			(layer "F.Paste")
		)
		(fp_circle
			(center -24.767 -1.905)
			(end -24.543 -1.905)
			(stroke
				(width 0.445)
				(type solid)
			)
			(fill no)
			(layer "F.Paste")
		)
		(fp_circle
			(center 24.765 -0.635)
			(end 24.987 -0.635)
			(stroke
				(width 0.445)
				(type solid)
			)
			(fill no)
			(layer "F.Paste")
		)
		(fp_circle
			(center 23.495 -0.635)
			(end 23.716 -0.635)
			(stroke
				(width 0.445)
				(type solid)
			)
			(fill no)
			(layer "F.Paste")
		)
		(fp_circle
			(center 22.225 -0.635)
			(end 22.446 -0.635)
			(stroke
				(width 0.445)
				(type solid)
			)
			(fill no)
			(layer "F.Paste")
		)
		(fp_circle
			(center 20.954 -0.635)
			(end 21.176 -0.635)
			(stroke
				(width 0.445)
				(type solid)
			)
			(fill no)
			(layer "F.Paste")
		)
		(fp_circle
			(center 19.684 -0.635)
			(end 19.906 -0.635)
			(stroke
				(width 0.445)
				(type solid)
			)
			(fill no)
			(layer "F.Paste")
		)
		(fp_circle
			(center 18.414 -0.635)
			(end 18.637 -0.635)
			(stroke
				(width 0.445)
				(type solid)
			)
			(fill no)
			(layer "F.Paste")
		)
		(fp_circle
			(center 17.144 -0.635)
			(end 17.367 -0.635)
			(stroke
				(width 0.445)
				(type solid)
			)
			(fill no)
			(layer "F.Paste")
		)
		(fp_circle
			(center 15.874 -0.635)
			(end 16.097 -0.635)
			(stroke
				(width 0.445)
				(type solid)
			)
			(fill no)
			(layer "F.Paste")
		)
		(fp_circle
			(center 14.605 -0.635)
			(end 14.826 -0.635)
			(stroke
				(width 0.445)
				(type solid)
			)
			(fill no)
			(layer "F.Paste")
		)
		(fp_circle
			(center 13.335 -0.635)
			(end 13.557 -0.635)
			(stroke
				(width 0.445)
				(type solid)
			)
			(fill no)
			(layer "F.Paste")
		)
		(fp_circle
			(center 12.063 -0.635)
			(end 12.287 -0.635)
			(stroke
				(width 0.445)
				(type solid)
			)
			(fill no)
			(layer "F.Paste")
		)
		(fp_circle
			(center 10.794 -0.635)
			(end 11.016 -0.635)
			(stroke
				(width 0.445)
				(type solid)
			)
			(fill no)
			(layer "F.Paste")
		)
		(fp_circle
			(center 9.525 -0.635)
			(end 9.746 -0.635)
			(stroke
				(width 0.445)
				(type solid)
			)
			(fill no)
			(layer "F.Paste")
		)
		(fp_circle
			(center 8.255 -0.635)
			(end 8.477 -0.635)
			(stroke
				(width 0.445)
				(type solid)
			)
			(fill no)
			(layer "F.Paste")
		)
		(fp_circle
			(center 6.985 -0.635)
			(end 7.206 -0.635)
			(stroke
				(width 0.445)
				(type solid)
			)
			(fill no)
			(layer "F.Paste")
		)
		(fp_circle
			(center 5.714 -0.635)
			(end 5.937 -0.635)
			(stroke
				(width 0.445)
				(type solid)
			)
			(fill no)
			(layer "F.Paste")
		)
		(fp_circle
			(center 4.445 -0.635)
			(end 4.666 -0.635)
			(stroke
				(width 0.445)
				(type solid)
			)
			(fill no)
			(layer "F.Paste")
		)
		(fp_circle
			(center 3.173 -0.635)
			(end 3.397 -0.635)
			(stroke
				(width 0.445)
				(type solid)
			)
			(fill no)
			(layer "F.Paste")
		)
		(fp_circle
			(center 1.904 -0.635)
			(end 2.127 -0.635)
			(stroke
				(width 0.445)
				(type solid)
			)
			(fill no)
			(layer "F.Paste")
		)
		(fp_circle
			(center 0.633 -0.635)
			(end 0.856 -0.635)
			(stroke
				(width 0.445)
				(type solid)
			)
			(fill no)
			(layer "F.Paste")
		)
		(fp_circle
			(center -0.635 -0.635)
			(end -0.414 -0.635)
			(stroke
				(width 0.445)
				(type solid)
			)
			(fill no)
			(layer "F.Paste")
		)
		(fp_circle
			(center -1.905 -0.635)
			(end -1.684 -0.635)
			(stroke
				(width 0.445)
				(type solid)
			)
			(fill no)
			(layer "F.Paste")
		)
		(fp_circle
			(center -3.176 -0.635)
			(end -2.953 -0.635)
			(stroke
				(width 0.445)
				(type solid)
			)
			(fill no)
			(layer "F.Paste")
		)
		(fp_circle
			(center -4.446 -0.635)
			(end -4.223 -0.635)
			(stroke
				(width 0.445)
				(type solid)
			)
			(fill no)
			(layer "F.Paste")
		)
		(fp_circle
			(center -5.715 -0.635)
			(end -5.494 -0.635)
			(stroke
				(width 0.445)
				(type solid)
			)
			(fill no)
			(layer "F.Paste")
		)
		(fp_circle
			(center -6.986 -0.635)
			(end -6.763 -0.635)
			(stroke
				(width 0.445)
				(type solid)
			)
			(fill no)
			(layer "F.Paste")
		)
		(fp_circle
			(center -8.257 -0.635)
			(end -8.033 -0.635)
			(stroke
				(width 0.445)
				(type solid)
			)
			(fill no)
			(layer "F.Paste")
		)
		(fp_circle
			(center -9.526 -0.635)
			(end -9.304 -0.635)
			(stroke
				(width 0.445)
				(type solid)
			)
			(fill no)
			(layer "F.Paste")
		)
		(fp_circle
			(center -10.795 -0.635)
			(end -10.574 -0.635)
			(stroke
				(width 0.445)
				(type solid)
			)
			(fill no)
			(layer "F.Paste")
		)
		(fp_circle
			(center -12.065 -0.635)
			(end -11.843 -0.635)
			(stroke
				(width 0.445)
				(type solid)
			)
			(fill no)
			(layer "F.Paste")
		)
		(fp_circle
			(center -13.337 -0.635)
			(end -13.113 -0.635)
			(stroke
				(width 0.445)
				(type solid)
			)
			(fill no)
			(layer "F.Paste")
		)
		(fp_circle
			(center -14.606 -0.635)
			(end -14.384 -0.635)
			(stroke
				(width 0.445)
				(type solid)
			)
			(fill no)
			(layer "F.Paste")
		)
		(fp_circle
			(center -15.875 -0.635)
			(end -15.654 -0.635)
			(stroke
				(width 0.445)
				(type solid)
			)
			(fill no)
			(layer "F.Paste")
		)
		(fp_circle
			(center -17.145 -0.635)
			(end -16.924 -0.635)
			(stroke
				(width 0.445)
				(type solid)
			)
			(fill no)
			(layer "F.Paste")
		)
		(fp_circle
			(center -18.415 -0.635)
			(end -18.194 -0.635)
			(stroke
				(width 0.445)
				(type solid)
			)
			(fill no)
			(layer "F.Paste")
		)
		(fp_circle
			(center -19.685 -0.635)
			(end -19.464 -0.635)
			(stroke
				(width 0.445)
				(type solid)
			)
			(fill no)
			(layer "F.Paste")
		)
		(fp_circle
			(center -20.956 -0.635)
			(end -20.734 -0.635)
			(stroke
				(width 0.445)
				(type solid)
			)
			(fill no)
			(layer "F.Paste")
		)
		(fp_circle
			(center -22.226 -0.635)
			(end -22.003 -0.635)
			(stroke
				(width 0.445)
				(type solid)
			)
			(fill no)
			(layer "F.Paste")
		)
		(fp_circle
			(center -23.497 -0.635)
			(end -23.273 -0.635)
			(stroke
				(width 0.445)
				(type solid)
			)
			(fill no)
			(layer "F.Paste")
		)
		(fp_circle
			(center -24.767 -0.635)
			(end -24.543 -0.635)
			(stroke
				(width 0.445)
				(type solid)
			)
			(fill no)
			(layer "F.Paste")
		)
		(fp_circle
			(center 24.765 0.633)
			(end 24.987 0.633)
			(stroke
				(width 0.445)
				(type solid)
			)
			(fill no)
			(layer "F.Paste")
		)
		(fp_circle
			(center 23.495 0.633)
			(end 23.716 0.633)
			(stroke
				(width 0.445)
				(type solid)
			)
			(fill no)
			(layer "F.Paste")
		)
		(fp_circle
			(center 22.225 0.633)
			(end 22.446 0.633)
			(stroke
				(width 0.445)
				(type solid)
			)
			(fill no)
			(layer "F.Paste")
		)
		(fp_circle
			(center 20.954 0.633)
			(end 21.176 0.633)
			(stroke
				(width 0.445)
				(type solid)
			)
			(fill no)
			(layer "F.Paste")
		)
		(fp_circle
			(center 19.684 0.633)
			(end 19.906 0.633)
			(stroke
				(width 0.445)
				(type solid)
			)
			(fill no)
			(layer "F.Paste")
		)
		(fp_circle
			(center 18.414 0.633)
			(end 18.637 0.633)
			(stroke
				(width 0.445)
				(type solid)
			)
			(fill no)
			(layer "F.Paste")
		)
		(fp_circle
			(center 17.144 0.633)
			(end 17.367 0.633)
			(stroke
				(width 0.445)
				(type solid)
			)
			(fill no)
			(layer "F.Paste")
		)
		(fp_circle
			(center 15.874 0.633)
			(end 16.097 0.633)
			(stroke
				(width 0.445)
				(type solid)
			)
			(fill no)
			(layer "F.Paste")
		)
		(fp_circle
			(center 14.605 0.633)
			(end 14.826 0.633)
			(stroke
				(width 0.445)
				(type solid)
			)
			(fill no)
			(layer "F.Paste")
		)
		(fp_circle
			(center 13.335 0.633)
			(end 13.557 0.633)
			(stroke
				(width 0.445)
				(type solid)
			)
			(fill no)
			(layer "F.Paste")
		)
		(fp_circle
			(center 12.063 0.633)
			(end 12.287 0.633)
			(stroke
				(width 0.445)
				(type solid)
			)
			(fill no)
			(layer "F.Paste")
		)
		(fp_circle
			(center 10.794 0.633)
			(end 11.016 0.633)
			(stroke
				(width 0.445)
				(type solid)
			)
			(fill no)
			(layer "F.Paste")
		)
		(fp_circle
			(center 9.525 0.633)
			(end 9.746 0.633)
			(stroke
				(width 0.445)
				(type solid)
			)
			(fill no)
			(layer "F.Paste")
		)
		(fp_circle
			(center 8.255 0.633)
			(end 8.477 0.633)
			(stroke
				(width 0.445)
				(type solid)
			)
			(fill no)
			(layer "F.Paste")
		)
		(fp_circle
			(center 6.985 0.633)
			(end 7.206 0.633)
			(stroke
				(width 0.445)
				(type solid)
			)
			(fill no)
			(layer "F.Paste")
		)
		(fp_circle
			(center 5.714 0.633)
			(end 5.937 0.633)
			(stroke
				(width 0.445)
				(type solid)
			)
			(fill no)
			(layer "F.Paste")
		)
		(fp_circle
			(center 4.445 0.633)
			(end 4.666 0.633)
			(stroke
				(width 0.445)
				(type solid)
			)
			(fill no)
			(layer "F.Paste")
		)
		(fp_circle
			(center 3.173 0.633)
			(end 3.397 0.633)
			(stroke
				(width 0.445)
				(type solid)
			)
			(fill no)
			(layer "F.Paste")
		)
		(fp_circle
			(center 1.904 0.633)
			(end 2.127 0.633)
			(stroke
				(width 0.445)
				(type solid)
			)
			(fill no)
			(layer "F.Paste")
		)
		(fp_circle
			(center 0.633 0.633)
			(end 0.856 0.633)
			(stroke
				(width 0.445)
				(type solid)
			)
			(fill no)
			(layer "F.Paste")
		)
		(fp_circle
			(center -0.635 0.633)
			(end -0.414 0.633)
			(stroke
				(width 0.445)
				(type solid)
			)
			(fill no)
			(layer "F.Paste")
		)
		(fp_circle
			(center -1.905 0.633)
			(end -1.684 0.633)
			(stroke
				(width 0.445)
				(type solid)
			)
			(fill no)
			(layer "F.Paste")
		)
		(fp_circle
			(center -3.176 0.633)
			(end -2.953 0.633)
			(stroke
				(width 0.445)
				(type solid)
			)
			(fill no)
			(layer "F.Paste")
		)
		(fp_circle
			(center -4.446 0.633)
			(end -4.223 0.633)
			(stroke
				(width 0.445)
				(type solid)
			)
			(fill no)
			(layer "F.Paste")
		)
		(fp_circle
			(center -5.715 0.633)
			(end -5.494 0.633)
			(stroke
				(width 0.445)
				(type solid)
			)
			(fill no)
			(layer "F.Paste")
		)
		(fp_circle
			(center -6.986 0.633)
			(end -6.763 0.633)
			(stroke
				(width 0.445)
				(type solid)
			)
			(fill no)
			(layer "F.Paste")
		)
		(fp_circle
			(center -8.257 0.633)
			(end -8.033 0.633)
			(stroke
				(width 0.445)
				(type solid)
			)
			(fill no)
			(layer "F.Paste")
		)
		(fp_circle
			(center -9.526 0.633)
			(end -9.304 0.633)
			(stroke
				(width 0.445)
				(type solid)
			)
			(fill no)
			(layer "F.Paste")
		)
		(fp_circle
			(center -10.795 0.633)
			(end -10.574 0.633)
			(stroke
				(width 0.445)
				(type solid)
			)
			(fill no)
			(layer "F.Paste")
		)
		(fp_circle
			(center -12.065 0.633)
			(end -11.843 0.633)
			(stroke
				(width 0.445)
				(type solid)
			)
			(fill no)
			(layer "F.Paste")
		)
		(fp_circle
			(center -13.337 0.633)
			(end -13.113 0.633)
			(stroke
				(width 0.445)
				(type solid)
			)
			(fill no)
			(layer "F.Paste")
		)
		(fp_circle
			(center -14.606 0.633)
			(end -14.384 0.633)
			(stroke
				(width 0.445)
				(type solid)
			)
			(fill no)
			(layer "F.Paste")
		)
		(fp_circle
			(center -15.875 0.633)
			(end -15.654 0.633)
			(stroke
				(width 0.445)
				(type solid)
			)
			(fill no)
			(layer "F.Paste")
		)
		(fp_circle
			(center -17.145 0.633)
			(end -16.924 0.633)
			(stroke
				(width 0.445)
				(type solid)
			)
			(fill no)
			(layer "F.Paste")
		)
		(fp_circle
			(center -18.415 0.633)
			(end -18.194 0.633)
			(stroke
				(width 0.445)
				(type solid)
			)
			(fill no)
			(layer "F.Paste")
		)
		(fp_circle
			(center -19.685 0.633)
			(end -19.464 0.633)
			(stroke
				(width 0.445)
				(type solid)
			)
			(fill no)
			(layer "F.Paste")
		)
		(fp_circle
			(center -20.956 0.633)
			(end -20.734 0.633)
			(stroke
				(width 0.445)
				(type solid)
			)
			(fill no)
			(layer "F.Paste")
		)
		(fp_circle
			(center -22.226 0.633)
			(end -22.003 0.633)
			(stroke
				(width 0.445)
				(type solid)
			)
			(fill no)
			(layer "F.Paste")
		)
		(fp_circle
			(center -23.497 0.633)
			(end -23.273 0.633)
			(stroke
				(width 0.445)
				(type solid)
			)
			(fill no)
			(layer "F.Paste")
		)
		(fp_circle
			(center -24.767 0.633)
			(end -24.543 0.633)
			(stroke
				(width 0.445)
				(type solid)
			)
			(fill no)
			(layer "F.Paste")
		)
		(fp_circle
			(center 24.765 1.904)
			(end 24.987 1.904)
			(stroke
				(width 0.445)
				(type solid)
			)
			(fill no)
			(layer "F.Paste")
		)
		(fp_circle
			(center 23.495 1.904)
			(end 23.716 1.904)
			(stroke
				(width 0.445)
				(type solid)
			)
			(fill no)
			(layer "F.Paste")
		)
		(fp_circle
			(center 22.225 1.904)
			(end 22.446 1.904)
			(stroke
				(width 0.445)
				(type solid)
			)
			(fill no)
			(layer "F.Paste")
		)
		(fp_circle
			(center 20.954 1.904)
			(end 21.176 1.904)
			(stroke
				(width 0.445)
				(type solid)
			)
			(fill no)
			(layer "F.Paste")
		)
		(fp_circle
			(center 19.684 1.904)
			(end 19.906 1.904)
			(stroke
				(width 0.445)
				(type solid)
			)
			(fill no)
			(layer "F.Paste")
		)
		(fp_circle
			(center 18.414 1.904)
			(end 18.637 1.904)
			(stroke
				(width 0.445)
				(type solid)
			)
			(fill no)
			(layer "F.Paste")
		)
		(fp_circle
			(center 17.144 1.904)
			(end 17.367 1.904)
			(stroke
				(width 0.445)
				(type solid)
			)
			(fill no)
			(layer "F.Paste")
		)
		(fp_circle
			(center 15.874 1.904)
			(end 16.097 1.904)
			(stroke
				(width 0.445)
				(type solid)
			)
			(fill no)
			(layer "F.Paste")
		)
		(fp_circle
			(center 14.605 1.904)
			(end 14.826 1.904)
			(stroke
				(width 0.445)
				(type solid)
			)
			(fill no)
			(layer "F.Paste")
		)
		(fp_circle
			(center 13.335 1.904)
			(end 13.557 1.904)
			(stroke
				(width 0.445)
				(type solid)
			)
			(fill no)
			(layer "F.Paste")
		)
		(fp_circle
			(center 12.063 1.904)
			(end 12.287 1.904)
			(stroke
				(width 0.445)
				(type solid)
			)
			(fill no)
			(layer "F.Paste")
		)
		(fp_circle
			(center 10.794 1.904)
			(end 11.016 1.904)
			(stroke
				(width 0.445)
				(type solid)
			)
			(fill no)
			(layer "F.Paste")
		)
		(fp_circle
			(center 9.525 1.904)
			(end 9.746 1.904)
			(stroke
				(width 0.445)
				(type solid)
			)
			(fill no)
			(layer "F.Paste")
		)
		(fp_circle
			(center 8.255 1.904)
			(end 8.477 1.904)
			(stroke
				(width 0.445)
				(type solid)
			)
			(fill no)
			(layer "F.Paste")
		)
		(fp_circle
			(center 6.985 1.904)
			(end 7.206 1.904)
			(stroke
				(width 0.445)
				(type solid)
			)
			(fill no)
			(layer "F.Paste")
		)
		(fp_circle
			(center 5.714 1.904)
			(end 5.937 1.904)
			(stroke
				(width 0.445)
				(type solid)
			)
			(fill no)
			(layer "F.Paste")
		)
		(fp_circle
			(center 4.445 1.904)
			(end 4.666 1.904)
			(stroke
				(width 0.445)
				(type solid)
			)
			(fill no)
			(layer "F.Paste")
		)
		(fp_circle
			(center 3.173 1.904)
			(end 3.397 1.904)
			(stroke
				(width 0.445)
				(type solid)
			)
			(fill no)
			(layer "F.Paste")
		)
		(fp_circle
			(center 1.904 1.904)
			(end 2.127 1.904)
			(stroke
				(width 0.445)
				(type solid)
			)
			(fill no)
			(layer "F.Paste")
		)
		(fp_circle
			(center 0.633 1.904)
			(end 0.856 1.904)
			(stroke
				(width 0.445)
				(type solid)
			)
			(fill no)
			(layer "F.Paste")
		)
		(fp_circle
			(center -0.635 1.904)
			(end -0.414 1.904)
			(stroke
				(width 0.445)
				(type solid)
			)
			(fill no)
			(layer "F.Paste")
		)
		(fp_circle
			(center -1.905 1.904)
			(end -1.684 1.904)
			(stroke
				(width 0.445)
				(type solid)
			)
			(fill no)
			(layer "F.Paste")
		)
		(fp_circle
			(center -3.176 1.904)
			(end -2.953 1.904)
			(stroke
				(width 0.445)
				(type solid)
			)
			(fill no)
			(layer "F.Paste")
		)
		(fp_circle
			(center -4.446 1.904)
			(end -4.223 1.904)
			(stroke
				(width 0.445)
				(type solid)
			)
			(fill no)
			(layer "F.Paste")
		)
		(fp_circle
			(center -5.715 1.904)
			(end -5.494 1.904)
			(stroke
				(width 0.445)
				(type solid)
			)
			(fill no)
			(layer "F.Paste")
		)
		(fp_circle
			(center -6.986 1.904)
			(end -6.763 1.904)
			(stroke
				(width 0.445)
				(type solid)
			)
			(fill no)
			(layer "F.Paste")
		)
		(fp_circle
			(center -8.257 1.904)
			(end -8.033 1.904)
			(stroke
				(width 0.445)
				(type solid)
			)
			(fill no)
			(layer "F.Paste")
		)
		(fp_circle
			(center -9.526 1.904)
			(end -9.304 1.904)
			(stroke
				(width 0.445)
				(type solid)
			)
			(fill no)
			(layer "F.Paste")
		)
		(fp_circle
			(center -10.795 1.904)
			(end -10.574 1.904)
			(stroke
				(width 0.445)
				(type solid)
			)
			(fill no)
			(layer "F.Paste")
		)
		(fp_circle
			(center -12.065 1.904)
			(end -11.843 1.904)
			(stroke
				(width 0.445)
				(type solid)
			)
			(fill no)
			(layer "F.Paste")
		)
		(fp_circle
			(center -13.337 1.904)
			(end -13.113 1.904)
			(stroke
				(width 0.445)
				(type solid)
			)
			(fill no)
			(layer "F.Paste")
		)
		(fp_circle
			(center -14.606 1.904)
			(end -14.384 1.904)
			(stroke
				(width 0.445)
				(type solid)
			)
			(fill no)
			(layer "F.Paste")
		)
		(fp_circle
			(center -15.875 1.904)
			(end -15.654 1.904)
			(stroke
				(width 0.445)
				(type solid)
			)
			(fill no)
			(layer "F.Paste")
		)
		(fp_circle
			(center -17.145 1.904)
			(end -16.924 1.904)
			(stroke
				(width 0.445)
				(type solid)
			)
			(fill no)
			(layer "F.Paste")
		)
		(fp_circle
			(center -18.415 1.904)
			(end -18.194 1.904)
			(stroke
				(width 0.445)
				(type solid)
			)
			(fill no)
			(layer "F.Paste")
		)
		(fp_circle
			(center -19.685 1.904)
			(end -19.464 1.904)
			(stroke
				(width 0.445)
				(type solid)
			)
			(fill no)
			(layer "F.Paste")
		)
		(fp_circle
			(center -20.956 1.904)
			(end -20.734 1.904)
			(stroke
				(width 0.445)
				(type solid)
			)
			(fill no)
			(layer "F.Paste")
		)
		(fp_circle
			(center -22.226 1.904)
			(end -22.003 1.904)
			(stroke
				(width 0.445)
				(type solid)
			)
			(fill no)
			(layer "F.Paste")
		)
		(fp_circle
			(center -23.497 1.904)
			(end -23.273 1.904)
			(stroke
				(width 0.445)
				(type solid)
			)
			(fill no)
			(layer "F.Paste")
		)
		(fp_circle
			(center -24.767 1.904)
			(end -24.543 1.904)
			(stroke
				(width 0.445)
				(type solid)
			)
			(fill no)
			(layer "F.Paste")
		)
		(fp_circle
			(center 24.765 3.173)
			(end 24.987 3.173)
			(stroke
				(width 0.445)
				(type solid)
			)
			(fill no)
			(layer "F.Paste")
		)
		(fp_circle
			(center 23.495 3.173)
			(end 23.716 3.173)
			(stroke
				(width 0.445)
				(type solid)
			)
			(fill no)
			(layer "F.Paste")
		)
		(fp_circle
			(center 22.225 3.173)
			(end 22.446 3.173)
			(stroke
				(width 0.445)
				(type solid)
			)
			(fill no)
			(layer "F.Paste")
		)
		(fp_circle
			(center 20.954 3.173)
			(end 21.176 3.173)
			(stroke
				(width 0.445)
				(type solid)
			)
			(fill no)
			(layer "F.Paste")
		)
		(fp_circle
			(center 19.684 3.173)
			(end 19.906 3.173)
			(stroke
				(width 0.445)
				(type solid)
			)
			(fill no)
			(layer "F.Paste")
		)
		(fp_circle
			(center 18.414 3.173)
			(end 18.637 3.173)
			(stroke
				(width 0.445)
				(type solid)
			)
			(fill no)
			(layer "F.Paste")
		)
		(fp_circle
			(center 17.144 3.173)
			(end 17.367 3.173)
			(stroke
				(width 0.445)
				(type solid)
			)
			(fill no)
			(layer "F.Paste")
		)
		(fp_circle
			(center 15.874 3.173)
			(end 16.097 3.173)
			(stroke
				(width 0.445)
				(type solid)
			)
			(fill no)
			(layer "F.Paste")
		)
		(fp_circle
			(center 14.605 3.173)
			(end 14.826 3.173)
			(stroke
				(width 0.445)
				(type solid)
			)
			(fill no)
			(layer "F.Paste")
		)
		(fp_circle
			(center 13.335 3.173)
			(end 13.557 3.173)
			(stroke
				(width 0.445)
				(type solid)
			)
			(fill no)
			(layer "F.Paste")
		)
		(fp_circle
			(center 12.063 3.173)
			(end 12.287 3.173)
			(stroke
				(width 0.445)
				(type solid)
			)
			(fill no)
			(layer "F.Paste")
		)
		(fp_circle
			(center 10.794 3.173)
			(end 11.016 3.173)
			(stroke
				(width 0.445)
				(type solid)
			)
			(fill no)
			(layer "F.Paste")
		)
		(fp_circle
			(center 9.525 3.173)
			(end 9.746 3.173)
			(stroke
				(width 0.445)
				(type solid)
			)
			(fill no)
			(layer "F.Paste")
		)
		(fp_circle
			(center 8.255 3.173)
			(end 8.477 3.173)
			(stroke
				(width 0.445)
				(type solid)
			)
			(fill no)
			(layer "F.Paste")
		)
		(fp_circle
			(center 6.985 3.173)
			(end 7.206 3.173)
			(stroke
				(width 0.445)
				(type solid)
			)
			(fill no)
			(layer "F.Paste")
		)
		(fp_circle
			(center 5.714 3.173)
			(end 5.937 3.173)
			(stroke
				(width 0.445)
				(type solid)
			)
			(fill no)
			(layer "F.Paste")
		)
		(fp_circle
			(center 4.445 3.173)
			(end 4.666 3.173)
			(stroke
				(width 0.445)
				(type solid)
			)
			(fill no)
			(layer "F.Paste")
		)
		(fp_circle
			(center 3.173 3.173)
			(end 3.397 3.173)
			(stroke
				(width 0.445)
				(type solid)
			)
			(fill no)
			(layer "F.Paste")
		)
		(fp_circle
			(center 1.904 3.173)
			(end 2.127 3.173)
			(stroke
				(width 0.445)
				(type solid)
			)
			(fill no)
			(layer "F.Paste")
		)
		(fp_circle
			(center 0.633 3.173)
			(end 0.856 3.173)
			(stroke
				(width 0.445)
				(type solid)
			)
			(fill no)
			(layer "F.Paste")
		)
		(fp_circle
			(center -0.635 3.173)
			(end -0.414 3.173)
			(stroke
				(width 0.445)
				(type solid)
			)
			(fill no)
			(layer "F.Paste")
		)
		(fp_circle
			(center -1.905 3.173)
			(end -1.684 3.173)
			(stroke
				(width 0.445)
				(type solid)
			)
			(fill no)
			(layer "F.Paste")
		)
		(fp_circle
			(center -3.176 3.173)
			(end -2.953 3.173)
			(stroke
				(width 0.445)
				(type solid)
			)
			(fill no)
			(layer "F.Paste")
		)
		(fp_circle
			(center -4.446 3.173)
			(end -4.223 3.173)
			(stroke
				(width 0.445)
				(type solid)
			)
			(fill no)
			(layer "F.Paste")
		)
		(fp_circle
			(center -5.715 3.173)
			(end -5.494 3.173)
			(stroke
				(width 0.445)
				(type solid)
			)
			(fill no)
			(layer "F.Paste")
		)
		(fp_circle
			(center -6.986 3.173)
			(end -6.763 3.173)
			(stroke
				(width 0.445)
				(type solid)
			)
			(fill no)
			(layer "F.Paste")
		)
		(fp_circle
			(center -8.257 3.173)
			(end -8.033 3.173)
			(stroke
				(width 0.445)
				(type solid)
			)
			(fill no)
			(layer "F.Paste")
		)
		(fp_circle
			(center -9.526 3.173)
			(end -9.304 3.173)
			(stroke
				(width 0.445)
				(type solid)
			)
			(fill no)
			(layer "F.Paste")
		)
		(fp_circle
			(center -10.795 3.173)
			(end -10.574 3.173)
			(stroke
				(width 0.445)
				(type solid)
			)
			(fill no)
			(layer "F.Paste")
		)
		(fp_circle
			(center -12.065 3.173)
			(end -11.843 3.173)
			(stroke
				(width 0.445)
				(type solid)
			)
			(fill no)
			(layer "F.Paste")
		)
		(fp_circle
			(center -13.337 3.173)
			(end -13.113 3.173)
			(stroke
				(width 0.445)
				(type solid)
			)
			(fill no)
			(layer "F.Paste")
		)
		(fp_circle
			(center -14.606 3.173)
			(end -14.384 3.173)
			(stroke
				(width 0.445)
				(type solid)
			)
			(fill no)
			(layer "F.Paste")
		)
		(fp_circle
			(center -15.875 3.173)
			(end -15.654 3.173)
			(stroke
				(width 0.445)
				(type solid)
			)
			(fill no)
			(layer "F.Paste")
		)
		(fp_circle
			(center -17.145 3.173)
			(end -16.924 3.173)
			(stroke
				(width 0.445)
				(type solid)
			)
			(fill no)
			(layer "F.Paste")
		)
		(fp_circle
			(center -18.415 3.173)
			(end -18.194 3.173)
			(stroke
				(width 0.445)
				(type solid)
			)
			(fill no)
			(layer "F.Paste")
		)
		(fp_circle
			(center -19.685 3.173)
			(end -19.464 3.173)
			(stroke
				(width 0.445)
				(type solid)
			)
			(fill no)
			(layer "F.Paste")
		)
		(fp_circle
			(center -20.956 3.173)
			(end -20.734 3.173)
			(stroke
				(width 0.445)
				(type solid)
			)
			(fill no)
			(layer "F.Paste")
		)
		(fp_circle
			(center -22.226 3.173)
			(end -22.003 3.173)
			(stroke
				(width 0.445)
				(type solid)
			)
			(fill no)
			(layer "F.Paste")
		)
		(fp_circle
			(center -23.497 3.173)
			(end -23.273 3.173)
			(stroke
				(width 0.445)
				(type solid)
			)
			(fill no)
			(layer "F.Paste")
		)
		(fp_circle
			(center -24.767 3.173)
			(end -24.543 3.173)
			(stroke
				(width 0.445)
				(type solid)
			)
			(fill no)
			(layer "F.Paste")
		)
		(fp_circle
			(center 24.765 4.445)
			(end 24.987 4.445)
			(stroke
				(width 0.445)
				(type solid)
			)
			(fill no)
			(layer "F.Paste")
		)
		(fp_circle
			(center 23.495 4.445)
			(end 23.716 4.445)
			(stroke
				(width 0.445)
				(type solid)
			)
			(fill no)
			(layer "F.Paste")
		)
		(fp_circle
			(center 22.225 4.445)
			(end 22.446 4.445)
			(stroke
				(width 0.445)
				(type solid)
			)
			(fill no)
			(layer "F.Paste")
		)
		(fp_circle
			(center 20.954 4.445)
			(end 21.176 4.445)
			(stroke
				(width 0.445)
				(type solid)
			)
			(fill no)
			(layer "F.Paste")
		)
		(fp_circle
			(center 19.684 4.445)
			(end 19.906 4.445)
			(stroke
				(width 0.445)
				(type solid)
			)
			(fill no)
			(layer "F.Paste")
		)
		(fp_circle
			(center 18.414 4.445)
			(end 18.637 4.445)
			(stroke
				(width 0.445)
				(type solid)
			)
			(fill no)
			(layer "F.Paste")
		)
		(fp_circle
			(center 17.144 4.445)
			(end 17.367 4.445)
			(stroke
				(width 0.445)
				(type solid)
			)
			(fill no)
			(layer "F.Paste")
		)
		(fp_circle
			(center 15.874 4.445)
			(end 16.097 4.445)
			(stroke
				(width 0.445)
				(type solid)
			)
			(fill no)
			(layer "F.Paste")
		)
		(fp_circle
			(center 14.605 4.445)
			(end 14.826 4.445)
			(stroke
				(width 0.445)
				(type solid)
			)
			(fill no)
			(layer "F.Paste")
		)
		(fp_circle
			(center 13.335 4.445)
			(end 13.557 4.445)
			(stroke
				(width 0.445)
				(type solid)
			)
			(fill no)
			(layer "F.Paste")
		)
		(fp_circle
			(center 12.063 4.445)
			(end 12.287 4.445)
			(stroke
				(width 0.445)
				(type solid)
			)
			(fill no)
			(layer "F.Paste")
		)
		(fp_circle
			(center 10.794 4.445)
			(end 11.016 4.445)
			(stroke
				(width 0.445)
				(type solid)
			)
			(fill no)
			(layer "F.Paste")
		)
		(fp_circle
			(center 9.525 4.445)
			(end 9.746 4.445)
			(stroke
				(width 0.445)
				(type solid)
			)
			(fill no)
			(layer "F.Paste")
		)
		(fp_circle
			(center 8.255 4.445)
			(end 8.477 4.445)
			(stroke
				(width 0.445)
				(type solid)
			)
			(fill no)
			(layer "F.Paste")
		)
		(fp_circle
			(center 6.985 4.445)
			(end 7.206 4.445)
			(stroke
				(width 0.445)
				(type solid)
			)
			(fill no)
			(layer "F.Paste")
		)
		(fp_circle
			(center 5.714 4.445)
			(end 5.937 4.445)
			(stroke
				(width 0.445)
				(type solid)
			)
			(fill no)
			(layer "F.Paste")
		)
		(fp_circle
			(center 4.445 4.445)
			(end 4.666 4.445)
			(stroke
				(width 0.445)
				(type solid)
			)
			(fill no)
			(layer "F.Paste")
		)
		(fp_circle
			(center 3.173 4.445)
			(end 3.397 4.445)
			(stroke
				(width 0.445)
				(type solid)
			)
			(fill no)
			(layer "F.Paste")
		)
		(fp_circle
			(center 1.904 4.445)
			(end 2.127 4.445)
			(stroke
				(width 0.445)
				(type solid)
			)
			(fill no)
			(layer "F.Paste")
		)
		(fp_circle
			(center 0.633 4.445)
			(end 0.856 4.445)
			(stroke
				(width 0.445)
				(type solid)
			)
			(fill no)
			(layer "F.Paste")
		)
		(fp_circle
			(center -0.635 4.445)
			(end -0.414 4.445)
			(stroke
				(width 0.445)
				(type solid)
			)
			(fill no)
			(layer "F.Paste")
		)
		(fp_circle
			(center -1.905 4.445)
			(end -1.684 4.445)
			(stroke
				(width 0.445)
				(type solid)
			)
			(fill no)
			(layer "F.Paste")
		)
		(fp_circle
			(center -3.176 4.445)
			(end -2.953 4.445)
			(stroke
				(width 0.445)
				(type solid)
			)
			(fill no)
			(layer "F.Paste")
		)
		(fp_circle
			(center -4.446 4.445)
			(end -4.223 4.445)
			(stroke
				(width 0.445)
				(type solid)
			)
			(fill no)
			(layer "F.Paste")
		)
		(fp_circle
			(center -5.715 4.445)
			(end -5.494 4.445)
			(stroke
				(width 0.445)
				(type solid)
			)
			(fill no)
			(layer "F.Paste")
		)
		(fp_circle
			(center -6.986 4.445)
			(end -6.763 4.445)
			(stroke
				(width 0.445)
				(type solid)
			)
			(fill no)
			(layer "F.Paste")
		)
		(fp_circle
			(center -8.257 4.445)
			(end -8.033 4.445)
			(stroke
				(width 0.445)
				(type solid)
			)
			(fill no)
			(layer "F.Paste")
		)
		(fp_circle
			(center -9.526 4.445)
			(end -9.304 4.445)
			(stroke
				(width 0.445)
				(type solid)
			)
			(fill no)
			(layer "F.Paste")
		)
		(fp_circle
			(center -10.795 4.445)
			(end -10.574 4.445)
			(stroke
				(width 0.445)
				(type solid)
			)
			(fill no)
			(layer "F.Paste")
		)
		(fp_circle
			(center -12.065 4.445)
			(end -11.843 4.445)
			(stroke
				(width 0.445)
				(type solid)
			)
			(fill no)
			(layer "F.Paste")
		)
		(fp_circle
			(center -13.337 4.445)
			(end -13.113 4.445)
			(stroke
				(width 0.445)
				(type solid)
			)
			(fill no)
			(layer "F.Paste")
		)
		(fp_circle
			(center -14.606 4.445)
			(end -14.384 4.445)
			(stroke
				(width 0.445)
				(type solid)
			)
			(fill no)
			(layer "F.Paste")
		)
		(fp_circle
			(center -15.875 4.445)
			(end -15.654 4.445)
			(stroke
				(width 0.445)
				(type solid)
			)
			(fill no)
			(layer "F.Paste")
		)
		(fp_circle
			(center -17.145 4.445)
			(end -16.924 4.445)
			(stroke
				(width 0.445)
				(type solid)
			)
			(fill no)
			(layer "F.Paste")
		)
		(fp_circle
			(center -18.415 4.445)
			(end -18.194 4.445)
			(stroke
				(width 0.445)
				(type solid)
			)
			(fill no)
			(layer "F.Paste")
		)
		(fp_circle
			(center -19.685 4.445)
			(end -19.464 4.445)
			(stroke
				(width 0.445)
				(type solid)
			)
			(fill no)
			(layer "F.Paste")
		)
		(fp_circle
			(center -20.956 4.445)
			(end -20.734 4.445)
			(stroke
				(width 0.445)
				(type solid)
			)
			(fill no)
			(layer "F.Paste")
		)
		(fp_circle
			(center -22.226 4.445)
			(end -22.003 4.445)
			(stroke
				(width 0.445)
				(type solid)
			)
			(fill no)
			(layer "F.Paste")
		)
		(fp_circle
			(center -23.497 4.445)
			(end -23.273 4.445)
			(stroke
				(width 0.445)
				(type solid)
			)
			(fill no)
			(layer "F.Paste")
		)
		(fp_circle
			(center -24.767 4.445)
			(end -24.543 4.445)
			(stroke
				(width 0.445)
				(type solid)
			)
			(fill no)
			(layer "F.Paste")
		)
		(fp_circle
			(center 24.765 5.714)
			(end 24.987 5.714)
			(stroke
				(width 0.445)
				(type solid)
			)
			(fill no)
			(layer "F.Paste")
		)
		(fp_circle
			(center 23.495 5.714)
			(end 23.716 5.714)
			(stroke
				(width 0.445)
				(type solid)
			)
			(fill no)
			(layer "F.Paste")
		)
		(fp_circle
			(center 22.225 5.714)
			(end 22.446 5.714)
			(stroke
				(width 0.445)
				(type solid)
			)
			(fill no)
			(layer "F.Paste")
		)
		(fp_circle
			(center 20.954 5.714)
			(end 21.176 5.714)
			(stroke
				(width 0.445)
				(type solid)
			)
			(fill no)
			(layer "F.Paste")
		)
		(fp_circle
			(center 19.684 5.714)
			(end 19.906 5.714)
			(stroke
				(width 0.445)
				(type solid)
			)
			(fill no)
			(layer "F.Paste")
		)
		(fp_circle
			(center 18.414 5.714)
			(end 18.637 5.714)
			(stroke
				(width 0.445)
				(type solid)
			)
			(fill no)
			(layer "F.Paste")
		)
		(fp_circle
			(center 17.144 5.714)
			(end 17.367 5.714)
			(stroke
				(width 0.445)
				(type solid)
			)
			(fill no)
			(layer "F.Paste")
		)
		(fp_circle
			(center 15.874 5.714)
			(end 16.097 5.714)
			(stroke
				(width 0.445)
				(type solid)
			)
			(fill no)
			(layer "F.Paste")
		)
		(fp_circle
			(center 14.605 5.714)
			(end 14.826 5.714)
			(stroke
				(width 0.445)
				(type solid)
			)
			(fill no)
			(layer "F.Paste")
		)
		(fp_circle
			(center 13.335 5.714)
			(end 13.557 5.714)
			(stroke
				(width 0.445)
				(type solid)
			)
			(fill no)
			(layer "F.Paste")
		)
		(fp_circle
			(center 12.063 5.714)
			(end 12.287 5.714)
			(stroke
				(width 0.445)
				(type solid)
			)
			(fill no)
			(layer "F.Paste")
		)
		(fp_circle
			(center 10.794 5.714)
			(end 11.016 5.714)
			(stroke
				(width 0.445)
				(type solid)
			)
			(fill no)
			(layer "F.Paste")
		)
		(fp_circle
			(center 9.525 5.714)
			(end 9.746 5.714)
			(stroke
				(width 0.445)
				(type solid)
			)
			(fill no)
			(layer "F.Paste")
		)
		(fp_circle
			(center 8.255 5.714)
			(end 8.477 5.714)
			(stroke
				(width 0.445)
				(type solid)
			)
			(fill no)
			(layer "F.Paste")
		)
		(fp_circle
			(center 6.985 5.714)
			(end 7.206 5.714)
			(stroke
				(width 0.445)
				(type solid)
			)
			(fill no)
			(layer "F.Paste")
		)
		(fp_circle
			(center 5.714 5.714)
			(end 5.937 5.714)
			(stroke
				(width 0.445)
				(type solid)
			)
			(fill no)
			(layer "F.Paste")
		)
		(fp_circle
			(center 4.445 5.714)
			(end 4.666 5.714)
			(stroke
				(width 0.445)
				(type solid)
			)
			(fill no)
			(layer "F.Paste")
		)
		(fp_circle
			(center 3.173 5.714)
			(end 3.397 5.714)
			(stroke
				(width 0.445)
				(type solid)
			)
			(fill no)
			(layer "F.Paste")
		)
		(fp_circle
			(center 1.904 5.714)
			(end 2.127 5.714)
			(stroke
				(width 0.445)
				(type solid)
			)
			(fill no)
			(layer "F.Paste")
		)
		(fp_circle
			(center 0.633 5.714)
			(end 0.856 5.714)
			(stroke
				(width 0.445)
				(type solid)
			)
			(fill no)
			(layer "F.Paste")
		)
		(fp_circle
			(center -0.635 5.714)
			(end -0.414 5.714)
			(stroke
				(width 0.445)
				(type solid)
			)
			(fill no)
			(layer "F.Paste")
		)
		(fp_circle
			(center -1.905 5.714)
			(end -1.684 5.714)
			(stroke
				(width 0.445)
				(type solid)
			)
			(fill no)
			(layer "F.Paste")
		)
		(fp_circle
			(center -3.176 5.714)
			(end -2.953 5.714)
			(stroke
				(width 0.445)
				(type solid)
			)
			(fill no)
			(layer "F.Paste")
		)
		(fp_circle
			(center -4.446 5.714)
			(end -4.223 5.714)
			(stroke
				(width 0.445)
				(type solid)
			)
			(fill no)
			(layer "F.Paste")
		)
		(fp_circle
			(center -5.715 5.714)
			(end -5.494 5.714)
			(stroke
				(width 0.445)
				(type solid)
			)
			(fill no)
			(layer "F.Paste")
		)
		(fp_circle
			(center -6.986 5.714)
			(end -6.763 5.714)
			(stroke
				(width 0.445)
				(type solid)
			)
			(fill no)
			(layer "F.Paste")
		)
		(fp_circle
			(center -8.257 5.714)
			(end -8.033 5.714)
			(stroke
				(width 0.445)
				(type solid)
			)
			(fill no)
			(layer "F.Paste")
		)
		(fp_circle
			(center -9.526 5.714)
			(end -9.304 5.714)
			(stroke
				(width 0.445)
				(type solid)
			)
			(fill no)
			(layer "F.Paste")
		)
		(fp_circle
			(center -10.795 5.714)
			(end -10.574 5.714)
			(stroke
				(width 0.445)
				(type solid)
			)
			(fill no)
			(layer "F.Paste")
		)
		(fp_circle
			(center -12.065 5.714)
			(end -11.843 5.714)
			(stroke
				(width 0.445)
				(type solid)
			)
			(fill no)
			(layer "F.Paste")
		)
		(fp_circle
			(center -13.337 5.714)
			(end -13.113 5.714)
			(stroke
				(width 0.445)
				(type solid)
			)
			(fill no)
			(layer "F.Paste")
		)
		(fp_circle
			(center -14.606 5.714)
			(end -14.384 5.714)
			(stroke
				(width 0.445)
				(type solid)
			)
			(fill no)
			(layer "F.Paste")
		)
		(fp_circle
			(center -15.875 5.714)
			(end -15.654 5.714)
			(stroke
				(width 0.445)
				(type solid)
			)
			(fill no)
			(layer "F.Paste")
		)
		(fp_circle
			(center -17.145 5.714)
			(end -16.924 5.714)
			(stroke
				(width 0.445)
				(type solid)
			)
			(fill no)
			(layer "F.Paste")
		)
		(fp_circle
			(center -18.415 5.714)
			(end -18.194 5.714)
			(stroke
				(width 0.445)
				(type solid)
			)
			(fill no)
			(layer "F.Paste")
		)
		(fp_circle
			(center -19.685 5.714)
			(end -19.464 5.714)
			(stroke
				(width 0.445)
				(type solid)
			)
			(fill no)
			(layer "F.Paste")
		)
		(fp_circle
			(center -20.956 5.714)
			(end -20.734 5.714)
			(stroke
				(width 0.445)
				(type solid)
			)
			(fill no)
			(layer "F.Paste")
		)
		(fp_circle
			(center -22.226 5.714)
			(end -22.003 5.714)
			(stroke
				(width 0.445)
				(type solid)
			)
			(fill no)
			(layer "F.Paste")
		)
		(fp_circle
			(center -23.497 5.714)
			(end -23.273 5.714)
			(stroke
				(width 0.445)
				(type solid)
			)
			(fill no)
			(layer "F.Paste")
		)
		(fp_circle
			(center -24.767 5.714)
			(end -24.543 5.714)
			(stroke
				(width 0.445)
				(type solid)
			)
			(fill no)
			(layer "F.Paste")
		)
		(fp_circle
			(center 24.765 6.985)
			(end 24.987 6.985)
			(stroke
				(width 0.445)
				(type solid)
			)
			(fill no)
			(layer "F.Paste")
		)
		(fp_circle
			(center 23.495 6.985)
			(end 23.716 6.985)
			(stroke
				(width 0.445)
				(type solid)
			)
			(fill no)
			(layer "F.Paste")
		)
		(fp_circle
			(center 22.225 6.985)
			(end 22.446 6.985)
			(stroke
				(width 0.445)
				(type solid)
			)
			(fill no)
			(layer "F.Paste")
		)
		(fp_circle
			(center 20.954 6.985)
			(end 21.176 6.985)
			(stroke
				(width 0.445)
				(type solid)
			)
			(fill no)
			(layer "F.Paste")
		)
		(fp_circle
			(center 19.684 6.985)
			(end 19.906 6.985)
			(stroke
				(width 0.445)
				(type solid)
			)
			(fill no)
			(layer "F.Paste")
		)
		(fp_circle
			(center 18.414 6.985)
			(end 18.637 6.985)
			(stroke
				(width 0.445)
				(type solid)
			)
			(fill no)
			(layer "F.Paste")
		)
		(fp_circle
			(center 17.144 6.985)
			(end 17.367 6.985)
			(stroke
				(width 0.445)
				(type solid)
			)
			(fill no)
			(layer "F.Paste")
		)
		(fp_circle
			(center 15.874 6.985)
			(end 16.097 6.985)
			(stroke
				(width 0.445)
				(type solid)
			)
			(fill no)
			(layer "F.Paste")
		)
		(fp_circle
			(center 14.605 6.985)
			(end 14.826 6.985)
			(stroke
				(width 0.445)
				(type solid)
			)
			(fill no)
			(layer "F.Paste")
		)
		(fp_circle
			(center 13.335 6.985)
			(end 13.557 6.985)
			(stroke
				(width 0.445)
				(type solid)
			)
			(fill no)
			(layer "F.Paste")
		)
		(fp_circle
			(center 12.063 6.985)
			(end 12.287 6.985)
			(stroke
				(width 0.445)
				(type solid)
			)
			(fill no)
			(layer "F.Paste")
		)
		(fp_circle
			(center 10.794 6.985)
			(end 11.016 6.985)
			(stroke
				(width 0.445)
				(type solid)
			)
			(fill no)
			(layer "F.Paste")
		)
		(fp_circle
			(center 9.525 6.985)
			(end 9.746 6.985)
			(stroke
				(width 0.445)
				(type solid)
			)
			(fill no)
			(layer "F.Paste")
		)
		(fp_circle
			(center 8.255 6.985)
			(end 8.477 6.985)
			(stroke
				(width 0.445)
				(type solid)
			)
			(fill no)
			(layer "F.Paste")
		)
		(fp_circle
			(center 6.985 6.985)
			(end 7.206 6.985)
			(stroke
				(width 0.445)
				(type solid)
			)
			(fill no)
			(layer "F.Paste")
		)
		(fp_circle
			(center 5.714 6.985)
			(end 5.937 6.985)
			(stroke
				(width 0.445)
				(type solid)
			)
			(fill no)
			(layer "F.Paste")
		)
		(fp_circle
			(center 4.445 6.985)
			(end 4.666 6.985)
			(stroke
				(width 0.445)
				(type solid)
			)
			(fill no)
			(layer "F.Paste")
		)
		(fp_circle
			(center 3.173 6.985)
			(end 3.397 6.985)
			(stroke
				(width 0.445)
				(type solid)
			)
			(fill no)
			(layer "F.Paste")
		)
		(fp_circle
			(center 1.904 6.985)
			(end 2.127 6.985)
			(stroke
				(width 0.445)
				(type solid)
			)
			(fill no)
			(layer "F.Paste")
		)
		(fp_circle
			(center 0.633 6.985)
			(end 0.856 6.985)
			(stroke
				(width 0.445)
				(type solid)
			)
			(fill no)
			(layer "F.Paste")
		)
		(fp_circle
			(center -0.635 6.985)
			(end -0.414 6.985)
			(stroke
				(width 0.445)
				(type solid)
			)
			(fill no)
			(layer "F.Paste")
		)
		(fp_circle
			(center -1.905 6.985)
			(end -1.684 6.985)
			(stroke
				(width 0.445)
				(type solid)
			)
			(fill no)
			(layer "F.Paste")
		)
		(fp_circle
			(center -3.176 6.985)
			(end -2.953 6.985)
			(stroke
				(width 0.445)
				(type solid)
			)
			(fill no)
			(layer "F.Paste")
		)
		(fp_circle
			(center -4.446 6.985)
			(end -4.223 6.985)
			(stroke
				(width 0.445)
				(type solid)
			)
			(fill no)
			(layer "F.Paste")
		)
		(fp_circle
			(center -5.715 6.985)
			(end -5.494 6.985)
			(stroke
				(width 0.445)
				(type solid)
			)
			(fill no)
			(layer "F.Paste")
		)
		(fp_circle
			(center -6.986 6.985)
			(end -6.763 6.985)
			(stroke
				(width 0.445)
				(type solid)
			)
			(fill no)
			(layer "F.Paste")
		)
		(fp_circle
			(center -8.257 6.985)
			(end -8.033 6.985)
			(stroke
				(width 0.445)
				(type solid)
			)
			(fill no)
			(layer "F.Paste")
		)
		(fp_circle
			(center -9.526 6.985)
			(end -9.304 6.985)
			(stroke
				(width 0.445)
				(type solid)
			)
			(fill no)
			(layer "F.Paste")
		)
		(fp_circle
			(center -10.795 6.985)
			(end -10.574 6.985)
			(stroke
				(width 0.445)
				(type solid)
			)
			(fill no)
			(layer "F.Paste")
		)
		(fp_circle
			(center -12.065 6.985)
			(end -11.843 6.985)
			(stroke
				(width 0.445)
				(type solid)
			)
			(fill no)
			(layer "F.Paste")
		)
		(fp_circle
			(center -13.337 6.985)
			(end -13.113 6.985)
			(stroke
				(width 0.445)
				(type solid)
			)
			(fill no)
			(layer "F.Paste")
		)
		(fp_circle
			(center -14.606 6.985)
			(end -14.384 6.985)
			(stroke
				(width 0.445)
				(type solid)
			)
			(fill no)
			(layer "F.Paste")
		)
		(fp_circle
			(center -15.875 6.985)
			(end -15.654 6.985)
			(stroke
				(width 0.445)
				(type solid)
			)
			(fill no)
			(layer "F.Paste")
		)
		(fp_circle
			(center -17.145 6.985)
			(end -16.924 6.985)
			(stroke
				(width 0.445)
				(type solid)
			)
			(fill no)
			(layer "F.Paste")
		)
		(fp_circle
			(center -18.415 6.985)
			(end -18.194 6.985)
			(stroke
				(width 0.445)
				(type solid)
			)
			(fill no)
			(layer "F.Paste")
		)
		(fp_circle
			(center -19.685 6.985)
			(end -19.464 6.985)
			(stroke
				(width 0.445)
				(type solid)
			)
			(fill no)
			(layer "F.Paste")
		)
		(fp_circle
			(center -20.956 6.985)
			(end -20.734 6.985)
			(stroke
				(width 0.445)
				(type solid)
			)
			(fill no)
			(layer "F.Paste")
		)
		(fp_circle
			(center -22.226 6.985)
			(end -22.003 6.985)
			(stroke
				(width 0.445)
				(type solid)
			)
			(fill no)
			(layer "F.Paste")
		)
		(fp_circle
			(center -23.497 6.985)
			(end -23.273 6.985)
			(stroke
				(width 0.445)
				(type solid)
			)
			(fill no)
			(layer "F.Paste")
		)
		(fp_circle
			(center -24.767 6.985)
			(end -24.543 6.985)
			(stroke
				(width 0.445)
				(type solid)
			)
			(fill no)
			(layer "F.Paste")
		)
		(fp_circle
			(center 24.765 8.255)
			(end 24.987 8.255)
			(stroke
				(width 0.445)
				(type solid)
			)
			(fill no)
			(layer "F.Paste")
		)
		(fp_circle
			(center 23.495 8.255)
			(end 23.716 8.255)
			(stroke
				(width 0.445)
				(type solid)
			)
			(fill no)
			(layer "F.Paste")
		)
		(fp_circle
			(center 22.225 8.255)
			(end 22.446 8.255)
			(stroke
				(width 0.445)
				(type solid)
			)
			(fill no)
			(layer "F.Paste")
		)
		(fp_circle
			(center 20.954 8.255)
			(end 21.176 8.255)
			(stroke
				(width 0.445)
				(type solid)
			)
			(fill no)
			(layer "F.Paste")
		)
		(fp_circle
			(center 19.684 8.255)
			(end 19.906 8.255)
			(stroke
				(width 0.445)
				(type solid)
			)
			(fill no)
			(layer "F.Paste")
		)
		(fp_circle
			(center 18.414 8.255)
			(end 18.637 8.255)
			(stroke
				(width 0.445)
				(type solid)
			)
			(fill no)
			(layer "F.Paste")
		)
		(fp_circle
			(center 17.144 8.255)
			(end 17.367 8.255)
			(stroke
				(width 0.445)
				(type solid)
			)
			(fill no)
			(layer "F.Paste")
		)
		(fp_circle
			(center 15.874 8.255)
			(end 16.097 8.255)
			(stroke
				(width 0.445)
				(type solid)
			)
			(fill no)
			(layer "F.Paste")
		)
		(fp_circle
			(center 14.605 8.255)
			(end 14.826 8.255)
			(stroke
				(width 0.445)
				(type solid)
			)
			(fill no)
			(layer "F.Paste")
		)
		(fp_circle
			(center 13.335 8.255)
			(end 13.557 8.255)
			(stroke
				(width 0.445)
				(type solid)
			)
			(fill no)
			(layer "F.Paste")
		)
		(fp_circle
			(center 12.063 8.255)
			(end 12.287 8.255)
			(stroke
				(width 0.445)
				(type solid)
			)
			(fill no)
			(layer "F.Paste")
		)
		(fp_circle
			(center 10.794 8.255)
			(end 11.016 8.255)
			(stroke
				(width 0.445)
				(type solid)
			)
			(fill no)
			(layer "F.Paste")
		)
		(fp_circle
			(center 9.525 8.255)
			(end 9.746 8.255)
			(stroke
				(width 0.445)
				(type solid)
			)
			(fill no)
			(layer "F.Paste")
		)
		(fp_circle
			(center 8.255 8.255)
			(end 8.477 8.255)
			(stroke
				(width 0.445)
				(type solid)
			)
			(fill no)
			(layer "F.Paste")
		)
		(fp_circle
			(center 6.985 8.255)
			(end 7.206 8.255)
			(stroke
				(width 0.445)
				(type solid)
			)
			(fill no)
			(layer "F.Paste")
		)
		(fp_circle
			(center 5.714 8.255)
			(end 5.937 8.255)
			(stroke
				(width 0.445)
				(type solid)
			)
			(fill no)
			(layer "F.Paste")
		)
		(fp_circle
			(center 4.445 8.255)
			(end 4.666 8.255)
			(stroke
				(width 0.445)
				(type solid)
			)
			(fill no)
			(layer "F.Paste")
		)
		(fp_circle
			(center 3.173 8.255)
			(end 3.397 8.255)
			(stroke
				(width 0.445)
				(type solid)
			)
			(fill no)
			(layer "F.Paste")
		)
		(fp_circle
			(center 1.904 8.255)
			(end 2.127 8.255)
			(stroke
				(width 0.445)
				(type solid)
			)
			(fill no)
			(layer "F.Paste")
		)
		(fp_circle
			(center 0.633 8.255)
			(end 0.856 8.255)
			(stroke
				(width 0.445)
				(type solid)
			)
			(fill no)
			(layer "F.Paste")
		)
		(fp_circle
			(center -0.635 8.255)
			(end -0.414 8.255)
			(stroke
				(width 0.445)
				(type solid)
			)
			(fill no)
			(layer "F.Paste")
		)
		(fp_circle
			(center -1.905 8.255)
			(end -1.684 8.255)
			(stroke
				(width 0.445)
				(type solid)
			)
			(fill no)
			(layer "F.Paste")
		)
		(fp_circle
			(center -3.176 8.255)
			(end -2.953 8.255)
			(stroke
				(width 0.445)
				(type solid)
			)
			(fill no)
			(layer "F.Paste")
		)
		(fp_circle
			(center -4.446 8.255)
			(end -4.223 8.255)
			(stroke
				(width 0.445)
				(type solid)
			)
			(fill no)
			(layer "F.Paste")
		)
		(fp_circle
			(center -5.715 8.255)
			(end -5.494 8.255)
			(stroke
				(width 0.445)
				(type solid)
			)
			(fill no)
			(layer "F.Paste")
		)
		(fp_circle
			(center -6.986 8.255)
			(end -6.763 8.255)
			(stroke
				(width 0.445)
				(type solid)
			)
			(fill no)
			(layer "F.Paste")
		)
		(fp_circle
			(center -8.257 8.255)
			(end -8.033 8.255)
			(stroke
				(width 0.445)
				(type solid)
			)
			(fill no)
			(layer "F.Paste")
		)
		(fp_circle
			(center -9.526 8.255)
			(end -9.304 8.255)
			(stroke
				(width 0.445)
				(type solid)
			)
			(fill no)
			(layer "F.Paste")
		)
		(fp_circle
			(center -10.795 8.255)
			(end -10.574 8.255)
			(stroke
				(width 0.445)
				(type solid)
			)
			(fill no)
			(layer "F.Paste")
		)
		(fp_circle
			(center -12.065 8.255)
			(end -11.843 8.255)
			(stroke
				(width 0.445)
				(type solid)
			)
			(fill no)
			(layer "F.Paste")
		)
		(fp_circle
			(center -13.337 8.255)
			(end -13.113 8.255)
			(stroke
				(width 0.445)
				(type solid)
			)
			(fill no)
			(layer "F.Paste")
		)
		(fp_circle
			(center -14.606 8.255)
			(end -14.384 8.255)
			(stroke
				(width 0.445)
				(type solid)
			)
			(fill no)
			(layer "F.Paste")
		)
		(fp_circle
			(center -15.875 8.255)
			(end -15.654 8.255)
			(stroke
				(width 0.445)
				(type solid)
			)
			(fill no)
			(layer "F.Paste")
		)
		(fp_circle
			(center -17.145 8.255)
			(end -16.924 8.255)
			(stroke
				(width 0.445)
				(type solid)
			)
			(fill no)
			(layer "F.Paste")
		)
		(fp_circle
			(center -18.415 8.255)
			(end -18.194 8.255)
			(stroke
				(width 0.445)
				(type solid)
			)
			(fill no)
			(layer "F.Paste")
		)
		(fp_circle
			(center -19.685 8.255)
			(end -19.464 8.255)
			(stroke
				(width 0.445)
				(type solid)
			)
			(fill no)
			(layer "F.Paste")
		)
		(fp_circle
			(center -20.956 8.255)
			(end -20.734 8.255)
			(stroke
				(width 0.445)
				(type solid)
			)
			(fill no)
			(layer "F.Paste")
		)
		(fp_circle
			(center -22.226 8.255)
			(end -22.003 8.255)
			(stroke
				(width 0.445)
				(type solid)
			)
			(fill no)
			(layer "F.Paste")
		)
		(fp_circle
			(center -23.497 8.255)
			(end -23.273 8.255)
			(stroke
				(width 0.445)
				(type solid)
			)
			(fill no)
			(layer "F.Paste")
		)
		(fp_circle
			(center -24.767 8.255)
			(end -24.543 8.255)
			(stroke
				(width 0.445)
				(type solid)
			)
			(fill no)
			(layer "F.Paste")
		)
		(fp_rect
			(start -29.729 -10.185)
			(end 29.726 10.182)
			(stroke
				(width 0.05)
				(type solid)
			)
			(fill no)
			(layer "F.CrtYd")
		)
		(fp_line
			(start 27.815 -9.18)
			(end 27.815 -2.847)
			(stroke
				(width 0.15)
				(type solid)
			)
			(layer "F.Fab")
		)
		(fp_line
			(start -28.825 -9.18)
			(end 27.815 -9.18)
			(stroke
				(width 0.15)
				(type solid)
			)
			(layer "F.Fab")
		)
		(fp_line
			(start 28.655 -2.847)
			(end 28.655 2.845)
			(stroke
				(width 0.15)
				(type solid)
			)
			(layer "F.Fab")
		)
		(fp_line
			(start 27.815 -2.847)
			(end 28.655 -2.847)
			(stroke
				(width 0.15)
				(type solid)
			)
			(layer "F.Fab")
		)
		(fp_line
			(start 28.655 2.845)
			(end 27.815 2.845)
			(stroke
				(width 0.15)
				(type solid)
			)
			(layer "F.Fab")
		)
		(fp_line
			(start 27.815 2.845)
			(end 27.815 9.179)
			(stroke
				(width 0.15)
				(type solid)
			)
			(layer "F.Fab")
		)
		(fp_line
			(start 27.815 9.179)
			(end -28.825 9.179)
			(stroke
				(width 0.15)
				(type solid)
			)
			(layer "F.Fab")
		)
		(fp_line
			(start -28.825 9.179)
			(end -28.825 -9.18)
			(stroke
				(width 0.15)
				(type solid)
			)
			(layer "F.Fab")
		)
		(pad "" np_thru_hole circle
			(at -31.5 -2 90)
			(size 6 6)
			(drill 3.2)
			(layers "*.Cu" "*.Mask")
		)
		(pad "" np_thru_hole circle
			(at -27.191 0 90)
			(size 1.27 1.27)
			(drill 1.27)
			(layers "*.Cu" "*.Mask")
		)
		(pad "" np_thru_hole circle
			(at 27.19 3.048 90)
			(size 1.27 1.27)
			(drill 1.27)
			(layers "*.Cu" "*.Mask")
		)
		(pad "" np_thru_hole circle
			(at 31.499 -2 90)
			(size 6 6)
			(drill 3.2)
			(layers "*.Cu" "*.Mask")
		)
		(pad "A01" smd circle
			(at 24.765 5.714 90)
			(size 0.64 0.64)
			(layers "F.Cu" "F.Mask")
			(net 1 "GND")
			(pinfunction "GND")
			(pintype "passive")
		)
		(pad "A02" smd circle
			(at 23.495 5.714 90)
			(size 0.64 0.64)
			(layers "F.Cu" "F.Mask")
			(net 312 "/FMC+ HSPC/GTX116.RX2_P")
			(pinfunction "DP1_M2C_P")
			(pintype "passive")
		)
		(pad "A03" smd circle
			(at 22.225 5.714 90)
			(size 0.64 0.64)
			(layers "F.Cu" "F.Mask")
			(net 307 "/FMC+ HSPC/GTX116.RX2_N")
			(pinfunction "DP1_M2C_N")
			(pintype "passive")
		)
		(pad "A04" smd circle
			(at 20.954 5.714 90)
			(size 0.64 0.64)
			(layers "F.Cu" "F.Mask")
			(net 1 "GND")
			(pinfunction "GND")
			(pintype "passive")
		)
		(pad "A05" smd circle
			(at 19.684 5.714 90)
			(size 0.64 0.64)
			(layers "F.Cu" "F.Mask")
			(net 1 "GND")
			(pinfunction "GND")
			(pintype "passive")
		)
		(pad "A06" smd circle
			(at 18.414 5.714 90)
			(size 0.64 0.64)
			(layers "F.Cu" "F.Mask")
			(net 288 "/FMC+ HSPC/GTX116.RX1_P")
			(pinfunction "DP2_M2C_P")
			(pintype "passive")
		)
		(pad "A07" smd circle
			(at 17.144 5.714 90)
			(size 0.64 0.64)
			(layers "F.Cu" "F.Mask")
			(net 283 "/FMC+ HSPC/GTX116.RX1_N")
			(pinfunction "DP2_M2C_N")
			(pintype "passive")
		)
		(pad "A08" smd circle
			(at 15.874 5.714 90)
			(size 0.64 0.64)
			(layers "F.Cu" "F.Mask")
			(net 1 "GND")
			(pinfunction "GND")
			(pintype "passive")
		)
		(pad "A09" smd circle
			(at 14.605 5.714 90)
			(size 0.64 0.64)
			(layers "F.Cu" "F.Mask")
			(net 1 "GND")
			(pinfunction "GND")
			(pintype "passive")
		)
		(pad "A10" smd circle
			(at 13.335 5.714 90)
			(size 0.64 0.64)
			(layers "F.Cu" "F.Mask")
			(net 249 "/FMC+ HSPC/GTX116.RX0_P")
			(pinfunction "DP3_M2C_P")
			(pintype "passive")
		)
		(pad "A11" smd circle
			(at 12.063 5.714 90)
			(size 0.64 0.64)
			(layers "F.Cu" "F.Mask")
			(net 490 "/FMC+ HSPC/GTX116.RX0_N")
			(pinfunction "DP3_M2C_N")
			(pintype "passive")
		)
		(pad "A12" smd circle
			(at 10.794 5.714 90)
			(size 0.64 0.64)
			(layers "F.Cu" "F.Mask")
			(net 1 "GND")
			(pinfunction "GND")
			(pintype "passive")
		)
		(pad "A13" smd circle
			(at 9.525 5.714 90)
			(size 0.64 0.64)
			(layers "F.Cu" "F.Mask")
			(net 1 "GND")
			(pinfunction "GND")
			(pintype "passive")
		)
		(pad "A14" smd circle
			(at 8.255 5.714 90)
			(size 0.64 0.64)
			(layers "F.Cu" "F.Mask")
			(net 479 "/FMC+ HSPC/GTX115.RX3_P")
			(pinfunction "DP4_M2C_P")
			(pintype "passive")
		)
		(pad "A15" smd circle
			(at 6.985 5.714 90)
			(size 0.64 0.64)
			(layers "F.Cu" "F.Mask")
			(net 473 "/FMC+ HSPC/GTX115.RX3_N")
			(pinfunction "DP4_M2C_N")
			(pintype "passive")
		)
		(pad "A16" smd circle
			(at 5.714 5.714 90)
			(size 0.64 0.64)
			(layers "F.Cu" "F.Mask")
			(net 1 "GND")
			(pinfunction "GND")
			(pintype "passive")
		)
		(pad "A17" smd circle
			(at 4.445 5.714 90)
			(size 0.64 0.64)
			(layers "F.Cu" "F.Mask")
			(net 1 "GND")
			(pinfunction "GND")
			(pintype "passive")
		)
		(pad "A18" smd circle
			(at 3.173 5.714 90)
			(size 0.64 0.64)
			(layers "F.Cu" "F.Mask")
			(net 459 "/FMC+ HSPC/GTX115.RX2_P")
			(pinfunction "DP5_M2C_P")
			(pintype "passive")
		)
		(pad "A19" smd circle
			(at 1.904 5.714 90)
			(size 0.64 0.64)
			(layers "F.Cu" "F.Mask")
			(net 454 "/FMC+ HSPC/GTX115.RX2_N")
			(pinfunction "DP5_M2C_N")
			(pintype "passive")
		)
		(pad "A20" smd circle
			(at 0.633 5.714 90)
			(size 0.64 0.64)
			(layers "F.Cu" "F.Mask")
			(net 1 "GND")
			(pinfunction "GND")
			(pintype "passive")
		)
		(pad "A21" smd circle
			(at -0.635 5.714 90)
			(size 0.64 0.64)
			(layers "F.Cu" "F.Mask")
			(net 1 "GND")
			(pinfunction "GND")
			(pintype "passive")
		)
		(pad "A22" smd circle
			(at -1.905 5.714 90)
			(size 0.64 0.64)
			(layers "F.Cu" "F.Mask")
			(net 64 "/FMC+ HSPC/GTX_TX1_C_P")
			(pinfunction "DP1_C2M_P")
			(pintype "passive")
		)
		(pad "A23" smd circle
			(at -3.176 5.714 90)
			(size 0.64 0.64)
			(layers "F.Cu" "F.Mask")
			(net 67 "/FMC+ HSPC/GTX_TX1_C_N")
			(pinfunction "DP1_C2M_N")
			(pintype "passive")
		)
		(pad "A24" smd circle
			(at -4.446 5.714 90)
			(size 0.64 0.64)
			(layers "F.Cu" "F.Mask")
			(net 1 "GND")
			(pinfunction "GND")
			(pintype "passive")
		)
		(pad "A25" smd circle
			(at -5.715 5.714 90)
			(size 0.64 0.64)
			(layers "F.Cu" "F.Mask")
			(net 1 "GND")
			(pinfunction "GND")
			(pintype "passive")
		)
		(pad "A26" smd circle
			(at -6.986 5.714 90)
			(size 0.64 0.64)
			(layers "F.Cu" "F.Mask")
			(net 71 "/FMC+ HSPC/GTX_TX2_C_P")
			(pinfunction "DP2_C2M_P")
			(pintype "passive")
		)
		(pad "A27" smd circle
			(at -8.257 5.714 90)
			(size 0.64 0.64)
			(layers "F.Cu" "F.Mask")
			(net 76 "/FMC+ HSPC/GTX_TX2_C_N")
			(pinfunction "DP2_C2M_N")
			(pintype "passive")
		)
		(pad "A28" smd circle
			(at -9.526 5.714 90)
			(size 0.64 0.64)
			(layers "F.Cu" "F.Mask")
			(net 1 "GND")
			(pinfunction "GND")
			(pintype "passive")
		)
		(pad "A29" smd circle
			(at -10.795 5.714 90)
			(size 0.64 0.64)
			(layers "F.Cu" "F.Mask")
			(net 1 "GND")
			(pinfunction "GND")
			(pintype "passive")
		)
		(pad "A30" smd circle
			(at -12.065 5.714 90)
			(size 0.64 0.64)
			(layers "F.Cu" "F.Mask")
			(net 79 "/FMC+ HSPC/GTX_TX3_C_P")
			(pinfunction "DP3_C2M_P")
			(pintype "passive")
		)
		(pad "A31" smd circle
			(at -13.337 5.714 90)
			(size 0.64 0.64)
			(layers "F.Cu" "F.Mask")
			(net 81 "/FMC+ HSPC/GTX_TX3_C_N")
			(pinfunction "DP3_C2M_N")
			(pintype "passive")
		)
		(pad "A32" smd circle
			(at -14.606 5.714 90)
			(size 0.64 0.64)
			(layers "F.Cu" "F.Mask")
			(net 1 "GND")
			(pinfunction "GND")
			(pintype "passive")
		)
		(pad "A33" smd circle
			(at -15.875 5.714 90)
			(size 0.64 0.64)
			(layers "F.Cu" "F.Mask")
			(net 1 "GND")
			(pinfunction "GND")
			(pintype "passive")
		)
		(pad "A34" smd circle
			(at -17.145 5.714 90)
			(size 0.64 0.64)
			(layers "F.Cu" "F.Mask")
			(net 83 "/FMC+ HSPC/GTX_TX4_C_P")
			(pinfunction "DP4_C2M_P")
			(pintype "passive")
		)
		(pad "A35" smd circle
			(at -18.415 5.714 90)
			(size 0.64 0.64)
			(layers "F.Cu" "F.Mask")
			(net 88 "/FMC+ HSPC/GTX_TX4_C_N")
			(pinfunction "DP4_C2M_N")
			(pintype "passive")
		)
		(pad "A36" smd circle
			(at -19.685 5.714 90)
			(size 0.64 0.64)
			(layers "F.Cu" "F.Mask")
			(net 1 "GND")
			(pinfunction "GND")
			(pintype "passive")
		)
		(pad "A37" smd circle
			(at -20.956 5.714 90)
			(size 0.64 0.64)
			(layers "F.Cu" "F.Mask")
			(net 1 "GND")
			(pinfunction "GND")
			(pintype "passive")
		)
		(pad "A38" smd circle
			(at -22.226 5.714 90)
			(size 0.64 0.64)
			(layers "F.Cu" "F.Mask")
			(net 96 "/FMC+ HSPC/GTX_TX5_C_P")
			(pinfunction "DP5_C2M_P")
			(pintype "passive")
		)
		(pad "A39" smd circle
			(at -23.497 5.714 90)
			(size 0.64 0.64)
			(layers "F.Cu" "F.Mask")
			(net 98 "/FMC+ HSPC/GTX_TX5_C_N")
			(pinfunction "DP5_C2M_N")
			(pintype "passive")
		)
		(pad "A40" smd circle
			(at -24.767 5.714 90)
			(size 0.64 0.64)
			(layers "F.Cu" "F.Mask")
			(net 1 "GND")
			(pinfunction "GND")
			(pintype "passive")
		)
		(pad "B01" smd circle
			(at 24.765 4.445 90)
			(size 0.64 0.64)
			(layers "F.Cu" "F.Mask")
			(net 514 "/FMC+ HSPC/FMC.CLK_DIR")
			(pinfunction "CLK_DIR")
			(pintype "passive")
		)
		(pad "B02" smd circle
			(at 23.495 4.445 90)
			(size 0.64 0.64)
			(layers "F.Cu" "F.Mask")
			(net 1 "GND")
			(pinfunction "GND")
			(pintype "passive")
		)
		(pad "B03" smd circle
			(at 22.225 4.445 90)
			(size 0.64 0.64)
			(layers "F.Cu" "F.Mask")
			(net 1 "GND")
			(pinfunction "GND")
			(pintype "passive")
		)
		(pad "B04" smd circle
			(at 20.954 4.445 90)
			(size 0.64 0.64)
			(layers "F.Cu" "F.Mask")
			(net 50 "unconnected-(J18H-DP9_M2C_P-PadB04)")
			(pinfunction "DP9_M2C_P")
			(pintype "passive+no_connect")
		)
		(pad "B05" smd circle
			(at 19.684 4.445 90)
			(size 0.64 0.64)
			(layers "F.Cu" "F.Mask")
			(net 51 "unconnected-(J18H-DP9_M2C_N-PadB05)")
			(pinfunction "DP9_M2C_N")
			(pintype "passive+no_connect")
		)
		(pad "B06" smd circle
			(at 18.414 4.445 90)
			(size 0.64 0.64)
			(layers "F.Cu" "F.Mask")
			(net 1 "GND")
			(pinfunction "GND")
			(pintype "passive")
		)
		(pad "B07" smd circle
			(at 17.144 4.445 90)
			(size 0.64 0.64)
			(layers "F.Cu" "F.Mask")
			(net 1 "GND")
			(pinfunction "GND")
			(pintype "passive")
		)
		(pad "B08" smd circle
			(at 15.874 4.445 90)
			(size 0.64 0.64)
			(layers "F.Cu" "F.Mask")
			(net 52 "unconnected-(J18H-DP8_M2C_P-PadB08)")
			(pinfunction "DP8_M2C_P")
			(pintype "passive+no_connect")
		)
		(pad "B09" smd circle
			(at 14.605 4.445 90)
			(size 0.64 0.64)
			(layers "F.Cu" "F.Mask")
			(net 53 "unconnected-(J18H-DP8_M2C_N-PadB09)")
			(pinfunction "DP8_M2C_N")
			(pintype "passive+no_connect")
		)
		(pad "B10" smd circle
			(at 13.335 4.445 90)
			(size 0.64 0.64)
			(layers "F.Cu" "F.Mask")
			(net 1 "GND")
			(pinfunction "GND")
			(pintype "passive")
		)
		(pad "B11" smd circle
			(at 12.063 4.445 90)
			(size 0.64 0.64)
			(layers "F.Cu" "F.Mask")
			(net 1 "GND")
			(pinfunction "GND")
			(pintype "passive")
		)
		(pad "B12" smd circle
			(at 10.794 4.445 90)
			(size 0.64 0.64)
			(layers "F.Cu" "F.Mask")
			(net 486 "/FMC+ HSPC/GTX115.RX0_P")
			(pinfunction "DP7_M2C_P")
			(pintype "passive")
		)
		(pad "B13" smd circle
			(at 9.525 4.445 90)
			(size 0.64 0.64)
			(layers "F.Cu" "F.Mask")
			(net 483 "/FMC+ HSPC/GTX115.RX0_N")
			(pinfunction "DP7_M2C_N")
			(pintype "passive")
		)
		(pad "B14" smd circle
			(at 8.255 4.445 90)
			(size 0.64 0.64)
			(layers "F.Cu" "F.Mask")
			(net 1 "GND")
			(pinfunction "GND")
			(pintype "passive")
		)
		(pad "B15" smd circle
			(at 6.985 4.445 90)
			(size 0.64 0.64)
			(layers "F.Cu" "F.Mask")
			(net 1 "GND")
			(pinfunction "GND")
			(pintype "passive")
		)
		(pad "B16" smd circle
			(at 5.714 4.445 90)
			(size 0.64 0.64)
			(layers "F.Cu" "F.Mask")
			(net 468 "/FMC+ HSPC/GTX115.RX1_P")
			(pinfunction "DP6_M2C_P")
			(pintype "passive")
		)
		(pad "B17" smd circle
			(at 4.445 4.445 90)
			(size 0.64 0.64)
			(layers "F.Cu" "F.Mask")
			(net 463 "/FMC+ HSPC/GTX115.RX1_N")
			(pinfunction "DP6_M2C_N")
			(pintype "passive")
		)
		(pad "B18" smd circle
			(at 3.173 4.445 90)
			(size 0.64 0.64)
			(layers "F.Cu" "F.Mask")
			(net 1 "GND")
			(pinfunction "GND")
			(pintype "passive")
		)
		(pad "B19" smd circle
			(at 1.904 4.445 90)
			(size 0.64 0.64)
			(layers "F.Cu" "F.Mask")
			(net 1 "GND")
			(pinfunction "GND")
			(pintype "passive")
		)
		(pad "B20" smd circle
			(at 0.633 4.445 90)
			(size 0.64 0.64)
			(layers "F.Cu" "F.Mask")
			(net 499 "/FMC+ HSPC/GTR_REFCLK1_R_P")
			(pinfunction "GBTCLK1_M2C_P")
			(pintype "passive")
		)
		(pad "B21" smd circle
			(at -0.635 4.445 90)
			(size 0.64 0.64)
			(layers "F.Cu" "F.Mask")
			(net 478 "/FMC+ HSPC/GTR_REFCLK1_R_N")
			(pinfunction "GBTCLK1_M2C_N")
			(pintype "passive")
		)
		(pad "B22" smd circle
			(at -1.905 4.445 90)
			(size 0.64 0.64)
			(layers "F.Cu" "F.Mask")
			(net 1 "GND")
			(pinfunction "GND")
			(pintype "passive")
		)
		(pad "B23" smd circle
			(at -3.176 4.445 90)
			(size 0.64 0.64)
			(layers "F.Cu" "F.Mask")
			(net 1 "GND")
			(pinfunction "GND")
			(pintype "passive")
		)
		(pad "B24" smd circle
			(at -4.446 4.445 90)
			(size 0.64 0.64)
			(layers "F.Cu" "F.Mask")
			(net 57 "unconnected-(J18H-DP9_C2M_P-PadB24)")
			(pinfunction "DP9_C2M_P")
			(pintype "passive+no_connect")
		)
		(pad "B25" smd circle
			(at -5.715 4.445 90)
			(size 0.64 0.64)
			(layers "F.Cu" "F.Mask")
			(net 58 "unconnected-(J18H-DP9_C2M_N-PadB25)")
			(pinfunction "DP9_C2M_N")
			(pintype "passive+no_connect")
		)
		(pad "B26" smd circle
			(at -6.986 4.445 90)
			(size 0.64 0.64)
			(layers "F.Cu" "F.Mask")
			(net 1 "GND")
			(pinfunction "GND")
			(pintype "passive")
		)
		(pad "B27" smd circle
			(at -8.257 4.445 90)
			(size 0.64 0.64)
			(layers "F.Cu" "F.Mask")
			(net 1 "GND")
			(pinfunction "GND")
			(pintype "passive")
		)
		(pad "B28" smd circle
			(at -9.526 4.445 90)
			(size 0.64 0.64)
			(layers "F.Cu" "F.Mask")
			(net 66 "unconnected-(J18H-DP8_C2M_P-PadB28)")
			(pinfunction "DP8_C2M_P")
			(pintype "passive+no_connect")
		)
		(pad "B29" smd circle
			(at -10.795 4.445 90)
			(size 0.64 0.64)
			(layers "F.Cu" "F.Mask")
			(net 68 "unconnected-(J18H-DP8_C2M_N-PadB29)")
			(pinfunction "DP8_C2M_N")
			(pintype "passive+no_connect")
		)
		(pad "B30" smd circle
			(at -12.065 4.445 90)
			(size 0.64 0.64)
			(layers "F.Cu" "F.Mask")
			(net 1 "GND")
			(pinfunction "GND")
			(pintype "passive")
		)
		(pad "B31" smd circle
			(at -13.337 4.445 90)
			(size 0.64 0.64)
			(layers "F.Cu" "F.Mask")
			(net 1 "GND")
			(pinfunction "GND")
			(pintype "passive")
		)
		(pad "B32" smd circle
			(at -14.606 4.445 90)
			(size 0.64 0.64)
			(layers "F.Cu" "F.Mask")
			(net 119 "/FMC+ HSPC/GTX_TX7_C_P")
			(pinfunction "DP7_C2M_P")
			(pintype "passive")
		)
		(pad "B33" smd circle
			(at -15.875 4.445 90)
			(size 0.64 0.64)
			(layers "F.Cu" "F.Mask")
			(net 123 "/FMC+ HSPC/GTX_TX7_C_N")
			(pinfunction "DP7_C2M_N")
			(pintype "passive")
		)
		(pad "B34" smd circle
			(at -17.145 4.445 90)
			(size 0.64 0.64)
			(layers "F.Cu" "F.Mask")
			(net 1 "GND")
			(pinfunction "GND")
			(pintype "passive")
		)
		(pad "B35" smd circle
			(at -18.415 4.445 90)
			(size 0.64 0.64)
			(layers "F.Cu" "F.Mask")
			(net 1 "GND")
			(pinfunction "GND")
			(pintype "passive")
		)
		(pad "B36" smd circle
			(at -19.685 4.445 90)
			(size 0.64 0.64)
			(layers "F.Cu" "F.Mask")
			(net 105 "/FMC+ HSPC/GTX_TX6_C_P")
			(pinfunction "DP6_C2M_P")
			(pintype "passive")
		)
		(pad "B37" smd circle
			(at -20.956 4.445 90)
			(size 0.64 0.64)
			(layers "F.Cu" "F.Mask")
			(net 109 "/FMC+ HSPC/GTX_TX6_C_N")
			(pinfunction "DP6_C2M_N")
			(pintype "passive")
		)
		(pad "B38" smd circle
			(at -22.226 4.445 90)
			(size 0.64 0.64)
			(layers "F.Cu" "F.Mask")
			(net 1 "GND")
			(pinfunction "GND")
			(pintype "passive")
		)
		(pad "B39" smd circle
			(at -23.497 4.445 90)
			(size 0.64 0.64)
			(layers "F.Cu" "F.Mask")
			(net 1 "GND")
			(pinfunction "GND")
			(pintype "passive")
		)
		(pad "B40" smd circle
			(at -24.767 4.445 90)
			(size 0.64 0.64)
			(layers "F.Cu" "F.Mask")
			(net 70 "unconnected-(J18A-RES0-PadB40)")
			(pinfunction "RES0")
			(pintype "no_connect")
		)
		(pad "C01" smd circle
			(at 24.765 3.173 90)
			(size 0.64 0.64)
			(layers "F.Cu" "F.Mask")
			(net 1 "GND")
			(pinfunction "GND")
			(pintype "passive")
		)
		(pad "C02" smd circle
			(at 23.495 3.173 90)
			(size 0.64 0.64)
			(layers "F.Cu" "F.Mask")
			(net 60 "/FMC+ HSPC/GTX_TX0_C_P")
			(pinfunction "DP0_C2M_P")
			(pintype "passive")
		)
		(pad "C03" smd circle
			(at 22.225 3.173 90)
			(size 0.64 0.64)
			(layers "F.Cu" "F.Mask")
			(net 62 "/FMC+ HSPC/GTX_TX0_C_N")
			(pinfunction "DP0_C2M_N")
			(pintype "passive")
		)
		(pad "C04" smd circle
			(at 20.954 3.173 90)
			(size 0.64 0.64)
			(layers "F.Cu" "F.Mask")
			(net 1 "GND")
			(pinfunction "GND")
			(pintype "passive")
		)
		(pad "C05" smd circle
			(at 19.684 3.173 90)
			(size 0.64 0.64)
			(layers "F.Cu" "F.Mask")
			(net 1 "GND")
			(pinfunction "GND")
			(pintype "passive")
		)
		(pad "C06" smd circle
			(at 18.414 3.173 90)
			(size 0.64 0.64)
			(layers "F.Cu" "F.Mask")
			(net 287 "/FMC+ HSPC/GTX116.RX3_P")
			(pinfunction "DP0_M2C_P")
			(pintype "passive")
		)
		(pad "C07" smd circle
			(at 17.144 3.173 90)
			(size 0.64 0.64)
			(layers "F.Cu" "F.Mask")
			(net 282 "/FMC+ HSPC/GTX116.RX3_N")
			(pinfunction "DP0_M2C_N")
			(pintype "passive")
		)
		(pad "C08" smd circle
			(at 15.874 3.173 90)
			(size 0.64 0.64)
			(layers "F.Cu" "F.Mask")
			(net 1 "GND")
			(pinfunction "GND")
			(pintype "passive")
		)
		(pad "C09" smd circle
			(at 14.605 3.173 90)
			(size 0.64 0.64)
			(layers "F.Cu" "F.Mask")
			(net 1 "GND")
			(pinfunction "GND")
			(pintype "passive")
		)
		(pad "C10" smd circle
			(at 13.335 3.173 90)
			(size 0.64 0.64)
			(layers "F.Cu" "F.Mask")
			(net 72 "unconnected-(J18C-LA06_P-PadC10)")
			(pinfunction "LA06_P")
			(pintype "passive+no_connect")
		)
		(pad "C11" smd circle
			(at 12.063 3.173 90)
			(size 0.64 0.64)
			(layers "F.Cu" "F.Mask")
			(net 77 "unconnected-(J18C-LA06_N-PadC11)")
			(pinfunction "LA06_N")
			(pintype "passive+no_connect")
		)
		(pad "C12" smd circle
			(at 10.794 3.173 90)
			(size 0.64 0.64)
			(layers "F.Cu" "F.Mask")
			(net 1 "GND")
			(pinfunction "GND")
			(pintype "passive")
		)
		(pad "C13" smd circle
			(at 9.525 3.173 90)
			(size 0.64 0.64)
			(layers "F.Cu" "F.Mask")
			(net 1 "GND")
			(pinfunction "GND")
			(pintype "passive")
		)
		(pad "C14" smd circle
			(at 8.255 3.173 90)
			(size 0.64 0.64)
			(layers "F.Cu" "F.Mask")
			(net 84 "unconnected-(J18C-LA10_P-PadC14)")
			(pinfunction "LA10_P")
			(pintype "passive+no_connect")
		)
		(pad "C15" smd circle
			(at 6.985 3.173 90)
			(size 0.64 0.64)
			(layers "F.Cu" "F.Mask")
			(net 85 "unconnected-(J18C-LA10_N-PadC15)")
			(pinfunction "LA10_N")
			(pintype "passive+no_connect")
		)
		(pad "C16" smd circle
			(at 5.714 3.173 90)
			(size 0.64 0.64)
			(layers "F.Cu" "F.Mask")
			(net 1 "GND")
			(pinfunction "GND")
			(pintype "passive")
		)
		(pad "C17" smd circle
			(at 4.445 3.173 90)
			(size 0.64 0.64)
			(layers "F.Cu" "F.Mask")
			(net 1 "GND")
			(pinfunction "GND")
			(pintype "passive")
		)
		(pad "C18" smd circle
			(at 3.173 3.173 90)
			(size 0.64 0.64)
			(layers "F.Cu" "F.Mask")
			(net 86 "unconnected-(J18C-LA14_P-PadC18)")
			(pinfunction "LA14_P")
			(pintype "passive+no_connect")
		)
		(pad "C19" smd circle
			(at 1.904 3.173 90)
			(size 0.64 0.64)
			(layers "F.Cu" "F.Mask")
			(net 90 "unconnected-(J18C-LA14_N-PadC19)")
			(pinfunction "LA14_N")
			(pintype "passive+no_connect")
		)
		(pad "C20" smd circle
			(at 0.633 3.173 90)
			(size 0.64 0.64)
			(layers "F.Cu" "F.Mask")
			(net 1 "GND")
			(pinfunction "GND")
			(pintype "passive")
		)
		(pad "C21" smd circle
			(at -0.635 3.173 90)
			(size 0.64 0.64)
			(layers "F.Cu" "F.Mask")
			(net 1 "GND")
			(pinfunction "GND")
			(pintype "passive")
		)
		(pad "C22" smd circle
			(at -1.905 3.173 90)
			(size 0.64 0.64)
			(layers "F.Cu" "F.Mask")
			(net 91 "unconnected-(J18C-LA18_P_CC-PadC22)")
			(pinfunction "LA18_P_CC")
			(pintype "passive+no_connect")
		)
		(pad "C23" smd circle
			(at -3.176 3.173 90)
			(size 0.64 0.64)
			(layers "F.Cu" "F.Mask")
			(net 92 "unconnected-(J18C-LA18_N_CC-PadC23)")
			(pinfunction "LA18_N_CC")
			(pintype "passive+no_connect")
		)
		(pad "C24" smd circle
			(at -4.446 3.173 90)
			(size 0.64 0.64)
			(layers "F.Cu" "F.Mask")
			(net 1 "GND")
			(pinfunction "GND")
			(pintype "passive")
		)
		(pad "C25" smd circle
			(at -5.715 3.173 90)
			(size 0.64 0.64)
			(layers "F.Cu" "F.Mask")
			(net 1 "GND")
			(pinfunction "GND")
			(pintype "passive")
		)
		(pad "C26" smd circle
			(at -6.986 3.173 90)
			(size 0.64 0.64)
			(layers "F.Cu" "F.Mask")
			(net 93 "unconnected-(J18C-LA27_P-PadC26)")
			(pinfunction "LA27_P")
			(pintype "passive+no_connect")
		)
		(pad "C27" smd circle
			(at -8.257 3.173 90)
			(size 0.64 0.64)
			(layers "F.Cu" "F.Mask")
			(net 94 "unconnected-(J18C-LA27_N-PadC27)")
			(pinfunction "LA27_N")
			(pintype "passive+no_connect")
		)
		(pad "C28" smd circle
			(at -9.526 3.173 90)
			(size 0.64 0.64)
			(layers "F.Cu" "F.Mask")
			(net 1 "GND")
			(pinfunction "GND")
			(pintype "passive")
		)
		(pad "C29" smd circle
			(at -10.795 3.173 90)
			(size 0.64 0.64)
			(layers "F.Cu" "F.Mask")
			(net 1 "GND")
			(pinfunction "GND")
			(pintype "passive")
		)
		(pad "C30" smd circle
			(at -12.065 3.173 90)
			(size 0.64 0.64)
			(layers "F.Cu" "F.Mask")
			(net 383 "FMC.SCL_3V3")
			(pinfunction "SCL")
			(pintype "passive")
		)
		(pad "C31" smd circle
			(at -13.337 3.173 90)
			(size 0.64 0.64)
			(layers "F.Cu" "F.Mask")
			(net 380 "FMC.SDA_3V3")
			(pinfunction "SDA")
			(pintype "passive")
		)
		(pad "C32" smd circle
			(at -14.606 3.173 90)
			(size 0.64 0.64)
			(layers "F.Cu" "F.Mask")
			(net 1 "GND")
			(pinfunction "GND")
			(pintype "passive")
		)
		(pad "C33" smd circle
			(at -15.875 3.173 90)
			(size 0.64 0.64)
			(layers "F.Cu" "F.Mask")
			(net 1 "GND")
			(pinfunction "GND")
			(pintype "passive")
		)
		(pad "C34" smd circle
			(at -17.145 3.173 90)
			(size 0.64 0.64)
			(layers "F.Cu" "F.Mask")
			(net 95 "unconnected-(J18B-GA0-PadC34)")
			(pinfunction "GA0")
			(pintype "passive+no_connect")
		)
		(pad "C35" smd circle
			(at -18.415 3.173 90)
			(size 0.64 0.64)
			(layers "F.Cu" "F.Mask")
			(net 59 "12P0V")
			(pinfunction "12P0V")
			(pintype "passive")
		)
		(pad "C36" smd circle
			(at -19.685 3.173 90)
			(size 0.64 0.64)
			(layers "F.Cu" "F.Mask")
			(net 1 "GND")
			(pinfunction "GND")
			(pintype "passive")
		)
		(pad "C37" smd circle
			(at -20.956 3.173 90)
			(size 0.64 0.64)
			(layers "F.Cu" "F.Mask")
			(net 59 "12P0V")
			(pinfunction "12P0V")
			(pintype "passive")
		)
		(pad "C38" smd circle
			(at -22.226 3.173 90)
			(size 0.64 0.64)
			(layers "F.Cu" "F.Mask")
			(net 1 "GND")
			(pinfunction "GND")
			(pintype "passive")
		)
		(pad "C39" smd circle
			(at -23.497 3.173 90)
			(size 0.64 0.64)
			(layers "F.Cu" "F.Mask")
			(net 24 "+3V3")
			(pinfunction "3P3V")
			(pintype "passive")
		)
		(pad "C40" smd circle
			(at -24.767 3.173 90)
			(size 0.64 0.64)
			(layers "F.Cu" "F.Mask")
			(net 1 "GND")
			(pinfunction "GND")
			(pintype "passive")
		)
		(pad "D01" smd circle
			(at 24.765 1.904 90)
			(size 0.64 0.64)
			(layers "F.Cu" "F.Mask")
			(net 99 "Net-(J18B-PG_C2M)")
			(pinfunction "PG_C2M")
			(pintype "passive")
		)
		(pad "D02" smd circle
			(at 23.495 1.904 90)
			(size 0.64 0.64)
			(layers "F.Cu" "F.Mask")
			(net 1 "GND")
			(pinfunction "GND")
			(pintype "passive")
		)
		(pad "D03" smd circle
			(at 22.225 1.904 90)
			(size 0.64 0.64)
			(layers "F.Cu" "F.Mask")
			(net 1 "GND")
			(pinfunction "GND")
			(pintype "passive")
		)
		(pad "D04" smd circle
			(at 20.954 1.904 90)
			(size 0.64 0.64)
			(layers "F.Cu" "F.Mask")
			(net 627 "/FMC+ HSPC/GTR_REFCLK0_R_P")
			(pinfunction "GBTCLK0_M2C_P")
			(pintype "passive")
		)
		(pad "D05" smd circle
			(at 19.684 1.904 90)
			(size 0.64 0.64)
			(layers "F.Cu" "F.Mask")
			(net 629 "/FMC+ HSPC/GTR_REFCLK0_R_N")
			(pinfunction "GBTCLK0_M2C_N")
			(pintype "passive")
		)
		(pad "D06" smd circle
			(at 18.414 1.904 90)
			(size 0.64 0.64)
			(layers "F.Cu" "F.Mask")
			(net 1 "GND")
			(pinfunction "GND")
			(pintype "passive")
		)
		(pad "D07" smd circle
			(at 17.144 1.904 90)
			(size 0.64 0.64)
			(layers "F.Cu" "F.Mask")
			(net 1 "GND")
			(pinfunction "GND")
			(pintype "passive")
		)
		(pad "D08" smd circle
			(at 15.874 1.904 90)
			(size 0.64 0.64)
			(layers "F.Cu" "F.Mask")
			(net 695 "/FMC+ HSPC/FMC.~{PERST}")
			(pinfunction "LA01_P_CC")
			(pintype "passive")
		)
		(pad "D09" smd circle
			(at 14.605 1.904 90)
			(size 0.64 0.64)
			(layers "F.Cu" "F.Mask")
			(net 100 "unconnected-(J18C-LA01_N_CC-PadD09)")
			(pinfunction "LA01_N_CC")
			(pintype "passive+no_connect")
		)
		(pad "D10" smd circle
			(at 13.335 1.904 90)
			(size 0.64 0.64)
			(layers "F.Cu" "F.Mask")
			(net 1 "GND")
			(pinfunction "GND")
			(pintype "passive")
		)
		(pad "D11" smd circle
			(at 12.063 1.904 90)
			(size 0.64 0.64)
			(layers "F.Cu" "F.Mask")
			(net 102 "unconnected-(J18C-LA05_P-PadD11)")
			(pinfunction "LA05_P")
			(pintype "passive+no_connect")
		)
		(pad "D12" smd circle
			(at 10.794 1.904 90)
			(size 0.64 0.64)
			(layers "F.Cu" "F.Mask")
			(net 103 "unconnected-(J18C-LA05_N-PadD12)")
			(pinfunction "LA05_N")
			(pintype "passive+no_connect")
		)
		(pad "D13" smd circle
			(at 9.525 1.904 90)
			(size 0.64 0.64)
			(layers "F.Cu" "F.Mask")
			(net 1 "GND")
			(pinfunction "GND")
			(pintype "passive")
		)
		(pad "D14" smd circle
			(at 8.255 1.904 90)
			(size 0.64 0.64)
			(layers "F.Cu" "F.Mask")
			(net 104 "unconnected-(J18C-LA09_P-PadD14)")
			(pinfunction "LA09_P")
			(pintype "passive+no_connect")
		)
		(pad "D15" smd circle
			(at 6.985 1.904 90)
			(size 0.64 0.64)
			(layers "F.Cu" "F.Mask")
			(net 106 "unconnected-(J18C-LA09_N-PadD15)")
			(pinfunction "LA09_N")
			(pintype "passive+no_connect")
		)
		(pad "D16" smd circle
			(at 5.714 1.904 90)
			(size 0.64 0.64)
			(layers "F.Cu" "F.Mask")
			(net 1 "GND")
			(pinfunction "GND")
			(pintype "passive")
		)
		(pad "D17" smd circle
			(at 4.445 1.904 90)
			(size 0.64 0.64)
			(layers "F.Cu" "F.Mask")
			(net 108 "unconnected-(J18C-LA13_P-PadD17)")
			(pinfunction "LA13_P")
			(pintype "passive+no_connect")
		)
		(pad "D18" smd circle
			(at 3.173 1.904 90)
			(size 0.64 0.64)
			(layers "F.Cu" "F.Mask")
			(net 110 "unconnected-(J18C-LA13_N-PadD18)")
			(pinfunction "LA13_N")
			(pintype "passive+no_connect")
		)
		(pad "D19" smd circle
			(at 1.904 1.904 90)
			(size 0.64 0.64)
			(layers "F.Cu" "F.Mask")
			(net 1 "GND")
			(pinfunction "GND")
			(pintype "passive")
		)
		(pad "D20" smd circle
			(at 0.633 1.904 90)
			(size 0.64 0.64)
			(layers "F.Cu" "F.Mask")
			(net 114 "unconnected-(J18C-LA17_P_CC-PadD20)")
			(pinfunction "LA17_P_CC")
			(pintype "passive+no_connect")
		)
		(pad "D21" smd circle
			(at -0.635 1.904 90)
			(size 0.64 0.64)
			(layers "F.Cu" "F.Mask")
			(net 116 "unconnected-(J18C-LA17_N_CC-PadD21)")
			(pinfunction "LA17_N_CC")
			(pintype "passive+no_connect")
		)
		(pad "D22" smd circle
			(at -1.905 1.904 90)
			(size 0.64 0.64)
			(layers "F.Cu" "F.Mask")
			(net 1 "GND")
			(pinfunction "GND")
			(pintype "passive")
		)
		(pad "D23" smd circle
			(at -3.176 1.904 90)
			(size 0.64 0.64)
			(layers "F.Cu" "F.Mask")
			(net 117 "unconnected-(J18C-LA23_P-PadD23)")
			(pinfunction "LA23_P")
			(pintype "passive+no_connect")
		)
		(pad "D24" smd circle
			(at -4.446 1.904 90)
			(size 0.64 0.64)
			(layers "F.Cu" "F.Mask")
			(net 118 "unconnected-(J18C-LA23_N-PadD24)")
			(pinfunction "LA23_N")
			(pintype "passive+no_connect")
		)
		(pad "D25" smd circle
			(at -5.715 1.904 90)
			(size 0.64 0.64)
			(layers "F.Cu" "F.Mask")
			(net 1 "GND")
			(pinfunction "GND")
			(pintype "passive")
		)
		(pad "D26" smd circle
			(at -6.986 1.904 90)
			(size 0.64 0.64)
			(layers "F.Cu" "F.Mask")
			(net 120 "unconnected-(J18C-LA26_P-PadD26)")
			(pinfunction "LA26_P")
			(pintype "passive+no_connect")
		)
		(pad "D27" smd circle
			(at -8.257 1.904 90)
			(size 0.64 0.64)
			(layers "F.Cu" "F.Mask")
			(net 121 "unconnected-(J18C-LA26_N-PadD27)")
			(pinfunction "LA26_N")
			(pintype "passive+no_connect")
		)
		(pad "D28" smd circle
			(at -9.526 1.904 90)
			(size 0.64 0.64)
			(layers "F.Cu" "F.Mask")
			(net 1 "GND")
			(pinfunction "GND")
			(pintype "passive")
		)
		(pad "D29" smd circle
			(at -10.795 1.904 90)
			(size 0.64 0.64)
			(layers "F.Cu" "F.Mask")
			(net 165 "/FPGA Config/JTAG.TCK")
			(pinfunction "TCK")
			(pintype "passive")
		)
		(pad "D30" smd circle
			(at -12.065 1.904 90)
			(size 0.64 0.64)
			(layers "F.Cu" "F.Mask")
			(net 220 "/FPGA Config/JTAG.TDI")
			(pinfunction "TDI")
			(pintype "passive")
		)
		(pad "D31" smd circle
			(at -13.337 1.904 90)
			(size 0.64 0.64)
			(layers "F.Cu" "F.Mask")
			(net 190 "/FPGA Config/JTAG.TDO")
			(pinfunction "TDO")
			(pintype "passive")
		)
		(pad "D32" smd circle
			(at -14.606 1.904 90)
			(size 0.64 0.64)
			(layers "F.Cu" "F.Mask")
			(net 125 "unconnected-(J18A-3P3VAUX-PadD32)")
			(pinfunction "3P3VAUX")
			(pintype "passive+no_connect")
		)
		(pad "D33" smd circle
			(at -15.875 1.904 90)
			(size 0.64 0.64)
			(layers "F.Cu" "F.Mask")
			(net 161 "/FPGA Config/JTAG.TMS")
			(pinfunction "TMS")
			(pintype "passive")
		)
		(pad "D34" smd circle
			(at -17.145 1.904 90)
			(size 0.64 0.64)
			(layers "F.Cu" "F.Mask")
			(net 431 "/FPGA Config/JTAG.RST")
			(pinfunction "TRST_L")
			(pintype "passive")
		)
		(pad "D35" smd circle
			(at -18.415 1.904 90)
			(size 0.64 0.64)
			(layers "F.Cu" "F.Mask")
			(net 126 "unconnected-(J18B-GA1-PadD35)")
			(pinfunction "GA1")
			(pintype "passive+no_connect")
		)
		(pad "D36" smd circle
			(at -19.685 1.904 90)
			(size 0.64 0.64)
			(layers "F.Cu" "F.Mask")
			(net 24 "+3V3")
			(pinfunction "3P3V")
			(pintype "passive")
		)
		(pad "D37" smd circle
			(at -20.956 1.904 90)
			(size 0.64 0.64)
			(layers "F.Cu" "F.Mask")
			(net 1 "GND")
			(pinfunction "GND")
			(pintype "passive")
		)
		(pad "D38" smd circle
			(at -22.226 1.904 90)
			(size 0.64 0.64)
			(layers "F.Cu" "F.Mask")
			(net 24 "+3V3")
			(pinfunction "3P3V")
			(pintype "passive")
		)
		(pad "D39" smd circle
			(at -23.497 1.904 90)
			(size 0.64 0.64)
			(layers "F.Cu" "F.Mask")
			(net 1 "GND")
			(pinfunction "GND")
			(pintype "passive")
		)
		(pad "D40" smd circle
			(at -24.767 1.904 90)
			(size 0.64 0.64)
			(layers "F.Cu" "F.Mask")
			(net 24 "+3V3")
			(pinfunction "3P3V")
			(pintype "passive")
		)
		(pad "E01" smd circle
			(at 24.765 0.633 90)
			(size 0.64 0.64)
			(layers "F.Cu" "F.Mask")
			(net 1 "GND")
			(pinfunction "GND")
			(pintype "passive")
		)
		(pad "E02" smd circle
			(at 23.495 0.633 90)
			(size 0.64 0.64)
			(layers "F.Cu" "F.Mask")
			(net 127 "unconnected-(J18D-HA01_P_CC-PadE02)")
			(pinfunction "HA01_P_CC")
			(pintype "passive+no_connect")
		)
		(pad "E03" smd circle
			(at 22.225 0.633 90)
			(size 0.64 0.64)
			(layers "F.Cu" "F.Mask")
			(net 128 "unconnected-(J18D-HA01_N_CC-PadE03)")
			(pinfunction "HA01_N_CC")
			(pintype "passive+no_connect")
		)
		(pad "E04" smd circle
			(at 20.954 0.633 90)
			(size 0.64 0.64)
			(layers "F.Cu" "F.Mask")
			(net 1 "GND")
			(pinfunction "GND")
			(pintype "passive")
		)
		(pad "E05" smd circle
			(at 19.684 0.633 90)
			(size 0.64 0.64)
			(layers "F.Cu" "F.Mask")
			(net 1 "GND")
			(pinfunction "GND")
			(pintype "passive")
		)
		(pad "E06" smd circle
			(at 18.414 0.633 90)
			(size 0.64 0.64)
			(layers "F.Cu" "F.Mask")
			(net 129 "unconnected-(J18D-HA05_P-PadE06)")
			(pinfunction "HA05_P")
			(pintype "passive+no_connect")
		)
		(pad "E07" smd circle
			(at 17.144 0.633 90)
			(size 0.64 0.64)
			(layers "F.Cu" "F.Mask")
			(net 130 "unconnected-(J18D-HA05_N-PadE07)")
			(pinfunction "HA05_N")
			(pintype "passive+no_connect")
		)
		(pad "E08" smd circle
			(at 15.874 0.633 90)
			(size 0.64 0.64)
			(layers "F.Cu" "F.Mask")
			(net 1 "GND")
			(pinfunction "GND")
			(pintype "passive")
		)
		(pad "E09" smd circle
			(at 14.605 0.633 90)
			(size 0.64 0.64)
			(layers "F.Cu" "F.Mask")
			(net 131 "unconnected-(J18D-HA09_P-PadE09)")
			(pinfunction "HA09_P")
			(pintype "passive+no_connect")
		)
		(pad "E10" smd circle
			(at 13.335 0.633 90)
			(size 0.64 0.64)
			(layers "F.Cu" "F.Mask")
			(net 132 "unconnected-(J18D-HA09_N-PadE10)")
			(pinfunction "HA09_N")
			(pintype "passive+no_connect")
		)
		(pad "E11" smd circle
			(at 12.063 0.633 90)
			(size 0.64 0.64)
			(layers "F.Cu" "F.Mask")
			(net 1 "GND")
			(pinfunction "GND")
			(pintype "passive")
		)
		(pad "E12" smd circle
			(at 10.794 0.633 90)
			(size 0.64 0.64)
			(layers "F.Cu" "F.Mask")
			(net 133 "unconnected-(J18D-HA13_P-PadE12)")
			(pinfunction "HA13_P")
			(pintype "passive+no_connect")
		)
		(pad "E13" smd circle
			(at 9.525 0.633 90)
			(size 0.64 0.64)
			(layers "F.Cu" "F.Mask")
			(net 134 "unconnected-(J18D-HA13_N-PadE13)")
			(pinfunction "HA13_N")
			(pintype "passive+no_connect")
		)
		(pad "E14" smd circle
			(at 8.255 0.633 90)
			(size 0.64 0.64)
			(layers "F.Cu" "F.Mask")
			(net 1 "GND")
			(pinfunction "GND")
			(pintype "passive")
		)
		(pad "E15" smd circle
			(at 6.985 0.633 90)
			(size 0.64 0.64)
			(layers "F.Cu" "F.Mask")
			(net 135 "unconnected-(J18D-HA16_P-PadE15)")
			(pinfunction "HA16_P")
			(pintype "passive+no_connect")
		)
		(pad "E16" smd circle
			(at 5.714 0.633 90)
			(size 0.64 0.64)
			(layers "F.Cu" "F.Mask")
			(net 136 "unconnected-(J18D-HA16_N-PadE16)")
			(pinfunction "HA16_N")
			(pintype "passive+no_connect")
		)
		(pad "E17" smd circle
			(at 4.445 0.633 90)
			(size 0.64 0.64)
			(layers "F.Cu" "F.Mask")
			(net 1 "GND")
			(pinfunction "GND")
			(pintype "passive")
		)
		(pad "E18" smd circle
			(at 3.173 0.633 90)
			(size 0.64 0.64)
			(layers "F.Cu" "F.Mask")
			(net 137 "unconnected-(J18D-HA20_P-PadE18)")
			(pinfunction "HA20_P")
			(pintype "passive+no_connect")
		)
		(pad "E19" smd circle
			(at 1.904 0.633 90)
			(size 0.64 0.64)
			(layers "F.Cu" "F.Mask")
			(net 138 "unconnected-(J18D-HA20_N-PadE19)")
			(pinfunction "HA20_N")
			(pintype "passive+no_connect")
		)
		(pad "E20" smd circle
			(at 0.633 0.633 90)
			(size 0.64 0.64)
			(layers "F.Cu" "F.Mask")
			(net 1 "GND")
			(pinfunction "GND")
			(pintype "passive")
		)
		(pad "E21" smd circle
			(at -0.635 0.633 90)
			(size 0.64 0.64)
			(layers "F.Cu" "F.Mask")
			(net 139 "unconnected-(J18E-HB03_P-PadE21)")
			(pinfunction "HB03_P")
			(pintype "passive+no_connect")
		)
		(pad "E22" smd circle
			(at -1.905 0.633 90)
			(size 0.64 0.64)
			(layers "F.Cu" "F.Mask")
			(net 140 "unconnected-(J18E-HB03_N-PadE22)")
			(pinfunction "HB03_N")
			(pintype "passive+no_connect")
		)
		(pad "E23" smd circle
			(at -3.176 0.633 90)
			(size 0.64 0.64)
			(layers "F.Cu" "F.Mask")
			(net 1 "GND")
			(pinfunction "GND")
			(pintype "passive")
		)
		(pad "E24" smd circle
			(at -4.446 0.633 90)
			(size 0.64 0.64)
			(layers "F.Cu" "F.Mask")
			(net 141 "unconnected-(J18E-HB05_P-PadE24)")
			(pinfunction "HB05_P")
			(pintype "passive+no_connect")
		)
		(pad "E25" smd circle
			(at -5.715 0.633 90)
			(size 0.64 0.64)
			(layers "F.Cu" "F.Mask")
			(net 142 "unconnected-(J18E-HB05_N-PadE25)")
			(pinfunction "HB05_N")
			(pintype "passive+no_connect")
		)
		(pad "E26" smd circle
			(at -6.986 0.633 90)
			(size 0.64 0.64)
			(layers "F.Cu" "F.Mask")
			(net 1 "GND")
			(pinfunction "GND")
			(pintype "passive")
		)
		(pad "E27" smd circle
			(at -8.257 0.633 90)
			(size 0.64 0.64)
			(layers "F.Cu" "F.Mask")
			(net 144 "unconnected-(J18E-HB09_P-PadE27)")
			(pinfunction "HB09_P")
			(pintype "passive+no_connect")
		)
		(pad "E28" smd circle
			(at -9.526 0.633 90)
			(size 0.64 0.64)
			(layers "F.Cu" "F.Mask")
			(net 145 "unconnected-(J18E-HB09_N-PadE28)")
			(pinfunction "HB09_N")
			(pintype "passive+no_connect")
		)
		(pad "E29" smd circle
			(at -10.795 0.633 90)
			(size 0.64 0.64)
			(layers "F.Cu" "F.Mask")
			(net 1 "GND")
			(pinfunction "GND")
			(pintype "passive")
		)
		(pad "E30" smd circle
			(at -12.065 0.633 90)
			(size 0.64 0.64)
			(layers "F.Cu" "F.Mask")
			(net 146 "unconnected-(J18E-HB13_P-PadE30)")
			(pinfunction "HB13_P")
			(pintype "passive+no_connect")
		)
		(pad "E31" smd circle
			(at -13.337 0.633 90)
			(size 0.64 0.64)
			(layers "F.Cu" "F.Mask")
			(net 147 "unconnected-(J18E-HB13_N-PadE31)")
			(pinfunction "HB13_N")
			(pintype "passive+no_connect")
		)
		(pad "E32" smd circle
			(at -14.606 0.633 90)
			(size 0.64 0.64)
			(layers "F.Cu" "F.Mask")
			(net 1 "GND")
			(pinfunction "GND")
			(pintype "passive")
		)
		(pad "E33" smd circle
			(at -15.875 0.633 90)
			(size 0.64 0.64)
			(layers "F.Cu" "F.Mask")
			(net 148 "unconnected-(J18E-HB19_P-PadE33)")
			(pinfunction "HB19_P")
			(pintype "passive+no_connect")
		)
		(pad "E34" smd circle
			(at -17.145 0.633 90)
			(size 0.64 0.64)
			(layers "F.Cu" "F.Mask")
			(net 149 "unconnected-(J18E-HB19_N-PadE34)")
			(pinfunction "HB19_N")
			(pintype "passive+no_connect")
		)
		(pad "E35" smd circle
			(at -18.415 0.633 90)
			(size 0.64 0.64)
			(layers "F.Cu" "F.Mask")
			(net 1 "GND")
			(pinfunction "GND")
			(pintype "passive")
		)
		(pad "E36" smd circle
			(at -19.685 0.633 90)
			(size 0.64 0.64)
			(layers "F.Cu" "F.Mask")
			(net 150 "unconnected-(J18E-HB21_P-PadE36)")
			(pinfunction "HB21_P")
			(pintype "passive+no_connect")
		)
		(pad "E37" smd circle
			(at -20.956 0.633 90)
			(size 0.64 0.64)
			(layers "F.Cu" "F.Mask")
			(net 151 "unconnected-(J18E-HB21_N-PadE37)")
			(pinfunction "HB21_N")
			(pintype "passive+no_connect")
		)
		(pad "E38" smd circle
			(at -22.226 0.633 90)
			(size 0.64 0.64)
			(layers "F.Cu" "F.Mask")
			(net 1 "GND")
			(pinfunction "GND")
			(pintype "passive")
		)
		(pad "E39" smd circle
			(at -23.497 0.633 90)
			(size 0.64 0.64)
			(layers "F.Cu" "F.Mask")
			(net 152 "unconnected-(J18A-VADJ-PadE39)")
			(pinfunction "VADJ")
			(pintype "passive+no_connect")
		)
		(pad "E40" smd circle
			(at -24.767 0.633 90)
			(size 0.64 0.64)
			(layers "F.Cu" "F.Mask")
			(net 1 "GND")
			(pinfunction "GND")
			(pintype "passive")
		)
		(pad "F01" smd circle
			(at 24.765 -0.635 90)
			(size 0.64 0.64)
			(layers "F.Cu" "F.Mask")
			(net 153 "Net-(J18B-PG_M2C)")
			(pinfunction "PG_M2C")
			(pintype "passive")
		)
		(pad "F02" smd circle
			(at 23.495 -0.635 90)
			(size 0.64 0.64)
			(layers "F.Cu" "F.Mask")
			(net 1 "GND")
			(pinfunction "GND")
			(pintype "passive")
		)
		(pad "F03" smd circle
			(at 22.225 -0.635 90)
			(size 0.64 0.64)
			(layers "F.Cu" "F.Mask")
			(net 1 "GND")
			(pinfunction "GND")
			(pintype "passive")
		)
		(pad "F04" smd circle
			(at 20.954 -0.635 90)
			(size 0.64 0.64)
			(layers "F.Cu" "F.Mask")
			(net 154 "unconnected-(J18D-HA00_P_CC-PadF04)")
			(pinfunction "HA00_P_CC")
			(pintype "passive+no_connect")
		)
		(pad "F05" smd circle
			(at 19.684 -0.635 90)
			(size 0.64 0.64)
			(layers "F.Cu" "F.Mask")
			(net 155 "unconnected-(J18D-HA00_N_CC-PadF05)")
			(pinfunction "HA00_N_CC")
			(pintype "passive+no_connect")
		)
		(pad "F06" smd circle
			(at 18.414 -0.635 90)
			(size 0.64 0.64)
			(layers "F.Cu" "F.Mask")
			(net 1 "GND")
			(pinfunction "GND")
			(pintype "passive")
		)
		(pad "F07" smd circle
			(at 17.144 -0.635 90)
			(size 0.64 0.64)
			(layers "F.Cu" "F.Mask")
			(net 156 "unconnected-(J18D-HA04_P-PadF07)")
			(pinfunction "HA04_P")
			(pintype "passive+no_connect")
		)
		(pad "F08" smd circle
			(at 15.874 -0.635 90)
			(size 0.64 0.64)
			(layers "F.Cu" "F.Mask")
			(net 157 "unconnected-(J18D-HA04_N-PadF08)")
			(pinfunction "HA04_N")
			(pintype "passive+no_connect")
		)
		(pad "F09" smd circle
			(at 14.605 -0.635 90)
			(size 0.64 0.64)
			(layers "F.Cu" "F.Mask")
			(net 1 "GND")
			(pinfunction "GND")
			(pintype "passive")
		)
		(pad "F10" smd circle
			(at 13.335 -0.635 90)
			(size 0.64 0.64)
			(layers "F.Cu" "F.Mask")
			(net 158 "unconnected-(J18D-HA08_P-PadF10)")
			(pinfunction "HA08_P")
			(pintype "passive+no_connect")
		)
		(pad "F11" smd circle
			(at 12.063 -0.635 90)
			(size 0.64 0.64)
			(layers "F.Cu" "F.Mask")
			(net 159 "unconnected-(J18D-HA08_N-PadF11)")
			(pinfunction "HA08_N")
			(pintype "passive+no_connect")
		)
		(pad "F12" smd circle
			(at 10.794 -0.635 90)
			(size 0.64 0.64)
			(layers "F.Cu" "F.Mask")
			(net 1 "GND")
			(pinfunction "GND")
			(pintype "passive")
		)
		(pad "F13" smd circle
			(at 9.525 -0.635 90)
			(size 0.64 0.64)
			(layers "F.Cu" "F.Mask")
			(net 160 "unconnected-(J18D-HA12_P-PadF13)")
			(pinfunction "HA12_P")
			(pintype "passive+no_connect")
		)
		(pad "F14" smd circle
			(at 8.255 -0.635 90)
			(size 0.64 0.64)
			(layers "F.Cu" "F.Mask")
			(net 162 "unconnected-(J18D-HA12_N-PadF14)")
			(pinfunction "HA12_N")
			(pintype "passive+no_connect")
		)
		(pad "F15" smd circle
			(at 6.985 -0.635 90)
			(size 0.64 0.64)
			(layers "F.Cu" "F.Mask")
			(net 1 "GND")
			(pinfunction "GND")
			(pintype "passive")
		)
		(pad "F16" smd circle
			(at 5.714 -0.635 90)
			(size 0.64 0.64)
			(layers "F.Cu" "F.Mask")
			(net 163 "unconnected-(J18D-HA15_P-PadF16)")
			(pinfunction "HA15_P")
			(pintype "passive+no_connect")
		)
		(pad "F17" smd circle
			(at 4.445 -0.635 90)
			(size 0.64 0.64)
			(layers "F.Cu" "F.Mask")
			(net 164 "unconnected-(J18D-HA15_N-PadF17)")
			(pinfunction "HA15_N")
			(pintype "passive+no_connect")
		)
		(pad "F18" smd circle
			(at 3.173 -0.635 90)
			(size 0.64 0.64)
			(layers "F.Cu" "F.Mask")
			(net 1 "GND")
			(pinfunction "GND")
			(pintype "passive")
		)
		(pad "F19" smd circle
			(at 1.904 -0.635 90)
			(size 0.64 0.64)
			(layers "F.Cu" "F.Mask")
			(net 166 "unconnected-(J18D-HA19_P-PadF19)")
			(pinfunction "HA19_P")
			(pintype "passive+no_connect")
		)
		(pad "F20" smd circle
			(at 0.633 -0.635 90)
			(size 0.64 0.64)
			(layers "F.Cu" "F.Mask")
			(net 167 "unconnected-(J18D-HA19_N-PadF20)")
			(pinfunction "HA19_N")
			(pintype "passive+no_connect")
		)
		(pad "F21" smd circle
			(at -0.635 -0.635 90)
			(size 0.64 0.64)
			(layers "F.Cu" "F.Mask")
			(net 1 "GND")
			(pinfunction "GND")
			(pintype "passive")
		)
		(pad "F22" smd circle
			(at -1.905 -0.635 90)
			(size 0.64 0.64)
			(layers "F.Cu" "F.Mask")
			(net 168 "unconnected-(J18E-HB02_P-PadF22)")
			(pinfunction "HB02_P")
			(pintype "passive+no_connect")
		)
		(pad "F23" smd circle
			(at -3.176 -0.635 90)
			(size 0.64 0.64)
			(layers "F.Cu" "F.Mask")
			(net 169 "unconnected-(J18E-HB02_N-PadF23)")
			(pinfunction "HB02_N")
			(pintype "passive+no_connect")
		)
		(pad "F24" smd circle
			(at -4.446 -0.635 90)
			(size 0.64 0.64)
			(layers "F.Cu" "F.Mask")
			(net 1 "GND")
			(pinfunction "GND")
			(pintype "passive")
		)
		(pad "F25" smd circle
			(at -5.715 -0.635 90)
			(size 0.64 0.64)
			(layers "F.Cu" "F.Mask")
			(net 170 "unconnected-(J18E-HB04_P-PadF25)")
			(pinfunction "HB04_P")
			(pintype "passive+no_connect")
		)
		(pad "F26" smd circle
			(at -6.986 -0.635 90)
			(size 0.64 0.64)
			(layers "F.Cu" "F.Mask")
			(net 171 "unconnected-(J18E-HB04_N-PadF26)")
			(pinfunction "HB04_N")
			(pintype "passive+no_connect")
		)
		(pad "F27" smd circle
			(at -8.257 -0.635 90)
			(size 0.64 0.64)
			(layers "F.Cu" "F.Mask")
			(net 1 "GND")
			(pinfunction "GND")
			(pintype "passive")
		)
		(pad "F28" smd circle
			(at -9.526 -0.635 90)
			(size 0.64 0.64)
			(layers "F.Cu" "F.Mask")
			(net 172 "unconnected-(J18E-HB08_P-PadF28)")
			(pinfunction "HB08_P")
			(pintype "passive+no_connect")
		)
		(pad "F29" smd circle
			(at -10.795 -0.635 90)
			(size 0.64 0.64)
			(layers "F.Cu" "F.Mask")
			(net 173 "unconnected-(J18E-HB08_N-PadF29)")
			(pinfunction "HB08_N")
			(pintype "passive+no_connect")
		)
		(pad "F30" smd circle
			(at -12.065 -0.635 90)
			(size 0.64 0.64)
			(layers "F.Cu" "F.Mask")
			(net 1 "GND")
			(pinfunction "GND")
			(pintype "passive")
		)
		(pad "F31" smd circle
			(at -13.337 -0.635 90)
			(size 0.64 0.64)
			(layers "F.Cu" "F.Mask")
			(net 174 "unconnected-(J18E-HB12_P-PadF31)")
			(pinfunction "HB12_P")
			(pintype "passive+no_connect")
		)
		(pad "F32" smd circle
			(at -14.606 -0.635 90)
			(size 0.64 0.64)
			(layers "F.Cu" "F.Mask")
			(net 175 "unconnected-(J18E-HB12_N-PadF32)")
			(pinfunction "HB12_N")
			(pintype "passive+no_connect")
		)
		(pad "F33" smd circle
			(at -15.875 -0.635 90)
			(size 0.64 0.64)
			(layers "F.Cu" "F.Mask")
			(net 1 "GND")
			(pinfunction "GND")
			(pintype "passive")
		)
		(pad "F34" smd circle
			(at -17.145 -0.635 90)
			(size 0.64 0.64)
			(layers "F.Cu" "F.Mask")
			(net 176 "unconnected-(J18E-HB16_P-PadF34)")
			(pinfunction "HB16_P")
			(pintype "passive+no_connect")
		)
		(pad "F35" smd circle
			(at -18.415 -0.635 90)
			(size 0.64 0.64)
			(layers "F.Cu" "F.Mask")
			(net 177 "unconnected-(J18E-HB16_N-PadF35)")
			(pinfunction "HB16_N")
			(pintype "passive+no_connect")
		)
		(pad "F36" smd circle
			(at -19.685 -0.635 90)
			(size 0.64 0.64)
			(layers "F.Cu" "F.Mask")
			(net 1 "GND")
			(pinfunction "GND")
			(pintype "passive")
		)
		(pad "F37" smd circle
			(at -20.956 -0.635 90)
			(size 0.64 0.64)
			(layers "F.Cu" "F.Mask")
			(net 178 "unconnected-(J18E-HB20_P-PadF37)")
			(pinfunction "HB20_P")
			(pintype "passive+no_connect")
		)
		(pad "F38" smd circle
			(at -22.226 -0.635 90)
			(size 0.64 0.64)
			(layers "F.Cu" "F.Mask")
			(net 179 "unconnected-(J18E-HB20_N-PadF38)")
			(pinfunction "HB20_N")
			(pintype "passive+no_connect")
		)
		(pad "F39" smd circle
			(at -23.497 -0.635 90)
			(size 0.64 0.64)
			(layers "F.Cu" "F.Mask")
			(net 1 "GND")
			(pinfunction "GND")
			(pintype "passive")
		)
		(pad "F40" smd circle
			(at -24.767 -0.635 90)
			(size 0.64 0.64)
			(layers "F.Cu" "F.Mask")
			(net 152 "unconnected-(J18A-VADJ-PadE39)")
			(pinfunction "VADJ")
			(pintype "passive+no_connect")
		)
		(pad "G01" smd circle
			(at 24.765 -1.905 90)
			(size 0.64 0.64)
			(layers "F.Cu" "F.Mask")
			(net 1 "GND")
			(pinfunction "GND")
			(pintype "passive")
		)
		(pad "G02" smd circle
			(at 23.495 -1.905 90)
			(size 0.64 0.64)
			(layers "F.Cu" "F.Mask")
			(net 180 "unconnected-(J18F-CLK1_M2C_P-PadG02)")
			(pinfunction "CLK1_M2C_P")
			(pintype "passive+no_connect")
		)
		(pad "G03" smd circle
			(at 22.225 -1.905 90)
			(size 0.64 0.64)
			(layers "F.Cu" "F.Mask")
			(net 181 "unconnected-(J18F-CLK1_M2C_N-PadG03)")
			(pinfunction "CLK1_M2C_N")
			(pintype "passive+no_connect")
		)
		(pad "G04" smd circle
			(at 20.954 -1.905 90)
			(size 0.64 0.64)
			(layers "F.Cu" "F.Mask")
			(net 1 "GND")
			(pinfunction "GND")
			(pintype "passive")
		)
		(pad "G05" smd circle
			(at 19.684 -1.905 90)
			(size 0.64 0.64)
			(layers "F.Cu" "F.Mask")
			(net 1 "GND")
			(pinfunction "GND")
			(pintype "passive")
		)
		(pad "G06" smd circle
			(at 18.414 -1.905 90)
			(size 0.64 0.64)
			(layers "F.Cu" "F.Mask")
			(net 182 "unconnected-(J18C-LA00_P_CC-PadG06)")
			(pinfunction "LA00_P_CC")
			(pintype "passive+no_connect")
		)
		(pad "G07" smd circle
			(at 17.144 -1.905 90)
			(size 0.64 0.64)
			(layers "F.Cu" "F.Mask")
			(net 183 "unconnected-(J18C-LA00_N_CC-PadG07)")
			(pinfunction "LA00_N_CC")
			(pintype "passive+no_connect")
		)
		(pad "G08" smd circle
			(at 15.874 -1.905 90)
			(size 0.64 0.64)
			(layers "F.Cu" "F.Mask")
			(net 1 "GND")
			(pinfunction "GND")
			(pintype "passive")
		)
		(pad "G09" smd circle
			(at 14.605 -1.905 90)
			(size 0.64 0.64)
			(layers "F.Cu" "F.Mask")
			(net 184 "unconnected-(J18C-LA03_P-PadG09)")
			(pinfunction "LA03_P")
			(pintype "passive+no_connect")
		)
		(pad "G10" smd circle
			(at 13.335 -1.905 90)
			(size 0.64 0.64)
			(layers "F.Cu" "F.Mask")
			(net 185 "unconnected-(J18C-LA03_N-PadG10)")
			(pinfunction "LA03_N")
			(pintype "passive+no_connect")
		)
		(pad "G11" smd circle
			(at 12.063 -1.905 90)
			(size 0.64 0.64)
			(layers "F.Cu" "F.Mask")
			(net 1 "GND")
			(pinfunction "GND")
			(pintype "passive")
		)
		(pad "G12" smd circle
			(at 10.794 -1.905 90)
			(size 0.64 0.64)
			(layers "F.Cu" "F.Mask")
			(net 186 "unconnected-(J18C-LA08_P-PadG12)")
			(pinfunction "LA08_P")
			(pintype "passive+no_connect")
		)
		(pad "G13" smd circle
			(at 9.525 -1.905 90)
			(size 0.64 0.64)
			(layers "F.Cu" "F.Mask")
			(net 187 "unconnected-(J18C-LA08_N-PadG13)")
			(pinfunction "LA08_N")
			(pintype "passive+no_connect")
		)
		(pad "G14" smd circle
			(at 8.255 -1.905 90)
			(size 0.64 0.64)
			(layers "F.Cu" "F.Mask")
			(net 1 "GND")
			(pinfunction "GND")
			(pintype "passive")
		)
		(pad "G15" smd circle
			(at 6.985 -1.905 90)
			(size 0.64 0.64)
			(layers "F.Cu" "F.Mask")
			(net 188 "unconnected-(J18C-LA12_P-PadG15)")
			(pinfunction "LA12_P")
			(pintype "passive+no_connect")
		)
		(pad "G16" smd circle
			(at 5.714 -1.905 90)
			(size 0.64 0.64)
			(layers "F.Cu" "F.Mask")
			(net 189 "unconnected-(J18C-LA12_N-PadG16)")
			(pinfunction "LA12_N")
			(pintype "passive+no_connect")
		)
		(pad "G17" smd circle
			(at 4.445 -1.905 90)
			(size 0.64 0.64)
			(layers "F.Cu" "F.Mask")
			(net 1 "GND")
			(pinfunction "GND")
			(pintype "passive")
		)
		(pad "G18" smd circle
			(at 3.173 -1.905 90)
			(size 0.64 0.64)
			(layers "F.Cu" "F.Mask")
			(net 455 "/FMC+ HSPC/FMC.IO2_P")
			(pinfunction "LA16_P")
			(pintype "passive")
		)
		(pad "G19" smd circle
			(at 1.904 -1.905 90)
			(size 0.64 0.64)
			(layers "F.Cu" "F.Mask")
			(net 450 "/FMC+ HSPC/FMC.IO2_N")
			(pinfunction "LA16_N")
			(pintype "passive")
		)
		(pad "G20" smd circle
			(at 0.633 -1.905 90)
			(size 0.64 0.64)
			(layers "F.Cu" "F.Mask")
			(net 1 "GND")
			(pinfunction "GND")
			(pintype "passive")
		)
		(pad "G21" smd circle
			(at -0.635 -1.905 90)
			(size 0.64 0.64)
			(layers "F.Cu" "F.Mask")
			(net 418 "/FMC+ HSPC/FMC.IO1_P")
			(pinfunction "LA20_P")
			(pintype "passive")
		)
		(pad "G22" smd circle
			(at -1.905 -1.905 90)
			(size 0.64 0.64)
			(layers "F.Cu" "F.Mask")
			(net 414 "/FMC+ HSPC/FMC.IO1_N")
			(pinfunction "LA20_N")
			(pintype "passive")
		)
		(pad "G23" smd circle
			(at -3.176 -1.905 90)
			(size 0.64 0.64)
			(layers "F.Cu" "F.Mask")
			(net 1 "GND")
			(pinfunction "GND")
			(pintype "passive")
		)
		(pad "G24" smd circle
			(at -4.446 -1.905 90)
			(size 0.64 0.64)
			(layers "F.Cu" "F.Mask")
			(net 405 "/FMC+ HSPC/FMC.IO6_P")
			(pinfunction "LA22_P")
			(pintype "passive")
		)
		(pad "G25" smd circle
			(at -5.715 -1.905 90)
			(size 0.64 0.64)
			(layers "F.Cu" "F.Mask")
			(net 401 "/FMC+ HSPC/FMC.IO6_N")
			(pinfunction "LA22_N")
			(pintype "passive")
		)
		(pad "G26" smd circle
			(at -6.986 -1.905 90)
			(size 0.64 0.64)
			(layers "F.Cu" "F.Mask")
			(net 1 "GND")
			(pinfunction "GND")
			(pintype "passive")
		)
		(pad "G27" smd circle
			(at -8.257 -1.905 90)
			(size 0.64 0.64)
			(layers "F.Cu" "F.Mask")
			(net 392 "/FMC+ HSPC/FMC.IO8_P")
			(pinfunction "LA25_P")
			(pintype "passive")
		)
		(pad "G28" smd circle
			(at -9.526 -1.905 90)
			(size 0.64 0.64)
			(layers "F.Cu" "F.Mask")
			(net 388 "/FMC+ HSPC/FMC.IO8_N")
			(pinfunction "LA25_N")
			(pintype "passive")
		)
		(pad "G29" smd circle
			(at -10.795 -1.905 90)
			(size 0.64 0.64)
			(layers "F.Cu" "F.Mask")
			(net 1 "GND")
			(pinfunction "GND")
			(pintype "passive")
		)
		(pad "G30" smd circle
			(at -12.065 -1.905 90)
			(size 0.64 0.64)
			(layers "F.Cu" "F.Mask")
			(net 381 "/FMC+ HSPC/FMC.IO9_P")
			(pinfunction "LA29_P")
			(pintype "passive")
		)
		(pad "G31" smd circle
			(at -13.337 -1.905 90)
			(size 0.64 0.64)
			(layers "F.Cu" "F.Mask")
			(net 377 "/FMC+ HSPC/FMC.IO9_N")
			(pinfunction "LA29_N")
			(pintype "passive")
		)
		(pad "G32" smd circle
			(at -14.606 -1.905 90)
			(size 0.64 0.64)
			(layers "F.Cu" "F.Mask")
			(net 1 "GND")
			(pinfunction "GND")
			(pintype "passive")
		)
		(pad "G33" smd circle
			(at -15.875 -1.905 90)
			(size 0.64 0.64)
			(layers "F.Cu" "F.Mask")
			(net 373 "/FMC+ HSPC/FMC.IO0")
			(pinfunction "LA31_P")
			(pintype "passive")
		)
		(pad "G34" smd circle
			(at -17.145 -1.905 90)
			(size 0.64 0.64)
			(layers "F.Cu" "F.Mask")
			(net 191 "unconnected-(J18C-LA31_N-PadG34)")
			(pinfunction "LA31_N")
			(pintype "passive+no_connect")
		)
		(pad "G35" smd circle
			(at -18.415 -1.905 90)
			(size 0.64 0.64)
			(layers "F.Cu" "F.Mask")
			(net 1 "GND")
			(pinfunction "GND")
			(pintype "passive")
		)
		(pad "G36" smd circle
			(at -19.685 -1.905 90)
			(size 0.64 0.64)
			(layers "F.Cu" "F.Mask")
			(net 192 "unconnected-(J18C-LA33_P-PadG36)")
			(pinfunction "LA33_P")
			(pintype "passive+no_connect")
		)
		(pad "G37" smd circle
			(at -20.956 -1.905 90)
			(size 0.64 0.64)
			(layers "F.Cu" "F.Mask")
			(net 193 "unconnected-(J18C-LA33_N-PadG37)")
			(pinfunction "LA33_N")
			(pintype "passive+no_connect")
		)
		(pad "G38" smd circle
			(at -22.226 -1.905 90)
			(size 0.64 0.64)
			(layers "F.Cu" "F.Mask")
			(net 1 "GND")
			(pinfunction "GND")
			(pintype "passive")
		)
		(pad "G39" smd circle
			(at -23.497 -1.905 90)
			(size 0.64 0.64)
			(layers "F.Cu" "F.Mask")
			(net 152 "unconnected-(J18A-VADJ-PadE39)")
			(pinfunction "VADJ")
			(pintype "passive+no_connect")
		)
		(pad "G40" smd circle
			(at -24.767 -1.905 90)
			(size 0.64 0.64)
			(layers "F.Cu" "F.Mask")
			(net 1 "GND")
			(pinfunction "GND")
			(pintype "passive")
		)
		(pad "H01" smd circle
			(at 24.765 -3.176 90)
			(size 0.64 0.64)
			(layers "F.Cu" "F.Mask")
			(net 194 "Net-(J18A-VREF_A_M2C)")
			(pinfunction "VREF_A_M2C")
			(pintype "passive")
		)
		(pad "H02" smd circle
			(at 23.495 -3.176 90)
			(size 0.64 0.64)
			(layers "F.Cu" "F.Mask")
			(net 696 "/FMC+ HSPC/FMC.PRSNT_M2C")
			(pinfunction "PRSNT_M2C_L")
			(pintype "passive")
		)
		(pad "H03" smd circle
			(at 22.225 -3.176 90)
			(size 0.64 0.64)
			(layers "F.Cu" "F.Mask")
			(net 1 "GND")
			(pinfunction "GND")
			(pintype "passive")
		)
		(pad "H04" smd circle
			(at 20.954 -3.176 90)
			(size 0.64 0.64)
			(layers "F.Cu" "F.Mask")
			(net 195 "unconnected-(J18F-CLK0_M2C_P-PadH04)")
			(pinfunction "CLK0_M2C_P")
			(pintype "passive+no_connect")
		)
		(pad "H05" smd circle
			(at 19.684 -3.176 90)
			(size 0.64 0.64)
			(layers "F.Cu" "F.Mask")
			(net 196 "unconnected-(J18F-CLK0_M2C_N-PadH05)")
			(pinfunction "CLK0_M2C_N")
			(pintype "passive+no_connect")
		)
		(pad "H06" smd circle
			(at 18.414 -3.176 90)
			(size 0.64 0.64)
			(layers "F.Cu" "F.Mask")
			(net 1 "GND")
			(pinfunction "GND")
			(pintype "passive")
		)
		(pad "H07" smd circle
			(at 17.144 -3.176 90)
			(size 0.64 0.64)
			(layers "F.Cu" "F.Mask")
			(net 197 "unconnected-(J18C-LA02_P-PadH07)")
			(pinfunction "LA02_P")
			(pintype "passive+no_connect")
		)
		(pad "H08" smd circle
			(at 15.874 -3.176 90)
			(size 0.64 0.64)
			(layers "F.Cu" "F.Mask")
			(net 198 "unconnected-(J18C-LA02_N-PadH08)")
			(pinfunction "LA02_N")
			(pintype "passive+no_connect")
		)
		(pad "H09" smd circle
			(at 14.605 -3.176 90)
			(size 0.64 0.64)
			(layers "F.Cu" "F.Mask")
			(net 1 "GND")
			(pinfunction "GND")
			(pintype "passive")
		)
		(pad "H10" smd circle
			(at 13.335 -3.176 90)
			(size 0.64 0.64)
			(layers "F.Cu" "F.Mask")
			(net 199 "unconnected-(J18C-LA04_P-PadH10)")
			(pinfunction "LA04_P")
			(pintype "passive+no_connect")
		)
		(pad "H11" smd circle
			(at 12.063 -3.176 90)
			(size 0.64 0.64)
			(layers "F.Cu" "F.Mask")
			(net 200 "unconnected-(J18C-LA04_N-PadH11)")
			(pinfunction "LA04_N")
			(pintype "passive+no_connect")
		)
		(pad "H12" smd circle
			(at 10.794 -3.176 90)
			(size 0.64 0.64)
			(layers "F.Cu" "F.Mask")
			(net 1 "GND")
			(pinfunction "GND")
			(pintype "passive")
		)
		(pad "H13" smd circle
			(at 9.525 -3.176 90)
			(size 0.64 0.64)
			(layers "F.Cu" "F.Mask")
			(net 201 "unconnected-(J18C-LA07_P-PadH13)")
			(pinfunction "LA07_P")
			(pintype "passive+no_connect")
		)
		(pad "H14" smd circle
			(at 8.255 -3.176 90)
			(size 0.64 0.64)
			(layers "F.Cu" "F.Mask")
			(net 202 "unconnected-(J18C-LA07_N-PadH14)")
			(pinfunction "LA07_N")
			(pintype "passive+no_connect")
		)
		(pad "H15" smd circle
			(at 6.985 -3.176 90)
			(size 0.64 0.64)
			(layers "F.Cu" "F.Mask")
			(net 1 "GND")
			(pinfunction "GND")
			(pintype "passive")
		)
		(pad "H16" smd circle
			(at 5.714 -3.176 90)
			(size 0.64 0.64)
			(layers "F.Cu" "F.Mask")
			(net 464 "/FMC+ HSPC/FMC.IO4_P")
			(pinfunction "LA11_P")
			(pintype "passive")
		)
		(pad "H17" smd circle
			(at 4.445 -3.176 90)
			(size 0.64 0.64)
			(layers "F.Cu" "F.Mask")
			(net 460 "/FMC+ HSPC/FMC.IO4_N")
			(pinfunction "LA11_N")
			(pintype "passive")
		)
		(pad "H18" smd circle
			(at 3.173 -3.176 90)
			(size 0.64 0.64)
			(layers "F.Cu" "F.Mask")
			(net 1 "GND")
			(pinfunction "GND")
			(pintype "passive")
		)
		(pad "H19" smd circle
			(at 1.904 -3.176 90)
			(size 0.64 0.64)
			(layers "F.Cu" "F.Mask")
			(net 449 "/FMC+ HSPC/FMC.IO3_P")
			(pinfunction "LA15_P")
			(pintype "passive")
		)
		(pad "H20" smd circle
			(at 0.633 -3.176 90)
			(size 0.64 0.64)
			(layers "F.Cu" "F.Mask")
			(net 446 "/FMC+ HSPC/FMC.IO3_N")
			(pinfunction "LA15_N")
			(pintype "passive")
		)
		(pad "H21" smd circle
			(at -0.635 -3.176 90)
			(size 0.64 0.64)
			(layers "F.Cu" "F.Mask")
			(net 1 "GND")
			(pinfunction "GND")
			(pintype "passive")
		)
		(pad "H22" smd circle
			(at -1.905 -3.176 90)
			(size 0.64 0.64)
			(layers "F.Cu" "F.Mask")
			(net 413 "/FMC+ HSPC/FMC.IO19_P")
			(pinfunction "LA19_P")
			(pintype "passive")
		)
		(pad "H23" smd circle
			(at -3.176 -3.176 90)
			(size 0.64 0.64)
			(layers "F.Cu" "F.Mask")
			(net 409 "/FMC+ HSPC/FMC.IO19_N")
			(pinfunction "LA19_N")
			(pintype "passive")
		)
		(pad "H24" smd circle
			(at -4.446 -3.176 90)
			(size 0.64 0.64)
			(layers "F.Cu" "F.Mask")
			(net 1 "GND")
			(pinfunction "GND")
			(pintype "passive")
		)
		(pad "H25" smd circle
			(at -5.715 -3.176 90)
			(size 0.64 0.64)
			(layers "F.Cu" "F.Mask")
			(net 400 "/FMC+ HSPC/FMC.IO10_P")
			(pinfunction "LA21_P")
			(pintype "passive")
		)
		(pad "H26" smd circle
			(at -6.986 -3.176 90)
			(size 0.64 0.64)
			(layers "F.Cu" "F.Mask")
			(net 396 "/FMC+ HSPC/FMC.IO10_N")
			(pinfunction "LA21_N")
			(pintype "passive")
		)
		(pad "H27" smd circle
			(at -8.257 -3.176 90)
			(size 0.64 0.64)
			(layers "F.Cu" "F.Mask")
			(net 1 "GND")
			(pinfunction "GND")
			(pintype "passive")
		)
		(pad "H28" smd circle
			(at -9.526 -3.176 90)
			(size 0.64 0.64)
			(layers "F.Cu" "F.Mask")
			(net 387 "/FMC+ HSPC/FMC.IO7_P")
			(pinfunction "LA24_P")
			(pintype "passive")
		)
		(pad "H29" smd circle
			(at -10.795 -3.176 90)
			(size 0.64 0.64)
			(layers "F.Cu" "F.Mask")
			(net 384 "/FMC+ HSPC/FMC.IO7_N")
			(pinfunction "LA24_N")
			(pintype "passive")
		)
		(pad "H30" smd circle
			(at -12.065 -3.176 90)
			(size 0.64 0.64)
			(layers "F.Cu" "F.Mask")
			(net 1 "GND")
			(pinfunction "GND")
			(pintype "passive")
		)
		(pad "H31" smd circle
			(at -13.337 -3.176 90)
			(size 0.64 0.64)
			(layers "F.Cu" "F.Mask")
			(net 642 "/FMC+ HSPC/FMC.IO22_P")
			(pinfunction "LA28_P")
			(pintype "passive")
		)
		(pad "H32" smd circle
			(at -14.606 -3.176 90)
			(size 0.64 0.64)
			(layers "F.Cu" "F.Mask")
			(net 634 "/FMC+ HSPC/FMC.IO22_N")
			(pinfunction "LA28_N")
			(pintype "passive")
		)
		(pad "H33" smd circle
			(at -15.875 -3.176 90)
			(size 0.64 0.64)
			(layers "F.Cu" "F.Mask")
			(net 1 "GND")
			(pinfunction "GND")
			(pintype "passive")
		)
		(pad "H34" smd circle
			(at -17.145 -3.176 90)
			(size 0.64 0.64)
			(layers "F.Cu" "F.Mask")
			(net 203 "unconnected-(J18C-LA30_P-PadH34)")
			(pinfunction "LA30_P")
			(pintype "passive+no_connect")
		)
		(pad "H35" smd circle
			(at -18.415 -3.176 90)
			(size 0.64 0.64)
			(layers "F.Cu" "F.Mask")
			(net 204 "unconnected-(J18C-LA30_N-PadH35)")
			(pinfunction "LA30_N")
			(pintype "passive+no_connect")
		)
		(pad "H36" smd circle
			(at -19.685 -3.176 90)
			(size 0.64 0.64)
			(layers "F.Cu" "F.Mask")
			(net 1 "GND")
			(pinfunction "GND")
			(pintype "passive")
		)
		(pad "H37" smd circle
			(at -20.956 -3.176 90)
			(size 0.64 0.64)
			(layers "F.Cu" "F.Mask")
			(net 205 "unconnected-(J18C-LA32_P-PadH37)")
			(pinfunction "LA32_P")
			(pintype "passive+no_connect")
		)
		(pad "H38" smd circle
			(at -22.226 -3.176 90)
			(size 0.64 0.64)
			(layers "F.Cu" "F.Mask")
			(net 206 "unconnected-(J18C-LA32_N-PadH38)")
			(pinfunction "LA32_N")
			(pintype "passive+no_connect")
		)
		(pad "H39" smd circle
			(at -23.497 -3.176 90)
			(size 0.64 0.64)
			(layers "F.Cu" "F.Mask")
			(net 1 "GND")
			(pinfunction "GND")
			(pintype "passive")
		)
		(pad "H40" smd circle
			(at -24.767 -3.176 90)
			(size 0.64 0.64)
			(layers "F.Cu" "F.Mask")
			(net 152 "unconnected-(J18A-VADJ-PadE39)")
			(pinfunction "VADJ")
			(pintype "passive+no_connect")
		)
		(pad "J01" smd circle
			(at 24.765 -4.446 90)
			(size 0.64 0.64)
			(layers "F.Cu" "F.Mask")
			(net 1 "GND")
			(pinfunction "GND")
			(pintype "passive")
		)
		(pad "J02" smd circle
			(at 23.495 -4.446 90)
			(size 0.64 0.64)
			(layers "F.Cu" "F.Mask")
			(net 597 "/FMC+ HSPC/GTR_REFCLK3_R_P")
			(pinfunction "CLK3_BIDIR_P")
			(pintype "passive")
		)
		(pad "J03" smd circle
			(at 22.225 -4.446 90)
			(size 0.64 0.64)
			(layers "F.Cu" "F.Mask")
			(net 599 "/FMC+ HSPC/GTR_REFCLK3_R_N")
			(pinfunction "CLK3_BIDIR_N")
			(pintype "passive")
		)
		(pad "J04" smd circle
			(at 20.954 -4.446 90)
			(size 0.64 0.64)
			(layers "F.Cu" "F.Mask")
			(net 1 "GND")
			(pinfunction "GND")
			(pintype "passive")
		)
		(pad "J05" smd circle
			(at 19.684 -4.446 90)
			(size 0.64 0.64)
			(layers "F.Cu" "F.Mask")
			(net 1 "GND")
			(pinfunction "GND")
			(pintype "passive")
		)
		(pad "J06" smd circle
			(at 18.414 -4.446 90)
			(size 0.64 0.64)
			(layers "F.Cu" "F.Mask")
			(net 643 "/FMC+ HSPC/FMC.IO15_P")
			(pinfunction "HA03_P")
			(pintype "passive")
		)
		(pad "J07" smd circle
			(at 17.144 -4.446 90)
			(size 0.64 0.64)
			(layers "F.Cu" "F.Mask")
			(net 641 "/FMC+ HSPC/FMC.IO15_N")
			(pinfunction "HA03_N")
			(pintype "passive")
		)
		(pad "J08" smd circle
			(at 15.874 -4.446 90)
			(size 0.64 0.64)
			(layers "F.Cu" "F.Mask")
			(net 1 "GND")
			(pinfunction "GND")
			(pintype "passive")
		)
		(pad "J09" smd circle
			(at 14.605 -4.446 90)
			(size 0.64 0.64)
			(layers "F.Cu" "F.Mask")
			(net 254 "/FMC+ HSPC/FMC.IO18_P")
			(pinfunction "HA07_P")
			(pintype "passive")
		)
		(pad "J10" smd circle
			(at 13.335 -4.446 90)
			(size 0.64 0.64)
			(layers "F.Cu" "F.Mask")
			(net 241 "/FMC+ HSPC/FMC.IO18_N")
			(pinfunction "HA07_N")
			(pintype "passive")
		)
		(pad "J11" smd circle
			(at 12.063 -4.446 90)
			(size 0.64 0.64)
			(layers "F.Cu" "F.Mask")
			(net 1 "GND")
			(pinfunction "GND")
			(pintype "passive")
		)
		(pad "J12" smd circle
			(at 10.794 -4.446 90)
			(size 0.64 0.64)
			(layers "F.Cu" "F.Mask")
			(net 445 "/FMC+ HSPC/FMC.IO23_P")
			(pinfunction "HA11_P")
			(pintype "passive")
		)
		(pad "J13" smd circle
			(at 9.525 -4.446 90)
			(size 0.64 0.64)
			(layers "F.Cu" "F.Mask")
			(net 444 "/FMC+ HSPC/FMC.IO23_N")
			(pinfunction "HA11_N")
			(pintype "passive")
		)
		(pad "J14" smd circle
			(at 8.255 -4.446 90)
			(size 0.64 0.64)
			(layers "F.Cu" "F.Mask")
			(net 1 "GND")
			(pinfunction "GND")
			(pintype "passive")
		)
		(pad "J15" smd circle
			(at 6.985 -4.446 90)
			(size 0.64 0.64)
			(layers "F.Cu" "F.Mask")
			(net 207 "unconnected-(J18D-HA14_P-PadJ15)")
			(pinfunction "HA14_P")
			(pintype "passive+no_connect")
		)
		(pad "J16" smd circle
			(at 5.714 -4.446 90)
			(size 0.64 0.64)
			(layers "F.Cu" "F.Mask")
			(net 208 "unconnected-(J18D-HA14_N-PadJ16)")
			(pinfunction "HA14_N")
			(pintype "passive+no_connect")
		)
		(pad "J17" smd circle
			(at 4.445 -4.446 90)
			(size 0.64 0.64)
			(layers "F.Cu" "F.Mask")
			(net 1 "GND")
			(pinfunction "GND")
			(pintype "passive")
		)
		(pad "J18" smd circle
			(at 3.173 -4.446 90)
			(size 0.64 0.64)
			(layers "F.Cu" "F.Mask")
			(net 441 "/FMC+ HSPC/FMC.IO5_P")
			(pinfunction "HA18_P")
			(pintype "passive")
		)
		(pad "J19" smd circle
			(at 1.904 -4.446 90)
			(size 0.64 0.64)
			(layers "F.Cu" "F.Mask")
			(net 440 "/FMC+ HSPC/FMC.IO5_N")
			(pinfunction "HA18_N")
			(pintype "passive")
		)
		(pad "J20" smd circle
			(at 0.633 -4.446 90)
			(size 0.64 0.64)
			(layers "F.Cu" "F.Mask")
			(net 1 "GND")
			(pinfunction "GND")
			(pintype "passive")
		)
		(pad "J21" smd circle
			(at -0.635 -4.446 90)
			(size 0.64 0.64)
			(layers "F.Cu" "F.Mask")
			(net 354 "/FMC+ HSPC/FMC.IO12_P")
			(pinfunction "HA22_P")
			(pintype "passive")
		)
		(pad "J22" smd circle
			(at -1.905 -4.446 90)
			(size 0.64 0.64)
			(layers "F.Cu" "F.Mask")
			(net 353 "/FMC+ HSPC/FMC.IO12_N")
			(pinfunction "HA22_N")
			(pintype "passive")
		)
		(pad "J23" smd circle
			(at -3.176 -4.446 90)
			(size 0.64 0.64)
			(layers "F.Cu" "F.Mask")
			(net 1 "GND")
			(pinfunction "GND")
			(pintype "passive")
		)
		(pad "J24" smd circle
			(at -4.446 -4.446 90)
			(size 0.64 0.64)
			(layers "F.Cu" "F.Mask")
			(net 352 "/FMC+ HSPC/FMC.IO14_P")
			(pinfunction "HB01_P")
			(pintype "passive")
		)
		(pad "J25" smd circle
			(at -5.715 -4.446 90)
			(size 0.64 0.64)
			(layers "F.Cu" "F.Mask")
			(net 351 "/FMC+ HSPC/FMC.IO14_N")
			(pinfunction "HB01_N")
			(pintype "passive")
		)
		(pad "J26" smd circle
			(at -6.986 -4.446 90)
			(size 0.64 0.64)
			(layers "F.Cu" "F.Mask")
			(net 1 "GND")
			(pinfunction "GND")
			(pintype "passive")
		)
		(pad "J27" smd circle
			(at -8.257 -4.446 90)
			(size 0.64 0.64)
			(layers "F.Cu" "F.Mask")
			(net 350 "/FMC+ HSPC/FMC.IO24_P")
			(pinfunction "HB07_P")
			(pintype "passive")
		)
		(pad "J28" smd circle
			(at -9.526 -4.446 90)
			(size 0.64 0.64)
			(layers "F.Cu" "F.Mask")
			(net 349 "/FMC+ HSPC/FMC.IO24_N")
			(pinfunction "HB07_N")
			(pintype "passive")
		)
		(pad "J29" smd circle
			(at -10.795 -4.446 90)
			(size 0.64 0.64)
			(layers "F.Cu" "F.Mask")
			(net 1 "GND")
			(pinfunction "GND")
			(pintype "passive")
		)
		(pad "J30" smd circle
			(at -12.065 -4.446 90)
			(size 0.64 0.64)
			(layers "F.Cu" "F.Mask")
			(net 209 "unconnected-(J18E-HB11_P-PadJ30)")
			(pinfunction "HB11_P")
			(pintype "passive+no_connect")
		)
		(pad "J31" smd circle
			(at -13.337 -4.446 90)
			(size 0.64 0.64)
			(layers "F.Cu" "F.Mask")
			(net 210 "unconnected-(J18E-HB11_N-PadJ31)")
			(pinfunction "HB11_N")
			(pintype "passive+no_connect")
		)
		(pad "J32" smd circle
			(at -14.606 -4.446 90)
			(size 0.64 0.64)
			(layers "F.Cu" "F.Mask")
			(net 1 "GND")
			(pinfunction "GND")
			(pintype "passive")
		)
		(pad "J33" smd circle
			(at -15.875 -4.446 90)
			(size 0.64 0.64)
			(layers "F.Cu" "F.Mask")
			(net 211 "unconnected-(J18E-HB15_P-PadJ33)")
			(pinfunction "HB15_P")
			(pintype "passive+no_connect")
		)
		(pad "J34" smd circle
			(at -17.145 -4.446 90)
			(size 0.64 0.64)
			(layers "F.Cu" "F.Mask")
			(net 212 "unconnected-(J18E-HB15_N-PadJ34)")
			(pinfunction "HB15_N")
			(pintype "passive+no_connect")
		)
		(pad "J35" smd circle
			(at -18.415 -4.446 90)
			(size 0.64 0.64)
			(layers "F.Cu" "F.Mask")
			(net 1 "GND")
			(pinfunction "GND")
			(pintype "passive")
		)
		(pad "J36" smd circle
			(at -19.685 -4.446 90)
			(size 0.64 0.64)
			(layers "F.Cu" "F.Mask")
			(net 213 "unconnected-(J18E-HB18_P-PadJ36)")
			(pinfunction "HB18_P")
			(pintype "passive+no_connect")
		)
		(pad "J37" smd circle
			(at -20.956 -4.446 90)
			(size 0.64 0.64)
			(layers "F.Cu" "F.Mask")
			(net 214 "unconnected-(J18E-HB18_N-PadJ37)")
			(pinfunction "HB18_N")
			(pintype "passive+no_connect")
		)
		(pad "J38" smd circle
			(at -22.226 -4.446 90)
			(size 0.64 0.64)
			(layers "F.Cu" "F.Mask")
			(net 1 "GND")
			(pinfunction "GND")
			(pintype "passive")
		)
		(pad "J39" smd circle
			(at -23.497 -4.446 90)
			(size 0.64 0.64)
			(layers "F.Cu" "F.Mask")
			(net 215 "unconnected-(J18A-VIO_B_M2C-PadJ39)")
			(pinfunction "VIO_B_M2C")
			(pintype "passive+no_connect")
		)
		(pad "J40" smd circle
			(at -24.767 -4.446 90)
			(size 0.64 0.64)
			(layers "F.Cu" "F.Mask")
			(net 1 "GND")
			(pinfunction "GND")
			(pintype "passive")
		)
		(pad "K01" smd circle
			(at 24.765 -5.715 90)
			(size 0.64 0.64)
			(layers "F.Cu" "F.Mask")
			(net 216 "Net-(J18A-VREF_B_M2C)")
			(pinfunction "VREF_B_M2C")
			(pintype "passive")
		)
		(pad "K02" smd circle
			(at 23.495 -5.715 90)
			(size 0.64 0.64)
			(layers "F.Cu" "F.Mask")
			(net 1 "GND")
			(pinfunction "GND")
			(pintype "passive")
		)
		(pad "K03" smd circle
			(at 22.225 -5.715 90)
			(size 0.64 0.64)
			(layers "F.Cu" "F.Mask")
			(net 1 "GND")
			(pinfunction "GND")
			(pintype "passive")
		)
		(pad "K04" smd circle
			(at 20.954 -5.715 90)
			(size 0.64 0.64)
			(layers "F.Cu" "F.Mask")
			(net 593 "/FMC+ HSPC/GTR_REFCLK2_R_P")
			(pinfunction "CLK2_BIDIR_P")
			(pintype "passive")
		)
		(pad "K05" smd circle
			(at 19.684 -5.715 90)
			(size 0.64 0.64)
			(layers "F.Cu" "F.Mask")
			(net 595 "/FMC+ HSPC/GTR_REFCLK2_R_N")
			(pinfunction "CLK2_BIDIR_N")
			(pintype "passive")
		)
		(pad "K06" smd circle
			(at 18.414 -5.715 90)
			(size 0.64 0.64)
			(layers "F.Cu" "F.Mask")
			(net 1 "GND")
			(pinfunction "GND")
			(pintype "passive")
		)
		(pad "K07" smd circle
			(at 17.144 -5.715 90)
			(size 0.64 0.64)
			(layers "F.Cu" "F.Mask")
			(net 278 "/FMC+ HSPC/FMC.IO16_P")
			(pinfunction "HA02_P")
			(pintype "passive")
		)
		(pad "K08" smd circle
			(at 15.874 -5.715 90)
			(size 0.64 0.64)
			(layers "F.Cu" "F.Mask")
			(net 268 "/FMC+ HSPC/FMC.IO16_N")
			(pinfunction "HA02_N")
			(pintype "passive")
		)
		(pad "K09" smd circle
			(at 14.605 -5.715 90)
			(size 0.64 0.64)
			(layers "F.Cu" "F.Mask")
			(net 1 "GND")
			(pinfunction "GND")
			(pintype "passive")
		)
		(pad "K10" smd circle
			(at 13.335 -5.715 90)
			(size 0.64 0.64)
			(layers "F.Cu" "F.Mask")
			(net 239 "/FMC+ HSPC/FMC.IO21_P")
			(pinfunction "HA06_P")
			(pintype "passive")
		)
		(pad "K11" smd circle
			(at 12.063 -5.715 90)
			(size 0.64 0.64)
			(layers "F.Cu" "F.Mask")
			(net 437 "/FMC+ HSPC/FMC.IO21_N")
			(pinfunction "HA06_N")
			(pintype "passive")
		)
		(pad "K12" smd circle
			(at 10.794 -5.715 90)
			(size 0.64 0.64)
			(layers "F.Cu" "F.Mask")
			(net 1 "GND")
			(pinfunction "GND")
			(pintype "passive")
		)
		(pad "K13" smd circle
			(at 9.525 -5.715 90)
			(size 0.64 0.64)
			(layers "F.Cu" "F.Mask")
			(net 217 "unconnected-(J18D-HA10_P-PadK13)")
			(pinfunction "HA10_P")
			(pintype "passive+no_connect")
		)
		(pad "K14" smd circle
			(at 8.255 -5.715 90)
			(size 0.64 0.64)
			(layers "F.Cu" "F.Mask")
			(net 218 "unconnected-(J18D-HA10_N-PadK14)")
			(pinfunction "HA10_N")
			(pintype "passive+no_connect")
		)
		(pad "K15" smd circle
			(at 6.985 -5.715 90)
			(size 0.64 0.64)
			(layers "F.Cu" "F.Mask")
			(net 1 "GND")
			(pinfunction "GND")
			(pintype "passive")
		)
		(pad "K16" smd circle
			(at 5.714 -5.715 90)
			(size 0.64 0.64)
			(layers "F.Cu" "F.Mask")
			(net 428 "/FMC+ HSPC/FMC.IO17_P")
			(pinfunction "HA17_P_CC")
			(pintype "passive")
		)
		(pad "K17" smd circle
			(at 4.445 -5.715 90)
			(size 0.64 0.64)
			(layers "F.Cu" "F.Mask")
			(net 426 "/FMC+ HSPC/FMC.IO17_N")
			(pinfunction "HA17_N_CC")
			(pintype "passive")
		)
		(pad "K18" smd circle
			(at 3.173 -5.715 90)
			(size 0.64 0.64)
			(layers "F.Cu" "F.Mask")
			(net 1 "GND")
			(pinfunction "GND")
			(pintype "passive")
		)
		(pad "K19" smd circle
			(at 1.904 -5.715 90)
			(size 0.64 0.64)
			(layers "F.Cu" "F.Mask")
			(net 424 "/FMC+ HSPC/FMC.IO13_P")
			(pinfunction "HA21_P")
			(pintype "passive")
		)
		(pad "K20" smd circle
			(at 0.633 -5.715 90)
			(size 0.64 0.64)
			(layers "F.Cu" "F.Mask")
			(net 423 "/FMC+ HSPC/FMC.IO13_N")
			(pinfunction "HA21_N")
			(pintype "passive")
		)
		(pad "K21" smd circle
			(at -0.635 -5.715 90)
			(size 0.64 0.64)
			(layers "F.Cu" "F.Mask")
			(net 1 "GND")
			(pinfunction "GND")
			(pintype "passive")
		)
		(pad "K22" smd circle
			(at -1.905 -5.715 90)
			(size 0.64 0.64)
			(layers "F.Cu" "F.Mask")
			(net 340 "/FMC+ HSPC/FMC.IO11_P")
			(pinfunction "HA23_P")
			(pintype "passive")
		)
		(pad "K23" smd circle
			(at -3.176 -5.715 90)
			(size 0.64 0.64)
			(layers "F.Cu" "F.Mask")
			(net 339 "/FMC+ HSPC/FMC.IO11_N")
			(pinfunction "HA23_N")
			(pintype "passive")
		)
		(pad "K24" smd circle
			(at -4.446 -5.715 90)
			(size 0.64 0.64)
			(layers "F.Cu" "F.Mask")
			(net 1 "GND")
			(pinfunction "GND")
			(pintype "passive")
		)
		(pad "K25" smd circle
			(at -5.715 -5.715 90)
			(size 0.64 0.64)
			(layers "F.Cu" "F.Mask")
			(net 337 "/FMC+ HSPC/FMC.IO20_P")
			(pinfunction "HB00_P_CC")
			(pintype "passive")
		)
		(pad "K26" smd circle
			(at -6.986 -5.715 90)
			(size 0.64 0.64)
			(layers "F.Cu" "F.Mask")
			(net 335 "/FMC+ HSPC/FMC.IO20_N")
			(pinfunction "HB00_N_CC")
			(pintype "passive")
		)
		(pad "K27" smd circle
			(at -8.257 -5.715 90)
			(size 0.64 0.64)
			(layers "F.Cu" "F.Mask")
			(net 1 "GND")
			(pinfunction "GND")
			(pintype "passive")
		)
		(pad "K28" smd circle
			(at -9.526 -5.715 90)
			(size 0.64 0.64)
			(layers "F.Cu" "F.Mask")
			(net 334 "/FMC+ HSPC/FMC.IO25")
			(pinfunction "HB06_P_CC")
			(pintype "passive")
		)
		(pad "K29" smd circle
			(at -10.795 -5.715 90)
			(size 0.64 0.64)
			(layers "F.Cu" "F.Mask")
			(net 219 "unconnected-(J18E-HB06_N_CC-PadK29)")
			(pinfunction "HB06_N_CC")
			(pintype "passive+no_connect")
		)
		(pad "K30" smd circle
			(at -12.065 -5.715 90)
			(size 0.64 0.64)
			(layers "F.Cu" "F.Mask")
			(net 1 "GND")
			(pinfunction "GND")
			(pintype "passive")
		)
		(pad "K31" smd circle
			(at -13.337 -5.715 90)
			(size 0.64 0.64)
			(layers "F.Cu" "F.Mask")
			(net 221 "unconnected-(J18E-HB10_P-PadK31)")
			(pinfunction "HB10_P")
			(pintype "passive+no_connect")
		)
		(pad "K32" smd circle
			(at -14.606 -5.715 90)
			(size 0.64 0.64)
			(layers "F.Cu" "F.Mask")
			(net 222 "unconnected-(J18E-HB10_N-PadK32)")
			(pinfunction "HB10_N")
			(pintype "passive+no_connect")
		)
		(pad "K33" smd circle
			(at -15.875 -5.715 90)
			(size 0.64 0.64)
			(layers "F.Cu" "F.Mask")
			(net 1 "GND")
			(pinfunction "GND")
			(pintype "passive")
		)
		(pad "K34" smd circle
			(at -17.145 -5.715 90)
			(size 0.64 0.64)
			(layers "F.Cu" "F.Mask")
			(net 223 "unconnected-(J18E-HB14_P-PadK34)")
			(pinfunction "HB14_P")
			(pintype "passive+no_connect")
		)
		(pad "K35" smd circle
			(at -18.415 -5.715 90)
			(size 0.64 0.64)
			(layers "F.Cu" "F.Mask")
			(net 224 "unconnected-(J18E-HB14_N-PadK35)")
			(pinfunction "HB14_N")
			(pintype "passive+no_connect")
		)
		(pad "K36" smd circle
			(at -19.685 -5.715 90)
			(size 0.64 0.64)
			(layers "F.Cu" "F.Mask")
			(net 1 "GND")
			(pinfunction "GND")
			(pintype "passive")
		)
		(pad "K37" smd circle
			(at -20.956 -5.715 90)
			(size 0.64 0.64)
			(layers "F.Cu" "F.Mask")
			(net 225 "unconnected-(J18E-HB17_P_CC-PadK37)")
			(pinfunction "HB17_P_CC")
			(pintype "passive+no_connect")
		)
		(pad "K38" smd circle
			(at -22.226 -5.715 90)
			(size 0.64 0.64)
			(layers "F.Cu" "F.Mask")
			(net 226 "unconnected-(J18E-HB17_N_CC-PadK38)")
			(pinfunction "HB17_N_CC")
			(pintype "passive+no_connect")
		)
		(pad "K39" smd circle
			(at -23.497 -5.715 90)
			(size 0.64 0.64)
			(layers "F.Cu" "F.Mask")
			(net 1 "GND")
			(pinfunction "GND")
			(pintype "passive")
		)
		(pad "K40" smd circle
			(at -24.767 -5.715 90)
			(size 0.64 0.64)
			(layers "F.Cu" "F.Mask")
			(net 215 "unconnected-(J18A-VIO_B_M2C-PadJ39)")
			(pinfunction "VIO_B_M2C")
			(pintype "passive+no_connect")
		)
		(pad "L01" smd circle
			(at 24.765 -6.986 90)
			(size 0.64 0.64)
			(layers "F.Cu" "F.Mask")
			(net 227 "unconnected-(J18A-RES1-PadL01)")
			(pinfunction "RES1")
			(pintype "no_connect")
		)
		(pad "L02" smd circle
			(at 23.495 -6.986 90)
			(size 0.64 0.64)
			(layers "F.Cu" "F.Mask")
			(net 1 "GND")
			(pinfunction "GND")
			(pintype "passive")
		)
		(pad "L03" smd circle
			(at 22.225 -6.986 90)
			(size 0.64 0.64)
			(layers "F.Cu" "F.Mask")
			(net 1 "GND")
			(pinfunction "GND")
			(pintype "passive")
		)
		(pad "L04" smd circle
			(at 20.954 -6.986 90)
			(size 0.64 0.64)
			(layers "F.Cu" "F.Mask")
			(net 228 "unconnected-(J18G-GBTCLK4_M2C_P-PadL04)")
			(pinfunction "GBTCLK4_M2C_P")
			(pintype "passive+no_connect")
		)
		(pad "L05" smd circle
			(at 19.684 -6.986 90)
			(size 0.64 0.64)
			(layers "F.Cu" "F.Mask")
			(net 229 "unconnected-(J18G-GBTCLK4_M2C_N-PadL05)")
			(pinfunction "GBTCLK4_M2C_N")
			(pintype "passive+no_connect")
		)
		(pad "L06" smd circle
			(at 18.414 -6.986 90)
			(size 0.64 0.64)
			(layers "F.Cu" "F.Mask")
			(net 1 "GND")
			(pinfunction "GND")
			(pintype "passive")
		)
		(pad "L07" smd circle
			(at 17.144 -6.986 90)
			(size 0.64 0.64)
			(layers "F.Cu" "F.Mask")
			(net 1 "GND")
			(pinfunction "GND")
			(pintype "passive")
		)
		(pad "L08" smd circle
			(at 15.874 -6.986 90)
			(size 0.64 0.64)
			(layers "F.Cu" "F.Mask")
			(net 230 "unconnected-(J18G-GBTCLK3_M2C_P-PadL08)")
			(pinfunction "GBTCLK3_M2C_P")
			(pintype "passive+no_connect")
		)
		(pad "L09" smd circle
			(at 14.605 -6.986 90)
			(size 0.64 0.64)
			(layers "F.Cu" "F.Mask")
			(net 231 "unconnected-(J18G-GBTCLK3_M2C_N-PadL09)")
			(pinfunction "GBTCLK3_M2C_N")
			(pintype "passive+no_connect")
		)
		(pad "L10" smd circle
			(at 13.335 -6.986 90)
			(size 0.64 0.64)
			(layers "F.Cu" "F.Mask")
			(net 1 "GND")
			(pinfunction "GND")
			(pintype "passive")
		)
		(pad "L11" smd circle
			(at 12.063 -6.986 90)
			(size 0.64 0.64)
			(layers "F.Cu" "F.Mask")
			(net 1 "GND")
			(pinfunction "GND")
			(pintype "passive")
		)
		(pad "L12" smd circle
			(at 10.794 -6.986 90)
			(size 0.64 0.64)
			(layers "F.Cu" "F.Mask")
			(net 232 "unconnected-(J18G-GBTCLK2_M2C_P-PadL12)")
			(pinfunction "GBTCLK2_M2C_P")
			(pintype "passive+no_connect")
		)
		(pad "L13" smd circle
			(at 9.525 -6.986 90)
			(size 0.64 0.64)
			(layers "F.Cu" "F.Mask")
			(net 233 "unconnected-(J18G-GBTCLK2_M2C_N-PadL13)")
			(pinfunction "GBTCLK2_M2C_N")
			(pintype "passive+no_connect")
		)
		(pad "L14" smd circle
			(at 8.255 -6.986 90)
			(size 0.64 0.64)
			(layers "F.Cu" "F.Mask")
			(net 1 "GND")
			(pinfunction "GND")
			(pintype "passive")
		)
		(pad "L15" smd circle
			(at 6.985 -6.986 90)
			(size 0.64 0.64)
			(layers "F.Cu" "F.Mask")
			(net 1 "GND")
			(pinfunction "GND")
			(pintype "passive")
		)
		(pad "L16" smd circle
			(at 5.714 -6.986 90)
			(size 0.64 0.64)
			(layers "F.Cu" "F.Mask")
			(net 234 "unconnected-(J18G-SYNC_C2M_P-PadL16)")
			(pinfunction "SYNC_C2M_P")
			(pintype "passive+no_connect")
		)
		(pad "L17" smd circle
			(at 4.445 -6.986 90)
			(size 0.64 0.64)
			(layers "F.Cu" "F.Mask")
			(net 235 "unconnected-(J18G-SYNC_C2M_N-PadL17)")
			(pinfunction "SYNC_C2M_N")
			(pintype "passive+no_connect")
		)
		(pad "L18" smd circle
			(at 3.173 -6.986 90)
			(size 0.64 0.64)
			(layers "F.Cu" "F.Mask")
			(net 1 "GND")
			(pinfunction "GND")
			(pintype "passive")
		)
		(pad "L19" smd circle
			(at 1.904 -6.986 90)
			(size 0.64 0.64)
			(layers "F.Cu" "F.Mask")
			(net 1 "GND")
			(pinfunction "GND")
			(pintype "passive")
		)
		(pad "L20" smd circle
			(at 0.633 -6.986 90)
			(size 0.64 0.64)
			(layers "F.Cu" "F.Mask")
			(net 236 "unconnected-(J18G-REFCLK_C2M_P-PadL20)")
			(pinfunction "REFCLK_C2M_P")
			(pintype "passive+no_connect")
		)
		(pad "L21" smd circle
			(at -0.635 -6.986 90)
			(size 0.64 0.64)
			(layers "F.Cu" "F.Mask")
			(net 237 "unconnected-(J18G-REFCLK_C2M_N-PadL21)")
			(pinfunction "REFCLK_C2M_N")
			(pintype "passive+no_connect")
		)
		(pad "L22" smd circle
			(at -1.905 -6.986 90)
			(size 0.64 0.64)
			(layers "F.Cu" "F.Mask")
			(net 1 "GND")
			(pinfunction "GND")
			(pintype "passive")
		)
		(pad "L23" smd circle
			(at -3.176 -6.986 90)
			(size 0.64 0.64)
			(layers "F.Cu" "F.Mask")
			(net 1 "GND")
			(pinfunction "GND")
			(pintype "passive")
		)
		(pad "L24" smd circle
			(at -4.446 -6.986 90)
			(size 0.64 0.64)
			(layers "F.Cu" "F.Mask")
			(net 238 "unconnected-(J18G-REFCLK_M2C_P-PadL24)")
			(pinfunction "REFCLK_M2C_P")
			(pintype "passive+no_connect")
		)
		(pad "L25" smd circle
			(at -5.715 -6.986 90)
			(size 0.64 0.64)
			(layers "F.Cu" "F.Mask")
			(net 240 "unconnected-(J18G-REFCLK_M2C_N-PadL25)")
			(pinfunction "REFCLK_M2C_N")
			(pintype "passive+no_connect")
		)
		(pad "L26" smd circle
			(at -6.986 -6.986 90)
			(size 0.64 0.64)
			(layers "F.Cu" "F.Mask")
			(net 1 "GND")
			(pinfunction "GND")
			(pintype "passive")
		)
		(pad "L27" smd circle
			(at -8.257 -6.986 90)
			(size 0.64 0.64)
			(layers "F.Cu" "F.Mask")
			(net 1 "GND")
			(pinfunction "GND")
			(pintype "passive")
		)
		(pad "L28" smd circle
			(at -9.526 -6.986 90)
			(size 0.64 0.64)
			(layers "F.Cu" "F.Mask")
			(net 242 "unconnected-(J18G-SYNC_M2C_P-PadL28)")
			(pinfunction "SYNC_M2C_P")
			(pintype "passive+no_connect")
		)
		(pad "L29" smd circle
			(at -10.795 -6.986 90)
			(size 0.64 0.64)
			(layers "F.Cu" "F.Mask")
			(net 243 "unconnected-(J18G-SYNC_M2C_N-PadL29)")
			(pinfunction "SYNC_M2C_N")
			(pintype "passive+no_connect")
		)
		(pad "L30" smd circle
			(at -12.065 -6.986 90)
			(size 0.64 0.64)
			(layers "F.Cu" "F.Mask")
			(net 1 "GND")
			(pinfunction "GND")
			(pintype "passive")
		)
		(pad "L31" smd circle
			(at -13.337 -6.986 90)
			(size 0.64 0.64)
			(layers "F.Cu" "F.Mask")
			(net 1 "GND")
			(pinfunction "GND")
			(pintype "passive")
		)
		(pad "L32" smd circle
			(at -14.606 -6.986 90)
			(size 0.64 0.64)
			(layers "F.Cu" "F.Mask")
			(net 244 "unconnected-(J18A-RES2-PadL32)")
			(pinfunction "RES2")
			(pintype "no_connect")
		)
		(pad "L33" smd circle
			(at -15.875 -6.986 90)
			(size 0.64 0.64)
			(layers "F.Cu" "F.Mask")
			(net 245 "unconnected-(J18A-RES3-PadL33)")
			(pinfunction "RES3")
			(pintype "no_connect")
		)
		(pad "L34" smd circle
			(at -17.145 -6.986 90)
			(size 0.64 0.64)
			(layers "F.Cu" "F.Mask")
			(net 1 "GND")
			(pinfunction "GND")
			(pintype "passive")
		)
		(pad "L35" smd circle
			(at -18.415 -6.986 90)
			(size 0.64 0.64)
			(layers "F.Cu" "F.Mask")
			(net 1 "GND")
			(pinfunction "GND")
			(pintype "passive")
		)
		(pad "L36" smd circle
			(at -19.685 -6.986 90)
			(size 0.64 0.64)
			(layers "F.Cu" "F.Mask")
			(net 59 "12P0V")
			(pinfunction "12P0V")
			(pintype "passive")
		)
		(pad "L37" smd circle
			(at -20.956 -6.986 90)
			(size 0.64 0.64)
			(layers "F.Cu" "F.Mask")
			(net 59 "12P0V")
			(pinfunction "12P0V")
			(pintype "passive")
		)
		(pad "L38" smd circle
			(at -22.226 -6.986 90)
			(size 0.64 0.64)
			(layers "F.Cu" "F.Mask")
			(net 1 "GND")
			(pinfunction "GND")
			(pintype "passive")
		)
		(pad "L39" smd circle
			(at -23.497 -6.986 90)
			(size 0.64 0.64)
			(layers "F.Cu" "F.Mask")
			(net 1 "GND")
			(pinfunction "GND")
			(pintype "passive")
		)
		(pad "L40" smd circle
			(at -24.767 -6.986 90)
			(size 0.64 0.64)
			(layers "F.Cu" "F.Mask")
			(net 59 "12P0V")
			(pinfunction "12P0V")
			(pintype "passive")
		)
		(pad "M01" smd circle
			(at 24.765 -8.257 90)
			(size 0.64 0.64)
			(layers "F.Cu" "F.Mask")
			(net 1 "GND")
			(pinfunction "GND")
			(pintype "passive")
		)
		(pad "M02" smd circle
			(at 23.495 -8.257 90)
			(size 0.64 0.64)
			(layers "F.Cu" "F.Mask")
			(net 247 "unconnected-(J18H-DP23_M2C_P-PadM02)")
			(pinfunction "DP23_M2C_P")
			(pintype "passive+no_connect")
		)
		(pad "M03" smd circle
			(at 22.225 -8.257 90)
			(size 0.64 0.64)
			(layers "F.Cu" "F.Mask")
			(net 248 "unconnected-(J18H-DP23_M2C_N-PadM03)")
			(pinfunction "DP23_M2C_N")
			(pintype "passive+no_connect")
		)
		(pad "M04" smd circle
			(at 20.954 -8.257 90)
			(size 0.64 0.64)
			(layers "F.Cu" "F.Mask")
			(net 1 "GND")
			(pinfunction "GND")
			(pintype "passive")
		)
		(pad "M05" smd circle
			(at 19.684 -8.257 90)
			(size 0.64 0.64)
			(layers "F.Cu" "F.Mask")
			(net 1 "GND")
			(pinfunction "GND")
			(pintype "passive")
		)
		(pad "M06" smd circle
			(at 18.414 -8.257 90)
			(size 0.64 0.64)
			(layers "F.Cu" "F.Mask")
			(net 251 "unconnected-(J18H-DP22_M2C_P-PadM06)")
			(pinfunction "DP22_M2C_P")
			(pintype "passive+no_connect")
		)
		(pad "M07" smd circle
			(at 17.144 -8.257 90)
			(size 0.64 0.64)
			(layers "F.Cu" "F.Mask")
			(net 252 "unconnected-(J18H-DP22_M2C_N-PadM07)")
			(pinfunction "DP22_M2C_N")
			(pintype "passive+no_connect")
		)
		(pad "M08" smd circle
			(at 15.874 -8.257 90)
			(size 0.64 0.64)
			(layers "F.Cu" "F.Mask")
			(net 1 "GND")
			(pinfunction "GND")
			(pintype "passive")
		)
		(pad "M09" smd circle
			(at 14.605 -8.257 90)
			(size 0.64 0.64)
			(layers "F.Cu" "F.Mask")
			(net 1 "GND")
			(pinfunction "GND")
			(pintype "passive")
		)
		(pad "M10" smd circle
			(at 13.335 -8.257 90)
			(size 0.64 0.64)
			(layers "F.Cu" "F.Mask")
			(net 253 "unconnected-(J18H-DP21_M2C_P-PadM10)")
			(pinfunction "DP21_M2C_P")
			(pintype "passive+no_connect")
		)
		(pad "M11" smd circle
			(at 12.063 -8.257 90)
			(size 0.64 0.64)
			(layers "F.Cu" "F.Mask")
			(net 255 "unconnected-(J18H-DP21_M2C_N-PadM11)")
			(pinfunction "DP21_M2C_N")
			(pintype "passive+no_connect")
		)
		(pad "M12" smd circle
			(at 10.794 -8.257 90)
			(size 0.64 0.64)
			(layers "F.Cu" "F.Mask")
			(net 1 "GND")
			(pinfunction "GND")
			(pintype "passive")
		)
		(pad "M13" smd circle
			(at 9.525 -8.257 90)
			(size 0.64 0.64)
			(layers "F.Cu" "F.Mask")
			(net 1 "GND")
			(pinfunction "GND")
			(pintype "passive")
		)
		(pad "M14" smd circle
			(at 8.255 -8.257 90)
			(size 0.64 0.64)
			(layers "F.Cu" "F.Mask")
			(net 256 "unconnected-(J18H-DP20_M2C_P-PadM14)")
			(pinfunction "DP20_M2C_P")
			(pintype "passive+no_connect")
		)
		(pad "M15" smd circle
			(at 6.985 -8.257 90)
			(size 0.64 0.64)
			(layers "F.Cu" "F.Mask")
			(net 258 "unconnected-(J18H-DP20_M2C_N-PadM15)")
			(pinfunction "DP20_M2C_N")
			(pintype "passive+no_connect")
		)
		(pad "M16" smd circle
			(at 5.714 -8.257 90)
			(size 0.64 0.64)
			(layers "F.Cu" "F.Mask")
			(net 1 "GND")
			(pinfunction "GND")
			(pintype "passive")
		)
		(pad "M17" smd circle
			(at 4.445 -8.257 90)
			(size 0.64 0.64)
			(layers "F.Cu" "F.Mask")
			(net 1 "GND")
			(pinfunction "GND")
			(pintype "passive")
		)
		(pad "M18" smd circle
			(at 3.173 -8.257 90)
			(size 0.64 0.64)
			(layers "F.Cu" "F.Mask")
			(net 259 "unconnected-(J18H-DP14_C2M_P-PadM18)")
			(pinfunction "DP14_C2M_P")
			(pintype "passive+no_connect")
		)
		(pad "M19" smd circle
			(at 1.904 -8.257 90)
			(size 0.64 0.64)
			(layers "F.Cu" "F.Mask")
			(net 261 "unconnected-(J18H-DP14_C2M_N-PadM19)")
			(pinfunction "DP14_C2M_N")
			(pintype "passive+no_connect")
		)
		(pad "M20" smd circle
			(at 0.633 -8.257 90)
			(size 0.64 0.64)
			(layers "F.Cu" "F.Mask")
			(net 1 "GND")
			(pinfunction "GND")
			(pintype "passive")
		)
		(pad "M21" smd circle
			(at -0.635 -8.257 90)
			(size 0.64 0.64)
			(layers "F.Cu" "F.Mask")
			(net 1 "GND")
			(pinfunction "GND")
			(pintype "passive")
		)
		(pad "M22" smd circle
			(at -1.905 -8.257 90)
			(size 0.64 0.64)
			(layers "F.Cu" "F.Mask")
			(net 262 "unconnected-(J18H-DP15_C2M_P-PadM22)")
			(pinfunction "DP15_C2M_P")
			(pintype "passive+no_connect")
		)
		(pad "M23" smd circle
			(at -3.176 -8.257 90)
			(size 0.64 0.64)
			(layers "F.Cu" "F.Mask")
			(net 263 "unconnected-(J18H-DP15_C2M_N-PadM23)")
			(pinfunction "DP15_C2M_N")
			(pintype "passive+no_connect")
		)
		(pad "M24" smd circle
			(at -4.446 -8.257 90)
			(size 0.64 0.64)
			(layers "F.Cu" "F.Mask")
			(net 1 "GND")
			(pinfunction "GND")
			(pintype "passive")
		)
		(pad "M25" smd circle
			(at -5.715 -8.257 90)
			(size 0.64 0.64)
			(layers "F.Cu" "F.Mask")
			(net 1 "GND")
			(pinfunction "GND")
			(pintype "passive")
		)
		(pad "M26" smd circle
			(at -6.986 -8.257 90)
			(size 0.64 0.64)
			(layers "F.Cu" "F.Mask")
			(net 264 "unconnected-(J18H-DP16_C2M_P-PadM26)")
			(pinfunction "DP16_C2M_P")
			(pintype "passive+no_connect")
		)
		(pad "M27" smd circle
			(at -8.257 -8.257 90)
			(size 0.64 0.64)
			(layers "F.Cu" "F.Mask")
			(net 266 "unconnected-(J18H-DP16_C2M_N-PadM27)")
			(pinfunction "DP16_C2M_N")
			(pintype "passive+no_connect")
		)
		(pad "M28" smd circle
			(at -9.526 -8.257 90)
			(size 0.64 0.64)
			(layers "F.Cu" "F.Mask")
			(net 1 "GND")
			(pinfunction "GND")
			(pintype "passive")
		)
		(pad "M29" smd circle
			(at -10.795 -8.257 90)
			(size 0.64 0.64)
			(layers "F.Cu" "F.Mask")
			(net 1 "GND")
			(pinfunction "GND")
			(pintype "passive")
		)
		(pad "M30" smd circle
			(at -12.065 -8.257 90)
			(size 0.64 0.64)
			(layers "F.Cu" "F.Mask")
			(net 269 "unconnected-(J18H-DP17_C2M_P-PadM30)")
			(pinfunction "DP17_C2M_P")
			(pintype "passive+no_connect")
		)
		(pad "M31" smd circle
			(at -13.337 -8.257 90)
			(size 0.64 0.64)
			(layers "F.Cu" "F.Mask")
			(net 270 "unconnected-(J18H-DP17_C2M_N-PadM31)")
			(pinfunction "DP17_C2M_N")
			(pintype "passive+no_connect")
		)
		(pad "M32" smd circle
			(at -14.606 -8.257 90)
			(size 0.64 0.64)
			(layers "F.Cu" "F.Mask")
			(net 1 "GND")
			(pinfunction "GND")
			(pintype "passive")
		)
		(pad "M33" smd circle
			(at -15.875 -8.257 90)
			(size 0.64 0.64)
			(layers "F.Cu" "F.Mask")
			(net 1 "GND")
			(pinfunction "GND")
			(pintype "passive")
		)
		(pad "M34" smd circle
			(at -17.145 -8.257 90)
			(size 0.64 0.64)
			(layers "F.Cu" "F.Mask")
			(net 271 "unconnected-(J18H-DP18_C2M_P-PadM34)")
			(pinfunction "DP18_C2M_P")
			(pintype "passive+no_connect")
		)
		(pad "M35" smd circle
			(at -18.415 -8.257 90)
			(size 0.64 0.64)
			(layers "F.Cu" "F.Mask")
			(net 272 "unconnected-(J18H-DP18_C2M_N-PadM35)")
			(pinfunction "DP18_C2M_N")
			(pintype "passive+no_connect")
		)
		(pad "M36" smd circle
			(at -19.685 -8.257 90)
			(size 0.64 0.64)
			(layers "F.Cu" "F.Mask")
			(net 1 "GND")
			(pinfunction "GND")
			(pintype "passive")
		)
		(pad "M37" smd circle
			(at -20.956 -8.257 90)
			(size 0.64 0.64)
			(layers "F.Cu" "F.Mask")
			(net 1 "GND")
			(pinfunction "GND")
			(pintype "passive")
		)
		(pad "M38" smd circle
			(at -22.226 -8.257 90)
			(size 0.64 0.64)
			(layers "F.Cu" "F.Mask")
			(net 273 "unconnected-(J18H-DP19_C2M_P-PadM38)")
			(pinfunction "DP19_C2M_P")
			(pintype "passive+no_connect")
		)
		(pad "M39" smd circle
			(at -23.497 -8.257 90)
			(size 0.64 0.64)
			(layers "F.Cu" "F.Mask")
			(net 274 "unconnected-(J18H-DP19_C2M_N-PadM39)")
			(pinfunction "DP19_C2M_N")
			(pintype "passive+no_connect")
		)
		(pad "M40" smd circle
			(at -24.767 -8.257 90)
			(size 0.64 0.64)
			(layers "F.Cu" "F.Mask")
			(net 1 "GND")
			(pinfunction "GND")
			(pintype "passive")
		)
		(pad "Y01" smd circle
			(at 24.765 8.255 90)
			(size 0.64 0.64)
			(layers "F.Cu" "F.Mask")
			(net 1 "GND")
			(pinfunction "GND")
			(pintype "passive")
		)
		(pad "Y02" smd circle
			(at 23.495 8.255 90)
			(size 0.64 0.64)
			(layers "F.Cu" "F.Mask")
			(net 275 "unconnected-(J18H-DP23_C2M_P-PadY02)")
			(pinfunction "DP23_C2M_P")
			(pintype "passive+no_connect")
		)
		(pad "Y03" smd circle
			(at 22.225 8.255 90)
			(size 0.64 0.64)
			(layers "F.Cu" "F.Mask")
			(net 277 "unconnected-(J18H-DP23_C2M_N-PadY03)")
			(pinfunction "DP23_C2M_N")
			(pintype "passive+no_connect")
		)
		(pad "Y04" smd circle
			(at 20.954 8.255 90)
			(size 0.64 0.64)
			(layers "F.Cu" "F.Mask")
			(net 1 "GND")
			(pinfunction "GND")
			(pintype "passive")
		)
		(pad "Y05" smd circle
			(at 19.684 8.255 90)
			(size 0.64 0.64)
			(layers "F.Cu" "F.Mask")
			(net 1 "GND")
			(pinfunction "GND")
			(pintype "passive")
		)
		(pad "Y06" smd circle
			(at 18.414 8.255 90)
			(size 0.64 0.64)
			(layers "F.Cu" "F.Mask")
			(net 280 "unconnected-(J18H-DP21_C2M_P-PadY06)")
			(pinfunction "DP21_C2M_P")
			(pintype "passive+no_connect")
		)
		(pad "Y07" smd circle
			(at 17.144 8.255 90)
			(size 0.64 0.64)
			(layers "F.Cu" "F.Mask")
			(net 281 "unconnected-(J18H-DP21_C2M_N-PadY07)")
			(pinfunction "DP21_C2M_N")
			(pintype "passive+no_connect")
		)
		(pad "Y08" smd circle
			(at 15.874 8.255 90)
			(size 0.64 0.64)
			(layers "F.Cu" "F.Mask")
			(net 1 "GND")
			(pinfunction "GND")
			(pintype "passive")
		)
		(pad "Y09" smd circle
			(at 14.605 8.255 90)
			(size 0.64 0.64)
			(layers "F.Cu" "F.Mask")
			(net 1 "GND")
			(pinfunction "GND")
			(pintype "passive")
		)
		(pad "Y10" smd circle
			(at 13.335 8.255 90)
			(size 0.64 0.64)
			(layers "F.Cu" "F.Mask")
			(net 284 "unconnected-(J18H-DP10_M2C_P-PadY10)")
			(pinfunction "DP10_M2C_P")
			(pintype "passive+no_connect")
		)
		(pad "Y11" smd circle
			(at 12.063 8.255 90)
			(size 0.64 0.64)
			(layers "F.Cu" "F.Mask")
			(net 285 "unconnected-(J18H-DP10_M2C_N-PadY11)")
			(pinfunction "DP10_M2C_N")
			(pintype "passive+no_connect")
		)
		(pad "Y12" smd circle
			(at 10.794 8.255 90)
			(size 0.64 0.64)
			(layers "F.Cu" "F.Mask")
			(net 1 "GND")
			(pinfunction "GND")
			(pintype "passive")
		)
		(pad "Y13" smd circle
			(at 9.525 8.255 90)
			(size 0.64 0.64)
			(layers "F.Cu" "F.Mask")
			(net 1 "GND")
			(pinfunction "GND")
			(pintype "passive")
		)
		(pad "Y14" smd circle
			(at 8.255 8.255 90)
			(size 0.64 0.64)
			(layers "F.Cu" "F.Mask")
			(net 286 "unconnected-(J18H-DP12_M2C_P-PadY14)")
			(pinfunction "DP12_M2C_P")
			(pintype "passive+no_connect")
		)
		(pad "Y15" smd circle
			(at 6.985 8.255 90)
			(size 0.64 0.64)
			(layers "F.Cu" "F.Mask")
			(net 289 "unconnected-(J18H-DP12_M2C_N-PadY15)")
			(pinfunction "DP12_M2C_N")
			(pintype "passive+no_connect")
		)
		(pad "Y16" smd circle
			(at 5.714 8.255 90)
			(size 0.64 0.64)
			(layers "F.Cu" "F.Mask")
			(net 1 "GND")
			(pinfunction "GND")
			(pintype "passive")
		)
		(pad "Y17" smd circle
			(at 4.445 8.255 90)
			(size 0.64 0.64)
			(layers "F.Cu" "F.Mask")
			(net 1 "GND")
			(pinfunction "GND")
			(pintype "passive")
		)
		(pad "Y18" smd circle
			(at 3.173 8.255 90)
			(size 0.64 0.64)
			(layers "F.Cu" "F.Mask")
			(net 290 "unconnected-(J18H-DP14_M2C_P-PadY18)")
			(pinfunction "DP14_M2C_P")
			(pintype "passive+no_connect")
		)
		(pad "Y19" smd circle
			(at 1.904 8.255 90)
			(size 0.64 0.64)
			(layers "F.Cu" "F.Mask")
			(net 291 "unconnected-(J18H-DP14_M2C_N-PadY19)")
			(pinfunction "DP14_M2C_N")
			(pintype "passive+no_connect")
		)
		(pad "Y20" smd circle
			(at 0.633 8.255 90)
			(size 0.64 0.64)
			(layers "F.Cu" "F.Mask")
			(net 1 "GND")
			(pinfunction "GND")
			(pintype "passive")
		)
		(pad "Y21" smd circle
			(at -0.635 8.255 90)
			(size 0.64 0.64)
			(layers "F.Cu" "F.Mask")
			(net 1 "GND")
			(pinfunction "GND")
			(pintype "passive")
		)
		(pad "Y22" smd circle
			(at -1.905 8.255 90)
			(size 0.64 0.64)
			(layers "F.Cu" "F.Mask")
			(net 292 "unconnected-(J18H-DP15_M2C_P-PadY22)")
			(pinfunction "DP15_M2C_P")
			(pintype "passive+no_connect")
		)
		(pad "Y23" smd circle
			(at -3.176 8.255 90)
			(size 0.64 0.64)
			(layers "F.Cu" "F.Mask")
			(net 293 "unconnected-(J18H-DP15_M2C_N-PadY23)")
			(pinfunction "DP15_M2C_N")
			(pintype "passive+no_connect")
		)
		(pad "Y24" smd circle
			(at -4.446 8.255 90)
			(size 0.64 0.64)
			(layers "F.Cu" "F.Mask")
			(net 1 "GND")
			(pinfunction "GND")
			(pintype "passive")
		)
		(pad "Y25" smd circle
			(at -5.715 8.255 90)
			(size 0.64 0.64)
			(layers "F.Cu" "F.Mask")
			(net 1 "GND")
			(pinfunction "GND")
			(pintype "passive")
		)
		(pad "Y26" smd circle
			(at -6.986 8.255 90)
			(size 0.64 0.64)
			(layers "F.Cu" "F.Mask")
			(net 294 "unconnected-(J18H-DP11_C2M_P-PadY26)")
			(pinfunction "DP11_C2M_P")
			(pintype "passive+no_connect")
		)
		(pad "Y27" smd circle
			(at -8.257 8.255 90)
			(size 0.64 0.64)
			(layers "F.Cu" "F.Mask")
			(net 295 "unconnected-(J18H-DP11_C2M_N-PadY27)")
			(pinfunction "DP11_C2M_N")
			(pintype "passive+no_connect")
		)
		(pad "Y28" smd circle
			(at -9.526 8.255 90)
			(size 0.64 0.64)
			(layers "F.Cu" "F.Mask")
			(net 1 "GND")
			(pinfunction "GND")
			(pintype "passive")
		)
		(pad "Y29" smd circle
			(at -10.795 8.255 90)
			(size 0.64 0.64)
			(layers "F.Cu" "F.Mask")
			(net 1 "GND")
			(pinfunction "GND")
			(pintype "passive")
		)
		(pad "Y30" smd circle
			(at -12.065 8.255 90)
			(size 0.64 0.64)
			(layers "F.Cu" "F.Mask")
			(net 296 "unconnected-(J18H-DP13_C2M_P-PadY30)")
			(pinfunction "DP13_C2M_P")
			(pintype "passive+no_connect")
		)
		(pad "Y31" smd circle
			(at -13.337 8.255 90)
			(size 0.64 0.64)
			(layers "F.Cu" "F.Mask")
			(net 297 "unconnected-(J18H-DP13_C2M_N-PadY31)")
			(pinfunction "DP13_C2M_N")
			(pintype "passive+no_connect")
		)
		(pad "Y32" smd circle
			(at -14.606 8.255 90)
			(size 0.64 0.64)
			(layers "F.Cu" "F.Mask")
			(net 1 "GND")
			(pinfunction "GND")
			(pintype "passive")
		)
		(pad "Y33" smd circle
			(at -15.875 8.255 90)
			(size 0.64 0.64)
			(layers "F.Cu" "F.Mask")
			(net 1 "GND")
			(pinfunction "GND")
			(pintype "passive")
		)
		(pad "Y34" smd circle
			(at -17.145 8.255 90)
			(size 0.64 0.64)
			(layers "F.Cu" "F.Mask")
			(net 302 "unconnected-(J18H-DP17_M2C_P-PadY34)")
			(pinfunction "DP17_M2C_P")
			(pintype "passive+no_connect")
		)
		(pad "Y35" smd circle
			(at -18.415 8.255 90)
			(size 0.64 0.64)
			(layers "F.Cu" "F.Mask")
			(net 303 "unconnected-(J18H-DP17_M2C_N-PadY35)")
			(pinfunction "DP17_M2C_N")
			(pintype "passive+no_connect")
		)
		(pad "Y36" smd circle
			(at -19.685 8.255 90)
			(size 0.64 0.64)
			(layers "F.Cu" "F.Mask")
			(net 1 "GND")
			(pinfunction "GND")
			(pintype "passive")
		)
		(pad "Y37" smd circle
			(at -20.956 8.255 90)
			(size 0.64 0.64)
			(layers "F.Cu" "F.Mask")
			(net 1 "GND")
			(pinfunction "GND")
			(pintype "passive")
		)
		(pad "Y38" smd circle
			(at -22.226 8.255 90)
			(size 0.64 0.64)
			(layers "F.Cu" "F.Mask")
			(net 304 "unconnected-(J18H-DP19_M2C_P-PadY38)")
			(pinfunction "DP19_M2C_P")
			(pintype "passive+no_connect")
		)
		(pad "Y39" smd circle
			(at -23.497 8.255 90)
			(size 0.64 0.64)
			(layers "F.Cu" "F.Mask")
			(net 305 "unconnected-(J18H-DP19_M2C_N-PadY39)")
			(pinfunction "DP19_M2C_N")
			(pintype "passive+no_connect")
		)
		(pad "Y40" smd circle
			(at -24.767 8.255 90)
			(size 0.64 0.64)
			(layers "F.Cu" "F.Mask")
			(net 1 "GND")
			(pinfunction "GND")
			(pintype "passive")
		)
		(pad "Z01" smd circle
			(at 24.765 6.985 90)
			(size 0.64 0.64)
			(layers "F.Cu" "F.Mask")
			(net 306 "unconnected-(J18B-HSPC_PRSNT_M2C_L-PadZ01)")
			(pinfunction "HSPC_PRSNT_M2C_L")
			(pintype "passive+no_connect")
		)
		(pad "Z02" smd circle
			(at 23.495 6.985 90)
			(size 0.64 0.64)
			(layers "F.Cu" "F.Mask")
			(net 1 "GND")
			(pinfunction "GND")
			(pintype "passive")
		)
		(pad "Z03" smd circle
			(at 22.225 6.985 90)
			(size 0.64 0.64)
			(layers "F.Cu" "F.Mask")
			(net 1 "GND")
			(pinfunction "GND")
			(pintype "passive")
		)
		(pad "Z04" smd circle
			(at 20.954 6.985 90)
			(size 0.64 0.64)
			(layers "F.Cu" "F.Mask")
			(net 308 "unconnected-(J18H-DP22_C2M_P-PadZ04)")
			(pinfunction "DP22_C2M_P")
			(pintype "passive+no_connect")
		)
		(pad "Z05" smd circle
			(at 19.684 6.985 90)
			(size 0.64 0.64)
			(layers "F.Cu" "F.Mask")
			(net 309 "unconnected-(J18H-DP22_C2M_N-PadZ05)")
			(pinfunction "DP22_C2M_N")
			(pintype "passive+no_connect")
		)
		(pad "Z06" smd circle
			(at 18.414 6.985 90)
			(size 0.64 0.64)
			(layers "F.Cu" "F.Mask")
			(net 1 "GND")
			(pinfunction "GND")
			(pintype "passive")
		)
		(pad "Z07" smd circle
			(at 17.144 6.985 90)
			(size 0.64 0.64)
			(layers "F.Cu" "F.Mask")
			(net 1 "GND")
			(pinfunction "GND")
			(pintype "passive")
		)
		(pad "Z08" smd circle
			(at 15.874 6.985 90)
			(size 0.64 0.64)
			(layers "F.Cu" "F.Mask")
			(net 310 "unconnected-(J18H-DP20_C2M_P-PadZ08)")
			(pinfunction "DP20_C2M_P")
			(pintype "passive+no_connect")
		)
		(pad "Z09" smd circle
			(at 14.605 6.985 90)
			(size 0.64 0.64)
			(layers "F.Cu" "F.Mask")
			(net 311 "unconnected-(J18H-DP20_C2M_N-PadZ09)")
			(pinfunction "DP20_C2M_N")
			(pintype "passive+no_connect")
		)
		(pad "Z10" smd circle
			(at 13.335 6.985 90)
			(size 0.64 0.64)
			(layers "F.Cu" "F.Mask")
			(net 1 "GND")
			(pinfunction "GND")
			(pintype "passive")
		)
		(pad "Z11" smd circle
			(at 12.063 6.985 90)
			(size 0.64 0.64)
			(layers "F.Cu" "F.Mask")
			(net 1 "GND")
			(pinfunction "GND")
			(pintype "passive")
		)
		(pad "Z12" smd circle
			(at 10.794 6.985 90)
			(size 0.64 0.64)
			(layers "F.Cu" "F.Mask")
			(net 313 "unconnected-(J18H-DP11_M2C_P-PadZ12)")
			(pinfunction "DP11_M2C_P")
			(pintype "passive+no_connect")
		)
		(pad "Z13" smd circle
			(at 9.525 6.985 90)
			(size 0.64 0.64)
			(layers "F.Cu" "F.Mask")
			(net 314 "unconnected-(J18H-DP11_M2C_N-PadZ13)")
			(pinfunction "DP11_M2C_N")
			(pintype "passive+no_connect")
		)
		(pad "Z14" smd circle
			(at 8.255 6.985 90)
			(size 0.64 0.64)
			(layers "F.Cu" "F.Mask")
			(net 1 "GND")
			(pinfunction "GND")
			(pintype "passive")
		)
		(pad "Z15" smd circle
			(at 6.985 6.985 90)
			(size 0.64 0.64)
			(layers "F.Cu" "F.Mask")
			(net 1 "GND")
			(pinfunction "GND")
			(pintype "passive")
		)
		(pad "Z16" smd circle
			(at 5.714 6.985 90)
			(size 0.64 0.64)
			(layers "F.Cu" "F.Mask")
			(net 315 "unconnected-(J18H-DP13_M2C_P-PadZ16)")
			(pinfunction "DP13_M2C_P")
			(pintype "passive+no_connect")
		)
		(pad "Z17" smd circle
			(at 4.445 6.985 90)
			(size 0.64 0.64)
			(layers "F.Cu" "F.Mask")
			(net 316 "unconnected-(J18H-DP13_M2C_N-PadZ17)")
			(pinfunction "DP13_M2C_N")
			(pintype "passive+no_connect")
		)
		(pad "Z18" smd circle
			(at 3.173 6.985 90)
			(size 0.64 0.64)
			(layers "F.Cu" "F.Mask")
			(net 1 "GND")
			(pinfunction "GND")
			(pintype "passive")
		)
		(pad "Z19" smd circle
			(at 1.904 6.985 90)
			(size 0.64 0.64)
			(layers "F.Cu" "F.Mask")
			(net 1 "GND")
			(pinfunction "GND")
			(pintype "passive")
		)
		(pad "Z20" smd circle
			(at 0.633 6.985 90)
			(size 0.64 0.64)
			(layers "F.Cu" "F.Mask")
			(net 317 "unconnected-(J18G-GBTCLK5_M2C_P-PadZ20)")
			(pinfunction "GBTCLK5_M2C_P")
			(pintype "passive+no_connect")
		)
		(pad "Z21" smd circle
			(at -0.635 6.985 90)
			(size 0.64 0.64)
			(layers "F.Cu" "F.Mask")
			(net 318 "unconnected-(J18G-GBTCLK5_M2C_N-PadZ21)")
			(pinfunction "GBTCLK5_M2C_N")
			(pintype "passive+no_connect")
		)
		(pad "Z22" smd circle
			(at -1.905 6.985 90)
			(size 0.64 0.64)
			(layers "F.Cu" "F.Mask")
			(net 1 "GND")
			(pinfunction "GND")
			(pintype "passive")
		)
		(pad "Z23" smd circle
			(at -3.176 6.985 90)
			(size 0.64 0.64)
			(layers "F.Cu" "F.Mask")
			(net 1 "GND")
			(pinfunction "GND")
			(pintype "passive")
		)
		(pad "Z24" smd circle
			(at -4.446 6.985 90)
			(size 0.64 0.64)
			(layers "F.Cu" "F.Mask")
			(net 319 "unconnected-(J18H-DP10_C2M_P-PadZ24)")
			(pinfunction "DP10_C2M_P")
			(pintype "passive+no_connect")
		)
		(pad "Z25" smd circle
			(at -5.715 6.985 90)
			(size 0.64 0.64)
			(layers "F.Cu" "F.Mask")
			(net 320 "unconnected-(J18H-DP10_C2M_N-PadZ25)")
			(pinfunction "DP10_C2M_N")
			(pintype "passive+no_connect")
		)
		(pad "Z26" smd circle
			(at -6.986 6.985 90)
			(size 0.64 0.64)
			(layers "F.Cu" "F.Mask")
			(net 1 "GND")
			(pinfunction "GND")
			(pintype "passive")
		)
		(pad "Z27" smd circle
			(at -8.257 6.985 90)
			(size 0.64 0.64)
			(layers "F.Cu" "F.Mask")
			(net 1 "GND")
			(pinfunction "GND")
			(pintype "passive")
		)
		(pad "Z28" smd circle
			(at -9.526 6.985 90)
			(size 0.64 0.64)
			(layers "F.Cu" "F.Mask")
			(net 321 "unconnected-(J18H-DP12_C2M_P-PadZ28)")
			(pinfunction "DP12_C2M_P")
			(pintype "passive+no_connect")
		)
		(pad "Z29" smd circle
			(at -10.795 6.985 90)
			(size 0.64 0.64)
			(layers "F.Cu" "F.Mask")
			(net 322 "unconnected-(J18H-DP12_C2M_N-PadZ29)")
			(pinfunction "DP12_C2M_N")
			(pintype "passive+no_connect")
		)
		(pad "Z30" smd circle
			(at -12.065 6.985 90)
			(size 0.64 0.64)
			(layers "F.Cu" "F.Mask")
			(net 1 "GND")
			(pinfunction "GND")
			(pintype "passive")
		)
		(pad "Z31" smd circle
			(at -13.337 6.985 90)
			(size 0.64 0.64)
			(layers "F.Cu" "F.Mask")
			(net 1 "GND")
			(pinfunction "GND")
			(pintype "passive")
		)
		(pad "Z32" smd circle
			(at -14.606 6.985 90)
			(size 0.64 0.64)
			(layers "F.Cu" "F.Mask")
			(net 323 "unconnected-(J18H-DP16_M2C_P-PadZ32)")
			(pinfunction "DP16_M2C_P")
			(pintype "passive+no_connect")
		)
		(pad "Z33" smd circle
			(at -15.875 6.985 90)
			(size 0.64 0.64)
			(layers "F.Cu" "F.Mask")
			(net 324 "unconnected-(J18H-DP16_M2C_N-PadZ33)")
			(pinfunction "DP16_M2C_N")
			(pintype "passive+no_connect")
		)
		(pad "Z34" smd circle
			(at -17.145 6.985 90)
			(size 0.64 0.64)
			(layers "F.Cu" "F.Mask")
			(net 1 "GND")
			(pinfunction "GND")
			(pintype "passive")
		)
		(pad "Z35" smd circle
			(at -18.415 6.985 90)
			(size 0.64 0.64)
			(layers "F.Cu" "F.Mask")
			(net 1 "GND")
			(pinfunction "GND")
			(pintype "passive")
		)
		(pad "Z36" smd circle
			(at -19.685 6.985 90)
			(size 0.64 0.64)
			(layers "F.Cu" "F.Mask")
			(net 325 "unconnected-(J18H-DP18_M2C_P-PadZ36)")
			(pinfunction "DP18_M2C_P")
			(pintype "passive+no_connect")
		)
		(pad "Z37" smd circle
			(at -20.956 6.985 90)
			(size 0.64 0.64)
			(layers "F.Cu" "F.Mask")
			(net 326 "unconnected-(J18H-DP18_M2C_N-PadZ37)")
			(pinfunction "DP18_M2C_N")
			(pintype "passive+no_connect")
		)
		(pad "Z38" smd circle
			(at -22.226 6.985 90)
			(size 0.64 0.64)
			(layers "F.Cu" "F.Mask")
			(net 1 "GND")
			(pinfunction "GND")
			(pintype "passive")
		)
		(pad "Z39" smd circle
			(at -23.497 6.985 90)
			(size 0.64 0.64)
			(layers "F.Cu" "F.Mask")
			(net 1 "GND")
			(pinfunction "GND")
			(pintype "passive")
		)
		(pad "Z40" smd circle
			(at -24.767 6.985 90)
			(size 0.64 0.64)
			(layers "F.Cu" "F.Mask")
			(net 24 "+3V3")
			(pinfunction "3P3V")
			(pintype "passive")
		)
	)
	(footprint "antmicro-footprints:C_0402_1005Metric"
		(layer "F.Cu")
		(at 250.145 130.735)
		(descr "Capacitor SMD 0402")
		(tags "capacitor SMD 0402")
		(property "Reference" "C240"
			(at -1.395 -0.435 0)
			(layer "F.SilkS")
			(effects
				(font
					(size 0.7 0.7)
					(thickness 0.15)
				)
				(justify left bottom)
			)
		)
		(property "Value" "C_100n_0402"
			(at 0 1.169 0)
			(layer "F.Fab")
			(effects
				(font
					(size 0.7 0.7)
					(thickness 0.15)
				)
				(justify left bottom)
			)
		)
		(property "Description" "SMD Multilayer Ceramic Capacitor, 0.1 µF, 50 V, 0402 [1005 Metric], ± 10%, X5R, GRM Series"
			(at 0 0 0)
			(layer "F.Fab")
			(hide yes)
			(effects
				(font
					(size 1.27 1.27)
					(thickness 0.15)
				)
			)
		)
		(property "Author" "Antmicro"
			(at 0 0 0)
			(layer "F.Fab")
			(hide yes)
			(effects
				(font
					(size 1 1)
					(thickness 0.15)
				)
			)
		)
		(property "Dielectric" "X5R"
			(at 0 0 0)
			(layer "F.Fab")
			(hide yes)
			(effects
				(font
					(size 1 1)
					(thickness 0.15)
				)
			)
		)
		(property "License" "Apache-2.0"
			(at 0 0 0)
			(layer "F.Fab")
			(hide yes)
			(effects
				(font
					(size 1 1)
					(thickness 0.15)
				)
			)
		)
		(property "MPN" "GRM155R61H104KE14D"
			(at 0 0 0)
			(layer "F.Fab")
			(hide yes)
			(effects
				(font
					(size 1 1)
					(thickness 0.15)
				)
			)
		)
		(property "Manufacturer" "Murata"
			(at 0 0 0)
			(layer "F.Fab")
			(hide yes)
			(effects
				(font
					(size 1 1)
					(thickness 0.15)
				)
			)
		)
		(property "Val" "100n"
			(at 0 0 0)
			(layer "F.Fab")
			(hide yes)
			(effects
				(font
					(size 1 1)
					(thickness 0.15)
				)
			)
		)
		(property "Voltage" "50V"
			(at 0 0 0)
			(layer "F.Fab")
			(hide yes)
			(effects
				(font
					(size 1 1)
					(thickness 0.15)
				)
			)
		)
		(sheetname "USB PHY")
		(sheetfile "usb-phy.kicad_sch")
		(attr smd)
		(fp_rect
			(start -0.925 -0.47)
			(end 0.925 0.47)
			(stroke
				(width 0.05)
				(type default)
			)
			(fill no)
			(layer "F.CrtYd")
		)
		(fp_line
			(start -0.494 -0.25)
			(end 0.504 -0.25)
			(stroke
				(width 0.15)
				(type solid)
			)
			(layer "F.Fab")
		)
		(fp_line
			(start -0.494 0.248)
			(end -0.494 -0.25)
			(stroke
				(width 0.15)
				(type solid)
			)
			(layer "F.Fab")
		)
		(fp_line
			(start 0.504 -0.25)
			(end 0.504 0.248)
			(stroke
				(width 0.15)
				(type solid)
			)
			(layer "F.Fab")
		)
		(fp_line
			(start 0.504 0.248)
			(end -0.494 0.248)
			(stroke
				(width 0.15)
				(type solid)
			)
			(layer "F.Fab")
		)
		(pad "1" smd roundrect
			(at -0.48 0)
			(size 0.59 0.64)
			(layers "F.Cu" "F.Mask" "F.Paste")
			(roundrect_rratio 0.25)
			(net 1 "GND")
			(pintype "passive")
		)
		(pad "2" smd roundrect
			(at 0.48 0)
			(size 0.59 0.64)
			(layers "F.Cu" "F.Mask" "F.Paste")
			(roundrect_rratio 0.25)
			(net 707 "/USB PHY/FTDI_3V3")
			(pintype "passive")
		)
	)
	(footprint "antmicro-footprints:NetTie-2_SMD_Pad0.127mm"
		(layer "F.Cu")
		(at 239.4 124.073 -90)
		(descr "Net tie, 2 pin, 0.127mm  SMD pads")
		(tags "net tie")
		(property "Reference" "NT15"
			(at -0.128 -1.345 270)
			(layer "F.SilkS")
			(hide yes)
			(effects
				(font
					(size 0.7 0.7)
					(thickness 0.15)
				)
				(justify left bottom)
			)
		)
		(property "Value" "Net-Tie_2"
			(at 0 1.199 270)
			(layer "F.Fab")
			(effects
				(font
					(size 0.7 0.7)
					(thickness 0.15)
				)
				(justify left bottom)
			)
		)
		(property "Description" "Net tie, 2 pins"
			(at 0 0 270)
			(layer "F.Fab")
			(hide yes)
			(effects
				(font
					(size 1.27 1.27)
					(thickness 0.15)
				)
			)
		)
		(property "Author" "Antmicro"
			(at 115.327 363.473 0)
			(layer "F.Fab")
			(hide yes)
			(effects
				(font
					(size 1 1)
					(thickness 0.15)
				)
			)
		)
		(property "License" "Apache-2.0"
			(at 115.327 363.473 0)
			(layer "F.Fab")
			(hide yes)
			(effects
				(font
					(size 1 1)
					(thickness 0.15)
				)
			)
		)
		(property "MPN" ""
			(at 115.327 363.473 0)
			(layer "F.Fab")
			(hide yes)
			(effects
				(font
					(size 1 1)
					(thickness 0.15)
				)
			)
		)
		(property "Manufacturer" ""
			(at 115.327 363.473 0)
			(layer "F.Fab")
			(hide yes)
			(effects
				(font
					(size 1 1)
					(thickness 0.15)
				)
			)
		)
		(sheetname "FPGA Bank 12 & 13")
		(sheetfile "fpga-bank-12-13.kicad_sch")
		(attr exclude_from_pos_files)
		(net_tie_pad_groups "1, 2")
		(fp_poly
			(pts
				(xy -0.0635 -0.0635) (xy 0.0625 -0.0635) (xy 0.0625 0.0635) (xy -0.0635 0.0635)
			)
			(stroke
				(width 0)
				(type solid)
			)
			(fill yes)
			(layer "F.Cu")
		)
		(pad "1" smd roundrect
			(at -0.127 0 90)
			(size 0.127 0.127)
			(layers "F.Cu")
			(roundrect_rratio 0.5)
			(chamfer_ratio 0)
			(chamfer top_left bottom_left)
			(net 1328 "/SUP_MCU.TX1")
			(pinfunction "1")
			(pintype "passive")
		)
		(pad "2" smd roundrect
			(at 0.126 0 270)
			(size 0.127 0.127)
			(layers "F.Cu")
			(roundrect_rratio 0.5)
			(chamfer_ratio 0)
			(chamfer top_left bottom_left)
			(net 45 "/FPGA Bank 12 & 13/UART1.RX")
			(pinfunction "2")
			(pintype "passive")
		)
	)
	(footprint "antmicro-footprints:TP_SMD_0.75mm"
		(layer "F.Cu")
		(at 180.9 170.8)
		(property "Reference" "TP5"
			(at 0.5 0.7 0)
			(layer "F.SilkS")
			(effects
				(font
					(size 0.7 0.7)
					(thickness 0.15)
				)
				(justify left bottom)
			)
		)
		(property "Value" "TP_0.75mm_SMD"
			(at 0 1.2 0)
			(layer "F.Fab")
			(effects
				(font
					(size 0.7 0.7)
					(thickness 0.15)
				)
				(justify left bottom)
			)
		)
		(property "Description" "SMT test point"
			(at 0 0 0)
			(layer "F.Fab")
			(hide yes)
			(effects
				(font
					(size 1.27 1.27)
					(thickness 0.15)
				)
			)
		)
		(property "Author" "Antmicro"
			(at 0 0 0)
			(layer "F.Fab")
			(hide yes)
			(effects
				(font
					(size 1 1)
					(thickness 0.15)
				)
			)
		)
		(property "License" "Apache-2.0"
			(at 0 0 0)
			(layer "F.Fab")
			(hide yes)
			(effects
				(font
					(size 1 1)
					(thickness 0.15)
				)
			)
		)
		(property "MPN" ""
			(at 0 0 0)
			(layer "F.Fab")
			(hide yes)
			(effects
				(font
					(size 1 1)
					(thickness 0.15)
				)
			)
		)
		(property "Manufacturer" ""
			(at 0 0 0)
			(layer "F.Fab")
			(hide yes)
			(effects
				(font
					(size 1 1)
					(thickness 0.15)
				)
			)
		)
		(sheetname "DC-DC Converters")
		(sheetfile "dc-dc.kicad_sch")
		(attr exclude_from_pos_files)
		(pad "1" smd circle
			(at 0 0)
			(size 0.75 0.75)
			(layers "F.Cu" "F.Mask")
			(net 1336 "/I2C.SDA")
			(pinfunction "1")
			(pintype "passive")
		)
	)
	(footprint "antmicro-footprints:R_0402_1005Metric"
		(layer "F.Cu")
		(at 218.4 152.8)
		(descr "Resistor SMD 0402")
		(tags "resistor SMD 0402")
		(property "Reference" "R233"
			(at -3.6 0.35 0)
			(layer "F.SilkS")
			(effects
				(font
					(size 0.7 0.7)
					(thickness 0.15)
				)
				(justify left bottom)
			)
		)
		(property "Value" "R_10R_0402"
			(at 0 1.4 0)
			(layer "F.Fab")
			(effects
				(font
					(size 0.7 0.7)
					(thickness 0.15)
				)
				(justify left bottom)
			)
		)
		(property "Description" "SMD Chip Resistor, 10 ohm, ± 1%, 62.5 mW, 0402 [1005 Metric], Thick Film, General Purpose"
			(at 0 0 0)
			(layer "F.Fab")
			(hide yes)
			(effects
				(font
					(size 1.27 1.27)
					(thickness 0.15)
				)
			)
		)
		(property "Author" "Antmicro"
			(at 0 0 0)
			(layer "F.Fab")
			(hide yes)
			(effects
				(font
					(size 1 1)
					(thickness 0.15)
				)
			)
		)
		(property "License" "Apache-2.0"
			(at 0 0 0)
			(layer "F.Fab")
			(hide yes)
			(effects
				(font
					(size 1 1)
					(thickness 0.15)
				)
			)
		)
		(property "MPN" "CR0402-FX-10R0GLF"
			(at 0 0 0)
			(layer "F.Fab")
			(hide yes)
			(effects
				(font
					(size 1 1)
					(thickness 0.15)
				)
			)
		)
		(property "Manufacturer" "Bourns"
			(at 0 0 0)
			(layer "F.Fab")
			(hide yes)
			(effects
				(font
					(size 1 1)
					(thickness 0.15)
				)
			)
		)
		(property "Tolerance" "1%"
			(at 0 0 0)
			(layer "F.Fab")
			(hide yes)
			(effects
				(font
					(size 1 1)
					(thickness 0.15)
				)
			)
		)
		(property "Val" "10R"
			(at 0 0 0)
			(layer "F.Fab")
			(hide yes)
			(effects
				(font
					(size 1 1)
					(thickness 0.15)
				)
			)
		)
		(sheetname "HDMI + Ethernet")
		(sheetfile "hdmi-ethernet.kicad_sch")
		(attr smd)
		(fp_rect
			(start -0.925 -0.47)
			(end 0.925 0.47)
			(stroke
				(width 0.05)
				(type default)
			)
			(fill no)
			(layer "F.CrtYd")
		)
		(fp_rect
			(start -0.5 -0.25)
			(end 0.5 0.25)
			(stroke
				(width 0.15)
				(type solid)
			)
			(fill no)
			(layer "F.Fab")
		)
		(pad "1" smd roundrect
			(at -0.48 0)
			(size 0.59 0.64)
			(layers "F.Cu" "F.Mask" "F.Paste")
			(roundrect_rratio 0.25)
			(net 515 "/FPGA Bank 18 & 32/ETH_RMII.TXD1")
			(pintype "passive")
		)
		(pad "2" smd roundrect
			(at 0.48 0)
			(size 0.59 0.64)
			(layers "F.Cu" "F.Mask" "F.Paste")
			(roundrect_rratio 0.25)
			(net 950 "/HDMI + Ethernet/ETH_PHY_TXD1")
			(pintype "passive")
		)
	)
	(footprint "antmicro-footprints:PinSocket_2x6_P2.54mm_Drill1.04mm_Horizontal"
		(layer "F.Cu")
		(at 236.1875 80.1495)
		(property "Reference" "J6"
			(at 14.3125 -1.7495 0)
			(layer "F.SilkS")
			(effects
				(font
					(size 0.7 0.7)
					(thickness 0.15)
				)
				(justify left bottom)
			)
		)
		(property "Value" "PinSocket_2x6_P2.54mm_Drill1.04mm_Horizontal"
			(at 0 4.75 0)
			(layer "F.Fab")
			(effects
				(font
					(size 0.7 0.7)
					(thickness 0.15)
				)
				(justify left bottom)
			)
		)
		(property "Description" "PCB Receptacle, Board-to-Board, 2.54 mm, 2 Rows, 12 Contacts, Through Hole Mount Right Angle, SSW"
			(at 0 0 0)
			(layer "F.Fab")
			(hide yes)
			(effects
				(font
					(size 1.27 1.27)
					(thickness 0.15)
				)
			)
		)
		(property "Author" "Antmicro"
			(at 0 0 0)
			(layer "F.Fab")
			(hide yes)
			(effects
				(font
					(size 1 1)
					(thickness 0.15)
				)
			)
		)
		(property "License" "Apache-2.0"
			(at 0 0 0)
			(layer "F.Fab")
			(hide yes)
			(effects
				(font
					(size 1 1)
					(thickness 0.15)
				)
			)
		)
		(property "MPN" "SSW-106-02-G-D-RA"
			(at 0 0 0)
			(layer "F.Fab")
			(hide yes)
			(effects
				(font
					(size 1 1)
					(thickness 0.15)
				)
			)
		)
		(property "Manufacturer" "Samtec"
			(at 0 0 0)
			(layer "F.Fab")
			(hide yes)
			(effects
				(font
					(size 1 1)
					(thickness 0.15)
				)
			)
		)
		(sheetname "User GPIO + LED + button + DIP switch")
		(sheetfile "user-gpio.kicad_sch")
		(attr through_hole)
		(fp_line
			(start -1.526 -1.524)
			(end -1.526 -10.035)
			(stroke
				(width 0.15)
				(type solid)
			)
			(layer "F.SilkS")
		)
		(fp_line
			(start 14.223 -10.035)
			(end -1.526 -10.035)
			(stroke
				(width 0.15)
				(type solid)
			)
			(layer "F.SilkS")
		)
		(fp_line
			(start 14.223 -10.035)
			(end 14.223 -1.524)
			(stroke
				(width 0.15)
				(type solid)
			)
			(layer "F.SilkS")
		)
		(fp_line
			(start 14.223 -1.524)
			(end -1.526 -1.524)
			(stroke
				(width 0.15)
				(type solid)
			)
			(layer "F.SilkS")
		)
		(fp_circle
			(center -1.2 0)
			(end -1.15 0)
			(stroke
				(width 0.15)
				(type solid)
			)
			(fill yes)
			(layer "F.SilkS")
		)
		(fp_rect
			(start -1.9 -10.4)
			(end 14.6 3.6)
			(stroke
				(width 0.05)
				(type solid)
			)
			(fill no)
			(layer "F.CrtYd")
		)
		(fp_line
			(start -1.526 -10.035)
			(end 14.223 -10.035)
			(stroke
				(width 0.15)
				(type solid)
			)
			(layer "F.Fab")
		)
		(fp_line
			(start -1.526 -10.035)
			(end 14.223 -10.035)
			(stroke
				(width 0.15)
				(type solid)
			)
			(layer "F.Fab")
		)
		(fp_line
			(start -1.526 -1.524)
			(end -1.526 -10.035)
			(stroke
				(width 0.15)
				(type solid)
			)
			(layer "F.Fab")
		)
		(fp_line
			(start -1.526 -1.524)
			(end -1.526 -10.035)
			(stroke
				(width 0.15)
				(type solid)
			)
			(layer "F.Fab")
		)
		(fp_line
			(start 14.223 -10.035)
			(end 14.223 -1.524)
			(stroke
				(width 0.15)
				(type solid)
			)
			(layer "F.Fab")
		)
		(fp_line
			(start 14.223 -10.035)
			(end 14.223 -1.524)
			(stroke
				(width 0.15)
				(type solid)
			)
			(layer "F.Fab")
		)
		(fp_line
			(start 14.223 -1.524)
			(end -1.526 -1.524)
			(stroke
				(width 0.15)
				(type solid)
			)
			(layer "F.Fab")
		)
		(pad "1" thru_hole rect
			(at 0 0)
			(size 1.84 1.84)
			(drill 1.04)
			(layers "*.Cu" "*.Mask")
			(remove_unused_layers no)
			(net 816 "/User GPIO + LED + button + DIP switch/PMOD_B_7")
			(pintype "passive")
		)
		(pad "2" thru_hole circle
			(at 0 2.539)
			(size 1.84 1.84)
			(drill 1.04)
			(layers "*.Cu" "*.Mask")
			(remove_unused_layers no)
			(net 817 "/User GPIO + LED + button + DIP switch/PMOD_B_1")
			(pintype "passive")
		)
		(pad "3" thru_hole circle
			(at 2.539 0)
			(size 1.84 1.84)
			(drill 1.04)
			(layers "*.Cu" "*.Mask")
			(remove_unused_layers no)
			(net 814 "/User GPIO + LED + button + DIP switch/PMOD_B_8")
			(pintype "passive")
		)
		(pad "4" thru_hole circle
			(at 2.539 2.539)
			(size 1.8 1.8)
			(drill 1.04)
			(layers "*.Cu" "*.Mask")
			(remove_unused_layers no)
			(net 815 "/User GPIO + LED + button + DIP switch/PMOD_B_2")
			(pintype "passive")
		)
		(pad "5" thru_hole circle
			(at 5.078 0)
			(size 1.84 1.84)
			(drill 1.04)
			(layers "*.Cu" "*.Mask")
			(remove_unused_layers no)
			(net 812 "/User GPIO + LED + button + DIP switch/PMOD_B_9")
			(pintype "passive")
		)
		(pad "6" thru_hole circle
			(at 5.078 2.539)
			(size 1.84 1.84)
			(drill 1.04)
			(layers "*.Cu" "*.Mask")
			(remove_unused_layers no)
			(net 813 "/User GPIO + LED + button + DIP switch/PMOD_B_3")
			(pintype "passive")
		)
		(pad "7" thru_hole circle
			(at 7.618 0)
			(size 1.84 1.84)
			(drill 1.04)
			(layers "*.Cu" "*.Mask")
			(remove_unused_layers no)
			(net 810 "/User GPIO + LED + button + DIP switch/PMOD_B_10")
			(pintype "passive")
		)
		(pad "8" thru_hole circle
			(at 7.618 2.539)
			(size 1.84 1.84)
			(drill 1.04)
			(layers "*.Cu" "*.Mask")
			(remove_unused_layers no)
			(net 811 "/User GPIO + LED + button + DIP switch/PMOD_B_4")
			(pintype "passive")
		)
		(pad "9" thru_hole circle
			(at 10.159 0)
			(size 1.84 1.84)
			(drill 1.04)
			(layers "*.Cu" "*.Mask")
			(remove_unused_layers no)
			(net 1 "GND")
			(pintype "passive")
		)
		(pad "10" thru_hole circle
			(at 10.159 2.539)
			(size 1.84 1.84)
			(drill 1.04)
			(layers "*.Cu" "*.Mask")
			(remove_unused_layers no)
			(net 1 "GND")
			(pintype "passive")
		)
		(pad "11" thru_hole circle
			(at 12.698 0)
			(size 1.84 1.84)
			(drill 1.04)
			(layers "*.Cu" "*.Mask")
			(remove_unused_layers no)
			(net 24 "+3V3")
			(pintype "passive")
		)
		(pad "12" thru_hole circle
			(at 12.698 2.539)
			(size 1.84 1.84)
			(drill 1.04)
			(layers "*.Cu" "*.Mask")
			(remove_unused_layers no)
			(net 24 "+3V3")
			(pintype "passive")
		)
	)
	(footprint "antmicro-footprints:C_0603_1608Metric"
		(layer "F.Cu")
		(at 174.9 165.5 180)
		(descr "Capacitor SMD 0603")
		(tags "capacitor 0603")
		(property "Reference" "C330"
			(at 1 -0.4 0)
			(layer "F.SilkS")
			(effects
				(font
					(size 0.7 0.7)
					(thickness 0.15)
				)
				(justify right bottom)
			)
		)
		(property "Value" "C_22u_0603"
			(at 0 1.6 0)
			(layer "F.Fab")
			(effects
				(font
					(size 0.7 0.7)
					(thickness 0.15)
				)
				(justify right bottom)
			)
		)
		(property "Description" "SMD Multilayer Ceramic Capacitor, 22 µF, 6.3 V, 0603 [1608 Metric], ± 20%, X5R, GRM Series"
			(at 0 0 180)
			(layer "F.Fab")
			(hide yes)
			(effects
				(font
					(size 1.27 1.27)
					(thickness 0.15)
				)
			)
		)
		(property "Author" "Antmicro"
			(at 349.8 331 0)
			(layer "F.Fab")
			(hide yes)
			(effects
				(font
					(size 1 1)
					(thickness 0.15)
				)
			)
		)
		(property "Dielectric" ""
			(at 349.8 331 0)
			(layer "F.Fab")
			(hide yes)
			(effects
				(font
					(size 1 1)
					(thickness 0.15)
				)
			)
		)
		(property "License" "Apache-2.0"
			(at 349.8 331 0)
			(layer "F.Fab")
			(hide yes)
			(effects
				(font
					(size 1 1)
					(thickness 0.15)
				)
			)
		)
		(property "MPN" "GRM188R60J226MEA0D"
			(at 349.8 331 0)
			(layer "F.Fab")
			(hide yes)
			(effects
				(font
					(size 1 1)
					(thickness 0.15)
				)
			)
		)
		(property "Manufacturer" "Murata"
			(at 349.8 331 0)
			(layer "F.Fab")
			(hide yes)
			(effects
				(font
					(size 1 1)
					(thickness 0.15)
				)
			)
		)
		(property "Val" "22u"
			(at 349.8 331 0)
			(layer "F.Fab")
			(hide yes)
			(effects
				(font
					(size 1 1)
					(thickness 0.15)
				)
			)
		)
		(property "Voltage" ""
			(at 349.8 331 0)
			(layer "F.Fab")
			(hide yes)
			(effects
				(font
					(size 1 1)
					(thickness 0.15)
				)
			)
		)
		(sheetname "DC-DC Converters")
		(sheetfile "dc-dc.kicad_sch")
		(attr smd)
		(fp_line
			(start -0.15 0.4)
			(end 0.15 0.4)
			(stroke
				(width 0.15)
				(type solid)
			)
			(layer "F.SilkS")
		)
		(fp_line
			(start -0.15 -0.4)
			(end 0.15 -0.4)
			(stroke
				(width 0.15)
				(type solid)
			)
			(layer "F.SilkS")
		)
		(fp_rect
			(start -1.25 -0.65)
			(end 1.25 0.65)
			(stroke
				(width 0.05)
				(type solid)
			)
			(fill no)
			(layer "F.CrtYd")
		)
		(fp_rect
			(start -0.8 -0.4)
			(end 0.8 0.4)
			(stroke
				(width 0.15)
				(type solid)
			)
			(fill no)
			(layer "F.Fab")
		)
		(pad "1" smd roundrect
			(at -0.7 0 180)
			(size 0.8 1)
			(layers "F.Cu" "F.Mask" "F.Paste")
			(roundrect_rratio 0.2)
			(net 1 "GND")
			(pintype "passive")
		)
		(pad "2" smd roundrect
			(at 0.7 0 180)
			(size 0.8 1)
			(layers "F.Cu" "F.Mask" "F.Paste")
			(roundrect_rratio 0.2)
			(net 735 "/DC-DC Converters/3V3_local")
			(pintype "passive")
		)
	)
	(footprint "antmicro-footprints:TP_SMD_0.75mm"
		(layer "F.Cu")
		(at 156.4625 176.675)
		(property "Reference" "TP4"
			(at 0.3375 2.475 90)
			(layer "F.SilkS")
			(effects
				(font
					(size 0.7 0.7)
					(thickness 0.15)
				)
				(justify left bottom)
			)
		)
		(property "Value" "TP_0.75mm_SMD"
			(at 0 1.2 0)
			(layer "F.Fab")
			(effects
				(font
					(size 0.7 0.7)
					(thickness 0.15)
				)
				(justify left bottom)
			)
		)
		(property "Description" "SMT test point"
			(at 0 0 0)
			(layer "F.Fab")
			(hide yes)
			(effects
				(font
					(size 1.27 1.27)
					(thickness 0.15)
				)
			)
		)
		(property "Author" "Antmicro"
			(at 0 0 0)
			(layer "F.Fab")
			(hide yes)
			(effects
				(font
					(size 1 1)
					(thickness 0.15)
				)
			)
		)
		(property "License" "Apache-2.0"
			(at 0 0 0)
			(layer "F.Fab")
			(hide yes)
			(effects
				(font
					(size 1 1)
					(thickness 0.15)
				)
			)
		)
		(property "MPN" ""
			(at 0 0 0)
			(layer "F.Fab")
			(hide yes)
			(effects
				(font
					(size 1 1)
					(thickness 0.15)
				)
			)
		)
		(property "Manufacturer" ""
			(at 0 0 0)
			(layer "F.Fab")
			(hide yes)
			(effects
				(font
					(size 1 1)
					(thickness 0.15)
				)
			)
		)
		(sheetname "DC-DC Converters")
		(sheetfile "dc-dc.kicad_sch")
		(attr exclude_from_pos_files)
		(pad "1" smd circle
			(at 0 0)
			(size 0.75 0.75)
			(layers "F.Cu" "F.Mask")
			(net 1413 "/SUP_MCU.PG_1V2")
			(pinfunction "1")
			(pintype "passive")
		)
	)
	(footprint "antmicro-footprints:C_0402_1005Metric"
		(layer "F.Cu")
		(at 228.725 140.75 -90)
		(descr "Capacitor SMD 0402")
		(tags "capacitor SMD 0402")
		(property "Reference" "C368"
			(at 3.15 0.125 0)
			(layer "F.SilkS")
			(effects
				(font
					(size 0.7 0.7)
					(thickness 0.15)
				)
				(justify right bottom)
			)
		)
		(property "Value" "C_100n_0402"
			(at 0 1.4 90)
			(layer "F.Fab")
			(effects
				(font
					(size 0.7 0.7)
					(thickness 0.15)
				)
				(justify right bottom)
			)
		)
		(property "Description" "SMD Multilayer Ceramic Capacitor, 0.1 µF, 50 V, 0402 [1005 Metric], ± 10%, X5R, GRM Series"
			(at 0 0 270)
			(layer "F.Fab")
			(hide yes)
			(effects
				(font
					(size 1.27 1.27)
					(thickness 0.15)
				)
			)
		)
		(property "Author" "Antmicro"
			(at 87.975 369.475 0)
			(layer "F.Fab")
			(hide yes)
			(effects
				(font
					(size 1 1)
					(thickness 0.15)
				)
			)
		)
		(property "Dielectric" "X5R"
			(at 87.975 369.475 0)
			(layer "F.Fab")
			(hide yes)
			(effects
				(font
					(size 1 1)
					(thickness 0.15)
				)
			)
		)
		(property "License" "Apache-2.0"
			(at 87.975 369.475 0)
			(layer "F.Fab")
			(hide yes)
			(effects
				(font
					(size 1 1)
					(thickness 0.15)
				)
			)
		)
		(property "MPN" "GRM155R61H104KE14D"
			(at 87.975 369.475 0)
			(layer "F.Fab")
			(hide yes)
			(effects
				(font
					(size 1 1)
					(thickness 0.15)
				)
			)
		)
		(property "Manufacturer" "Murata"
			(at 87.975 369.475 0)
			(layer "F.Fab")
			(hide yes)
			(effects
				(font
					(size 1 1)
					(thickness 0.15)
				)
			)
		)
		(property "Val" "100n"
			(at 87.975 369.475 0)
			(layer "F.Fab")
			(hide yes)
			(effects
				(font
					(size 1 1)
					(thickness 0.15)
				)
			)
		)
		(property "Voltage" "50V"
			(at 87.975 369.475 0)
			(layer "F.Fab")
			(hide yes)
			(effects
				(font
					(size 1 1)
					(thickness 0.15)
				)
			)
		)
		(sheetname "Clocks")
		(sheetfile "clocks.kicad_sch")
		(attr smd)
		(fp_rect
			(start -0.925 -0.47)
			(end 0.925 0.47)
			(stroke
				(width 0.05)
				(type default)
			)
			(fill no)
			(layer "F.CrtYd")
		)
		(fp_line
			(start -0.494 0.248)
			(end -0.494 -0.25)
			(stroke
				(width 0.15)
				(type solid)
			)
			(layer "F.Fab")
		)
		(fp_line
			(start 0.504 0.248)
			(end -0.494 0.248)
			(stroke
				(width 0.15)
				(type solid)
			)
			(layer "F.Fab")
		)
		(fp_line
			(start -0.494 -0.25)
			(end 0.504 -0.25)
			(stroke
				(width 0.15)
				(type solid)
			)
			(layer "F.Fab")
		)
		(fp_line
			(start 0.504 -0.25)
			(end 0.504 0.248)
			(stroke
				(width 0.15)
				(type solid)
			)
			(layer "F.Fab")
		)
		(pad "1" smd roundrect
			(at -0.48 0 270)
			(size 0.59 0.64)
			(layers "F.Cu" "F.Mask" "F.Paste")
			(roundrect_rratio 0.25)
			(net 1 "GND")
			(pintype "passive")
		)
		(pad "2" smd roundrect
			(at 0.48 0 270)
			(size 0.59 0.64)
			(layers "F.Cu" "F.Mask" "F.Paste")
			(roundrect_rratio 0.25)
			(net 1231 "Net-(C366-Pad2)")
			(pintype "passive")
		)
	)
	(footprint "antmicro-footprints:R_0402_1005Metric"
		(layer "F.Cu")
		(at 218.4 147.8)
		(descr "Resistor SMD 0402")
		(tags "resistor SMD 0402")
		(property "Reference" "R198"
			(at -3.6 0.35 180)
			(layer "F.SilkS")
			(effects
				(font
					(size 0.7 0.7)
					(thickness 0.15)
				)
				(justify left bottom)
			)
		)
		(property "Value" "R_1k_0402"
			(at 0 1.4 0)
			(layer "F.Fab")
			(effects
				(font
					(size 0.7 0.7)
					(thickness 0.15)
				)
				(justify left bottom)
			)
		)
		(property "Description" "SMD Chip Resistor, 1 kohm, ± 1%, 63 mW, 0402 [1005 Metric], Thick Film, General Purpose"
			(at 0 0 0)
			(layer "F.Fab")
			(hide yes)
			(effects
				(font
					(size 1.27 1.27)
					(thickness 0.15)
				)
			)
		)
		(property "Author" "Antmicro"
			(at 0 0 0)
			(layer "F.Fab")
			(hide yes)
			(effects
				(font
					(size 1 1)
					(thickness 0.15)
				)
			)
		)
		(property "License" "Apache-2.0"
			(at 0 0 0)
			(layer "F.Fab")
			(hide yes)
			(effects
				(font
					(size 1 1)
					(thickness 0.15)
				)
			)
		)
		(property "MPN" "CR0402-FX-1001GLF"
			(at 0 0 0)
			(layer "F.Fab")
			(hide yes)
			(effects
				(font
					(size 1 1)
					(thickness 0.15)
				)
			)
		)
		(property "Manufacturer" "Bourns"
			(at 0 0 0)
			(layer "F.Fab")
			(hide yes)
			(effects
				(font
					(size 1 1)
					(thickness 0.15)
				)
			)
		)
		(property "Tolerance" "1%"
			(at 0 0 0)
			(layer "F.Fab")
			(hide yes)
			(effects
				(font
					(size 1 1)
					(thickness 0.15)
				)
			)
		)
		(property "Val" "1k"
			(at 0 0 0)
			(layer "F.Fab")
			(hide yes)
			(effects
				(font
					(size 1 1)
					(thickness 0.15)
				)
			)
		)
		(sheetname "HDMI + Ethernet")
		(sheetfile "hdmi-ethernet.kicad_sch")
		(attr smd)
		(fp_rect
			(start -0.925 -0.47)
			(end 0.925 0.47)
			(stroke
				(width 0.05)
				(type default)
			)
			(fill no)
			(layer "F.CrtYd")
		)
		(fp_rect
			(start -0.5 -0.25)
			(end 0.5 0.25)
			(stroke
				(width 0.15)
				(type solid)
			)
			(fill no)
			(layer "F.Fab")
		)
		(pad "1" smd roundrect
			(at -0.48 0)
			(size 0.59 0.64)
			(layers "F.Cu" "F.Mask" "F.Paste")
			(roundrect_rratio 0.25)
			(net 26 "+1V8")
			(pintype "passive")
		)
		(pad "2" smd roundrect
			(at 0.48 0)
			(size 0.59 0.64)
			(layers "F.Cu" "F.Mask" "F.Paste")
			(roundrect_rratio 0.25)
			(net 502 "/FPGA Bank 18 & 32/ETH_RMII.MDIO")
			(pintype "passive")
		)
	)
	(footprint "antmicro-footprints:C_0603_1608Metric"
		(layer "F.Cu")
		(at 195.6 158.349001)
		(descr "Capacitor SMD 0603")
		(tags "capacitor 0603")
		(property "Reference" "C359"
			(at -3.9 0.400999 0)
			(layer "F.SilkS")
			(effects
				(font
					(size 0.7 0.7)
					(thickness 0.15)
				)
				(justify left bottom)
			)
		)
		(property "Value" "C_22u_0603"
			(at 0 1.6 0)
			(layer "F.Fab")
			(effects
				(font
					(size 0.7 0.7)
					(thickness 0.15)
				)
				(justify left bottom)
			)
		)
		(property "Description" "SMD Multilayer Ceramic Capacitor, 22 µF, 6.3 V, 0603 [1608 Metric], ± 20%, X5R, GRM Series"
			(at 0 0 0)
			(layer "F.Fab")
			(hide yes)
			(effects
				(font
					(size 1.27 1.27)
					(thickness 0.15)
				)
			)
		)
		(property "Author" "Antmicro"
			(at 0 0 0)
			(layer "F.Fab")
			(hide yes)
			(effects
				(font
					(size 1 1)
					(thickness 0.15)
				)
			)
		)
		(property "Dielectric" ""
			(at 0 0 0)
			(layer "F.Fab")
			(hide yes)
			(effects
				(font
					(size 1 1)
					(thickness 0.15)
				)
			)
		)
		(property "License" "Apache-2.0"
			(at 0 0 0)
			(layer "F.Fab")
			(hide yes)
			(effects
				(font
					(size 1 1)
					(thickness 0.15)
				)
			)
		)
		(property "MPN" "GRM188R60J226MEA0D"
			(at 0 0 0)
			(layer "F.Fab")
			(hide yes)
			(effects
				(font
					(size 1 1)
					(thickness 0.15)
				)
			)
		)
		(property "Manufacturer" "Murata"
			(at 0 0 0)
			(layer "F.Fab")
			(hide yes)
			(effects
				(font
					(size 1 1)
					(thickness 0.15)
				)
			)
		)
		(property "Val" "22u"
			(at 0 0 0)
			(layer "F.Fab")
			(hide yes)
			(effects
				(font
					(size 1 1)
					(thickness 0.15)
				)
			)
		)
		(property "Voltage" ""
			(at 0 0 0)
			(layer "F.Fab")
			(hide yes)
			(effects
				(font
					(size 1 1)
					(thickness 0.15)
				)
			)
		)
		(sheetname "DC-DC Converters")
		(sheetfile "dc-dc.kicad_sch")
		(attr smd)
		(fp_line
			(start -0.15 -0.4)
			(end 0.15 -0.4)
			(stroke
				(width 0.15)
				(type solid)
			)
			(layer "F.SilkS")
		)
		(fp_line
			(start -0.15 0.4)
			(end 0.15 0.4)
			(stroke
				(width 0.15)
				(type solid)
			)
			(layer "F.SilkS")
		)
		(fp_rect
			(start -1.25 -0.65)
			(end 1.25 0.65)
			(stroke
				(width 0.05)
				(type solid)
			)
			(fill no)
			(layer "F.CrtYd")
		)
		(fp_rect
			(start -0.8 -0.4)
			(end 0.8 0.4)
			(stroke
				(width 0.15)
				(type solid)
			)
			(fill no)
			(layer "F.Fab")
		)
		(pad "1" smd roundrect
			(at -0.7 0)
			(size 0.8 1)
			(layers "F.Cu" "F.Mask" "F.Paste")
			(roundrect_rratio 0.2)
			(net 1 "GND")
			(pintype "passive")
		)
		(pad "2" smd roundrect
			(at 0.7 0)
			(size 0.8 1)
			(layers "F.Cu" "F.Mask" "F.Paste")
			(roundrect_rratio 0.2)
			(net 751 "/DC-DC Converters/1V0_REG")
			(pintype "passive")
		)
	)
	(footprint "antmicro-footprints:SOD-523"
		(layer "F.Cu")
		(at 236.4 137.7 180)
		(property "Reference" "D30"
			(at 3.1 -0.35 180)
			(layer "F.SilkS")
			(effects
				(font
					(size 0.7 0.7)
					(thickness 0.15)
				)
				(justify left bottom)
			)
		)
		(property "Value" "BAT54-02V-G3-08"
			(at 0 1.499 180)
			(layer "F.Fab")
			(effects
				(font
					(size 0.7 0.7)
					(thickness 0.15)
				)
				(justify left bottom)
			)
		)
		(property "Description" "Small Signal Schottky Diode, Single, 30 V, 200 mA, 800 mV, 600 mA, 125 °C"
			(at 0 0 180)
			(layer "F.Fab")
			(hide yes)
			(effects
				(font
					(size 1.27 1.27)
					(thickness 0.15)
				)
			)
		)
		(property "Author" "Antmicro"
			(at 472.8 275.4 0)
			(layer "F.Fab")
			(hide yes)
			(effects
				(font
					(size 1 1)
					(thickness 0.15)
				)
			)
		)
		(property "License" "Apache-2.0"
			(at 472.8 275.4 0)
			(layer "F.Fab")
			(hide yes)
			(effects
				(font
					(size 1 1)
					(thickness 0.15)
				)
			)
		)
		(property "MPN" "BAT54-02V-G3-08"
			(at 472.8 275.4 0)
			(layer "F.Fab")
			(hide yes)
			(effects
				(font
					(size 1 1)
					(thickness 0.15)
				)
			)
		)
		(property "Manufacturer" "Vishay"
			(at 472.8 275.4 0)
			(layer "F.Fab")
			(hide yes)
			(effects
				(font
					(size 1 1)
					(thickness 0.15)
				)
			)
		)
		(property "Public" "False"
			(at 472.8 275.4 0)
			(layer "F.Fab")
			(hide yes)
			(effects
				(font
					(size 1 1)
					(thickness 0.15)
				)
			)
		)
		(sheetname "USB PHY")
		(sheetfile "usb-phy.kicad_sch")
		(attr smd)
		(fp_line
			(start -0.35 -0.5)
			(end -0.35 0.5)
			(stroke
				(width 0.15)
				(type solid)
			)
			(layer "F.SilkS")
		)
		(fp_rect
			(start -1 -0.6)
			(end 1 0.6)
			(stroke
				(width 0.05)
				(type solid)
			)
			(fill no)
			(layer "F.CrtYd")
		)
		(fp_line
			(start 0.65 -0.425)
			(end 0.65 0.423)
			(stroke
				(width 0.15)
				(type solid)
			)
			(layer "F.Fab")
		)
		(fp_line
			(start -0.35 -0.4)
			(end -0.35 0.4)
			(stroke
				(width 0.15)
				(type solid)
			)
			(layer "F.Fab")
		)
		(fp_line
			(start -0.652 0.423)
			(end 0.65 0.423)
			(stroke
				(width 0.15)
				(type solid)
			)
			(layer "F.Fab")
		)
		(fp_line
			(start -0.652 0.423)
			(end -0.652 -0.425)
			(stroke
				(width 0.15)
				(type solid)
			)
			(layer "F.Fab")
		)
		(fp_line
			(start -0.652 -0.425)
			(end 0.65 -0.425)
			(stroke
				(width 0.15)
				(type solid)
			)
			(layer "F.Fab")
		)
		(pad "1" smd roundrect
			(at -0.701 0 180)
			(size 0.5 0.6)
			(layers "F.Cu" "F.Mask" "F.Paste")
			(roundrect_rratio 0.25)
			(net 1047 "/USB PHY/FTDI_SDA_OUT")
			(pinfunction "C")
			(pintype "passive")
		)
		(pad "2" smd roundrect
			(at 0.699 0 180)
			(size 0.5 0.6)
			(layers "F.Cu" "F.Mask" "F.Paste")
			(roundrect_rratio 0.25)
			(net 942 "/USB PHY/FTDI_SDA_IN")
			(pinfunction "A")
			(pintype "passive")
		)
	)
	(footprint "antmicro-footprints:C_0402_1005Metric"
		(layer "F.Cu")
		(at 159.8 155.7 -90)
		(descr "Capacitor SMD 0402")
		(tags "capacitor SMD 0402")
		(property "Reference" "C344"
			(at 0.75 -0.4 90)
			(layer "F.SilkS")
			(effects
				(font
					(size 0.7 0.7)
					(thickness 0.15)
				)
				(justify right bottom)
			)
		)
		(property "Value" "C_10u_0402"
			(at 0 1.4 90)
			(layer "F.Fab")
			(effects
				(font
					(size 0.7 0.7)
					(thickness 0.15)
				)
				(justify right bottom)
			)
		)
		(property "Description" "SMD Multilayer Ceramic Capacitor, 10 µF, 6.3 V, 0402 [1005 Metric], ± 20%, X5R, CC Series"
			(at 0 0 270)
			(layer "F.Fab")
			(hide yes)
			(effects
				(font
					(size 1.27 1.27)
					(thickness 0.15)
				)
			)
		)
		(property "Author" "Antmicro"
			(at 4.1 315.5 0)
			(layer "F.Fab")
			(hide yes)
			(effects
				(font
					(size 1 1)
					(thickness 0.15)
				)
			)
		)
		(property "Dielectric" ""
			(at 4.1 315.5 0)
			(layer "F.Fab")
			(hide yes)
			(effects
				(font
					(size 1 1)
					(thickness 0.15)
				)
			)
		)
		(property "License" "Apache-2.0"
			(at 4.1 315.5 0)
			(layer "F.Fab")
			(hide yes)
			(effects
				(font
					(size 1 1)
					(thickness 0.15)
				)
			)
		)
		(property "MPN" "CC0402MRX5R5BB106"
			(at 4.1 315.5 0)
			(layer "F.Fab")
			(hide yes)
			(effects
				(font
					(size 1 1)
					(thickness 0.15)
				)
			)
		)
		(property "Manufacturer" "YAGEO"
			(at 4.1 315.5 0)
			(layer "F.Fab")
			(hide yes)
			(effects
				(font
					(size 1 1)
					(thickness 0.15)
				)
			)
		)
		(property "Val" "10u"
			(at 4.1 315.5 0)
			(layer "F.Fab")
			(hide yes)
			(effects
				(font
					(size 1 1)
					(thickness 0.15)
				)
			)
		)
		(property "Voltage" ""
			(at 4.1 315.5 0)
			(layer "F.Fab")
			(hide yes)
			(effects
				(font
					(size 1 1)
					(thickness 0.15)
				)
			)
		)
		(sheetname "DC-DC Converters")
		(sheetfile "dc-dc.kicad_sch")
		(attr smd)
		(fp_rect
			(start -0.925 -0.47)
			(end 0.925 0.47)
			(stroke
				(width 0.05)
				(type default)
			)
			(fill no)
			(layer "F.CrtYd")
		)
		(fp_line
			(start -0.494 0.248)
			(end -0.494 -0.25)
			(stroke
				(width 0.15)
				(type solid)
			)
			(layer "F.Fab")
		)
		(fp_line
			(start 0.504 0.248)
			(end -0.494 0.248)
			(stroke
				(width 0.15)
				(type solid)
			)
			(layer "F.Fab")
		)
		(fp_line
			(start -0.494 -0.25)
			(end 0.504 -0.25)
			(stroke
				(width 0.15)
				(type solid)
			)
			(layer "F.Fab")
		)
		(fp_line
			(start 0.504 -0.25)
			(end 0.504 0.248)
			(stroke
				(width 0.15)
				(type solid)
			)
			(layer "F.Fab")
		)
		(pad "1" smd roundrect
			(at -0.48 0 270)
			(size 0.59 0.64)
			(layers "F.Cu" "F.Mask" "F.Paste")
			(roundrect_rratio 0.25)
			(net 1 "GND")
			(pintype "passive")
		)
		(pad "2" smd roundrect
			(at 0.48 0 270)
			(size 0.59 0.64)
			(layers "F.Cu" "F.Mask" "F.Paste")
			(roundrect_rratio 0.25)
			(net 25 "+1V35")
			(pintype "passive")
		)
	)
	(footprint "antmicro-footprints:LGA-33_7x7mm_P0.65mm"
		(layer "F.Cu")
		(at 159.1625 170.825 180)
		(property "Reference" "U31"
			(at 5.2875 3.825 180)
			(layer "F.SilkS")
			(effects
				(font
					(size 0.7 0.7)
					(thickness 0.15)
				)
				(justify left bottom)
			)
		)
		(property "Value" "MPM54304GMN"
			(at -3.5 0.3 180)
			(layer "F.Fab")
			(effects
				(font
					(size 0.7 0.7)
					(thickness 0.15)
				)
				(justify left bottom)
			)
		)
		(property "Description" "DC-DC Switching Synchronous Step-Down Regulator, Multi Output, 4-16V in, 1V/3.3V, 4.2/3A out, LGA33"
			(at 0 0 180)
			(layer "F.Fab")
			(hide yes)
			(effects
				(font
					(size 1.27 1.27)
					(thickness 0.15)
				)
			)
		)
		(property "Author" "Antmicro"
			(at 318.325 341.65 0)
			(layer "F.Fab")
			(hide yes)
			(effects
				(font
					(size 1 1)
					(thickness 0.15)
				)
			)
		)
		(property "License" "Apache-2.0"
			(at 318.325 341.65 0)
			(layer "F.Fab")
			(hide yes)
			(effects
				(font
					(size 1 1)
					(thickness 0.15)
				)
			)
		)
		(property "MPN" "MPM54304GMN-0000"
			(at 318.325 341.65 0)
			(layer "F.Fab")
			(hide yes)
			(effects
				(font
					(size 1 1)
					(thickness 0.15)
				)
			)
		)
		(property "Manufacturer" "Monolithic Power Systems"
			(at 318.325 341.65 0)
			(layer "F.Fab")
			(hide yes)
			(effects
				(font
					(size 1 1)
					(thickness 0.15)
				)
			)
		)
		(sheetname "DC-DC Converters")
		(sheetfile "dc-dc.kicad_sch")
		(solder_paste_margin_ratio -0.1)
		(attr smd)
		(fp_line
			(start 3.648 3.648)
			(end 3.648 2.922)
			(stroke
				(width 0.15)
				(type solid)
			)
			(layer "F.SilkS")
		)
		(fp_line
			(start 3.648 -3.65)
			(end 3.648 -2.926)
			(stroke
				(width 0.15)
				(type solid)
			)
			(layer "F.SilkS")
		)
		(fp_line
			(start 2.922 3.648)
			(end 3.648 3.648)
			(stroke
				(width 0.15)
				(type solid)
			)
			(layer "F.SilkS")
		)
		(fp_line
			(start 2.922 -3.65)
			(end 3.648 -3.65)
			(stroke
				(width 0.15)
				(type solid)
			)
			(layer "F.SilkS")
		)
		(fp_line
			(start -2.926 3.648)
			(end -3.65 3.648)
			(stroke
				(width 0.15)
				(type solid)
			)
			(layer "F.SilkS")
		)
		(fp_line
			(start -3.65 3.648)
			(end -3.65 2.922)
			(stroke
				(width 0.15)
				(type solid)
			)
			(layer "F.SilkS")
		)
		(fp_line
			(start -3.665 -2.928)
			(end -3.665 -3.653)
			(stroke
				(width 0.15)
				(type solid)
			)
			(layer "F.SilkS")
		)
		(fp_line
			(start -3.665 -3.653)
			(end -2.94 -3.653)
			(stroke
				(width 0.15)
				(type solid)
			)
			(layer "F.SilkS")
		)
		(fp_circle
			(center -3.8 -1.925)
			(end -3.75 -1.925)
			(stroke
				(width 0.15)
				(type solid)
			)
			(fill yes)
			(layer "F.SilkS")
		)
		(fp_rect
			(start -4 -4)
			(end 3.999 3.999)
			(stroke
				(width 0.05)
				(type solid)
			)
			(fill no)
			(layer "F.CrtYd")
		)
		(fp_line
			(start 3.499 3.499)
			(end 3.499 -3.5)
			(stroke
				(width 0.15)
				(type solid)
			)
			(layer "F.Fab")
		)
		(fp_line
			(start 3.499 -3.5)
			(end -3.5 -3.5)
			(stroke
				(width 0.15)
				(type solid)
			)
			(layer "F.Fab")
		)
		(fp_line
			(start -3.101 -3.5)
			(end -3.5 -3.101)
			(stroke
				(width 0.15)
				(type solid)
			)
			(layer "F.Fab")
		)
		(fp_line
			(start -3.5 3.499)
			(end 3.499 3.499)
			(stroke
				(width 0.15)
				(type solid)
			)
			(layer "F.Fab")
		)
		(fp_line
			(start -3.5 -3.5)
			(end -3.5 3.499)
			(stroke
				(width 0.15)
				(type solid)
			)
			(layer "F.Fab")
		)
		(pad "1" smd rect
			(at -3.138 -1.625 270)
			(size 0.3 1.125)
			(layers "F.Cu" "F.Mask" "F.Paste")
			(net 737 "/DC-DC Converters/1V2_local")
			(pinfunction "VOUT3")
			(pintype "power_out")
		)
		(pad "2" smd rect
			(at -3.138 -0.975 270)
			(size 0.3 1.125)
			(layers "F.Cu" "F.Mask" "F.Paste")
			(net 1 "GND")
			(pinfunction "GND")
			(pintype "passive")
		)
		(pad "3" smd rect
			(at -3.138 -0.328 270)
			(size 0.3 1.125)
			(layers "F.Cu" "F.Mask" "F.Paste")
			(net 1336 "/I2C.SDA")
			(pinfunction "SDA")
			(pintype "bidirectional")
		)
		(pad "4" smd rect
			(at -3.138 0.325 270)
			(size 0.3 1.125)
			(layers "F.Cu" "F.Mask" "F.Paste")
			(net 1394 "/I2C.QDCDC1_SCL")
			(pinfunction "SCL")
			(pintype "input")
		)
		(pad "5" smd rect
			(at -3.138 0.972 270)
			(size 0.3 1.125)
			(layers "F.Cu" "F.Mask" "F.Paste")
			(net 1 "GND")
			(pinfunction "GND")
			(pintype "passive")
		)
		(pad "6" smd rect
			(at -3.138 1.624 270)
			(size 0.3 1.125)
			(layers "F.Cu" "F.Mask" "F.Paste")
			(net 960 "/DC-DC Converters/FB2")
			(pinfunction "FB2")
			(pintype "input")
		)
		(pad "7" smd rect
			(at -2.926 3.136)
			(size 0.3 1.125)
			(layers "F.Cu" "F.Mask" "F.Paste")
			(net 1 "GND")
			(pinfunction "GND")
			(pintype "passive")
		)
		(pad "8" smd rect
			(at -2.275 3.136)
			(size 0.3 1.125)
			(layers "F.Cu" "F.Mask" "F.Paste")
			(net 734 "/DC-DC Converters/1V8_local")
			(pinfunction "VOUT2")
			(pintype "power_out")
		)
		(pad "9" smd rect
			(at -1.625 3.136 180)
			(size 0.3 1.125)
			(layers "F.Cu" "F.Mask" "F.Paste")
			(net 734 "/DC-DC Converters/1V8_local")
			(pinfunction "VOUT2")
			(pintype "passive")
		)
		(pad "10" smd rect
			(at -0.975 3.136 180)
			(size 0.3 1.125)
			(layers "F.Cu" "F.Mask" "F.Paste")
			(net 1 "GND")
			(pinfunction "GND")
			(pintype "passive")
		)
		(pad "11" smd rect
			(at -0.328 3.136 180)
			(size 0.3 1.125)
			(layers "F.Cu" "F.Mask" "F.Paste")
			(net 1405 "unconnected-(U31-SW2-Pad11)")
			(pinfunction "SW2")
			(pintype "power_out+no_connect")
		)
		(pad "12" smd rect
			(at 0.325 3.136 180)
			(size 0.3 1.125)
			(layers "F.Cu" "F.Mask" "F.Paste")
			(net 1406 "unconnected-(U31-SW1-Pad12)")
			(pinfunction "SW1")
			(pintype "power_out+no_connect")
		)
		(pad "13" smd rect
			(at 0.972 3.136 180)
			(size 0.3 1.125)
			(layers "F.Cu" "F.Mask" "F.Paste")
			(net 1 "GND")
			(pinfunction "GND")
			(pintype "passive")
		)
		(pad "14" smd rect
			(at 1.624 3.136 180)
			(size 0.3 1.125)
			(layers "F.Cu" "F.Mask" "F.Paste")
			(net 733 "/DC-DC Converters/MGTAVCC_local")
			(pinfunction "VOUT1")
			(pintype "power_out")
		)
		(pad "15" smd rect
			(at 2.273 3.136 180)
			(size 0.3 1.125)
			(layers "F.Cu" "F.Mask" "F.Paste")
			(net 733 "/DC-DC Converters/MGTAVCC_local")
			(pinfunction "VOUT1")
			(pintype "passive")
		)
		(pad "16" smd rect
			(at 2.922 3.136 180)
			(size 0.3 1.125)
			(layers "F.Cu" "F.Mask" "F.Paste")
			(net 1 "GND")
			(pinfunction "GND")
			(pintype "passive")
		)
		(pad "17" smd rect
			(at 3.136 1.624 270)
			(size 0.3 1.125)
			(layers "F.Cu" "F.Mask" "F.Paste")
			(net 1 "GND")
			(pinfunction "SGND1")
			(pintype "power_out")
		)
		(pad "18" smd rect
			(at 3.136 0.972 270)
			(size 0.3 1.125)
			(layers "F.Cu" "F.Mask" "F.Paste")
			(net 959 "/DC-DC Converters/FB1")
			(pinfunction "FB1")
			(pintype "input")
		)
		(pad "19" smd rect
			(at 3.136 0.325 270)
			(size 0.3 1.125)
			(layers "F.Cu" "F.Mask" "F.Paste")
			(net 967 "/DC-DC Converters/EN2")
			(pinfunction "EN/SYNCI")
			(pintype "input")
		)
		(pad "20" smd rect
			(at 3.136 -0.328 270)
			(size 0.3 1.125)
			(layers "F.Cu" "F.Mask" "F.Paste")
			(net 1 "GND")
			(pinfunction "GND")
			(pintype "passive")
		)
		(pad "21" smd rect
			(at 3.136 -0.975 270)
			(size 0.3 1.125)
			(layers "F.Cu" "F.Mask" "F.Paste")
			(net 1 "GND")
			(pinfunction "GND")
			(pintype "passive")
		)
		(pad "22" smd rect
			(at 3.136 -1.625 270)
			(size 0.3 1.125)
			(layers "F.Cu" "F.Mask" "F.Paste")
			(net 738 "/DC-DC Converters/1V7_local")
			(pinfunction "VOUT4")
			(pintype "power_out")
		)
		(pad "23" smd rect
			(at 2.922 -3.138)
			(size 0.3 1.125)
			(layers "F.Cu" "F.Mask" "F.Paste")
			(net 738 "/DC-DC Converters/1V7_local")
			(pinfunction "VOUT4")
			(pintype "passive")
		)
		(pad "24" smd rect
			(at 2.273 -3.138)
			(size 0.3 1.125)
			(layers "F.Cu" "F.Mask" "F.Paste")
			(net 963 "/DC-DC Converters/FB4")
			(pinfunction "FB4")
			(pintype "input")
		)
		(pad "25" smd rect
			(at 1.624 -3.138 180)
			(size 0.3 1.125)
			(layers "F.Cu" "F.Mask" "F.Paste")
			(net 731 "/DC-DC Converters/QDCDC1_VCC")
			(pinfunction "VCC")
			(pintype "input")
		)
		(pad "26" smd rect
			(at 0.972 -3.138 180)
			(size 0.3 1.125)
			(layers "F.Cu" "F.Mask" "F.Paste")
			(net 1413 "/SUP_MCU.PG_1V2")
			(pinfunction "GPIO")
			(pintype "input")
		)
		(pad "27" smd rect
			(at 0.325 -3.138 180)
			(size 0.3 1.125)
			(layers "F.Cu" "F.Mask" "F.Paste")
			(net 1 "GND")
			(pinfunction "GND")
			(pintype "passive")
		)
		(pad "28" smd rect
			(at -0.328 -3.138 180)
			(size 0.3 1.125)
			(layers "F.Cu" "F.Mask" "F.Paste")
			(net 702 "VDC")
			(pinfunction "VIN")
			(pintype "input")
		)
		(pad "29" smd rect
			(at -0.975 -3.138 180)
			(size 0.3 1.125)
			(layers "F.Cu" "F.Mask" "F.Paste")
			(net 702 "VDC")
			(pinfunction "VIN")
			(pintype "passive")
		)
		(pad "30" smd rect
			(at -1.625 -3.138 180)
			(size 0.3 1.125)
			(layers "F.Cu" "F.Mask" "F.Paste")
			(net 1 "GND")
			(pinfunction "SGND2")
			(pintype "power_out")
		)
		(pad "31" smd rect
			(at -2.275 -3.138 180)
			(size 0.3 1.125)
			(layers "F.Cu" "F.Mask" "F.Paste")
			(net 962 "/DC-DC Converters/FB3")
			(pinfunction "FB3")
			(pintype "input")
		)
		(pad "32" smd rect
			(at -2.926 -3.138 180)
			(size 0.3 1.125)
			(layers "F.Cu" "F.Mask" "F.Paste")
			(net 737 "/DC-DC Converters/1V2_local")
			(pinfunction "VOUT3")
			(pintype "passive")
		)
		(pad "33" smd rect
			(at -0.863 -0.863 180)
			(size 1.725 1.725)
			(layers "F.Cu" "F.Mask" "F.Paste")
			(net 1 "GND")
			(pinfunction "GND")
			(pintype "passive")
			(solder_paste_margin -0.1)
		)
		(pad "33" smd rect
			(at -0.863 0.86 180)
			(size 1.725 1.725)
			(layers "F.Cu" "F.Mask" "F.Paste")
			(net 1 "GND")
			(pinfunction "GND")
			(pintype "passive")
			(solder_paste_margin -0.1)
		)
		(pad "33" smd rect
			(at 0.86 -0.863 180)
			(size 1.725 1.725)
			(layers "F.Cu" "F.Mask" "F.Paste")
			(net 1 "GND")
			(pinfunction "GND")
			(pintype "passive")
			(solder_paste_margin -0.1)
		)
		(pad "33" smd rect
			(at 0.86 0.86 180)
			(size 1.725 1.725)
			(layers "F.Cu" "F.Mask" "F.Paste")
			(net 1 "GND")
			(pinfunction "GND")
			(pintype "passive")
			(solder_paste_margin -0.1)
		)
	)
	(footprint "antmicro-footprints:R_0402_1005Metric"
		(layer "F.Cu")
		(at 235.915 120.5 180)
		(descr "Resistor SMD 0402")
		(tags "resistor SMD 0402")
		(property "Reference" "R75"
			(at -0.735 -0.35 180)
			(layer "F.SilkS")
			(effects
				(font
					(size 0.7 0.7)
					(thickness 0.15)
				)
				(justify left bottom)
			)
		)
		(property "Value" "R_0R_0402"
			(at 0 1.4 180)
			(layer "F.Fab")
			(effects
				(font
					(size 0.7 0.7)
					(thickness 0.15)
				)
				(justify left bottom)
			)
		)
		(property "Description" "SMD Chip Resistor, Jumper, 0 ohm, 100 mW, 0402 [1005 Metric], Thick Film, General Purpose"
			(at 0 0 180)
			(layer "F.Fab")
			(hide yes)
			(effects
				(font
					(size 1.27 1.27)
					(thickness 0.15)
				)
			)
		)
		(property "Author" "Antmicro"
			(at 471.83 241 0)
			(layer "F.Fab")
			(hide yes)
			(effects
				(font
					(size 1 1)
					(thickness 0.15)
				)
			)
		)
		(property "Current" "1A"
			(at 471.83 241 0)
			(layer "F.Fab")
			(hide yes)
			(effects
				(font
					(size 1 1)
					(thickness 0.15)
				)
			)
		)
		(property "License" "Apache-2.0"
			(at 471.83 241 0)
			(layer "F.Fab")
			(hide yes)
			(effects
				(font
					(size 1 1)
					(thickness 0.15)
				)
			)
		)
		(property "MPN" "ERJ2GE0R00X"
			(at 471.83 241 0)
			(layer "F.Fab")
			(hide yes)
			(effects
				(font
					(size 1 1)
					(thickness 0.15)
				)
			)
		)
		(property "Manufacturer" "Panasonic"
			(at 471.83 241 0)
			(layer "F.Fab")
			(hide yes)
			(effects
				(font
					(size 1 1)
					(thickness 0.15)
				)
			)
		)
		(property "Tolerance" ""
			(at 471.83 241 0)
			(layer "F.Fab")
			(hide yes)
			(effects
				(font
					(size 1 1)
					(thickness 0.15)
				)
			)
		)
		(property "Val" "0R"
			(at 471.83 241 0)
			(layer "F.Fab")
			(hide yes)
			(effects
				(font
					(size 1 1)
					(thickness 0.15)
				)
			)
		)
		(sheetname "SPI Flash + SD Card")
		(sheetfile "spi-flash.kicad_sch")
		(attr smd)
		(fp_rect
			(start -0.925 -0.47)
			(end 0.925 0.47)
			(stroke
				(width 0.05)
				(type default)
			)
			(fill no)
			(layer "F.CrtYd")
		)
		(fp_rect
			(start -0.5 -0.25)
			(end 0.5 0.25)
			(stroke
				(width 0.15)
				(type solid)
			)
			(fill no)
			(layer "F.Fab")
		)
		(pad "1" smd roundrect
			(at -0.48 0 180)
			(size 0.59 0.64)
			(layers "F.Cu" "F.Mask" "F.Paste")
			(roundrect_rratio 0.25)
			(net 56 "/FPGA Bank 14 & 15/SYSTEM_FLASH.CLK")
			(pintype "passive")
		)
		(pad "2" smd roundrect
			(at 0.48 0 180)
			(size 0.59 0.64)
			(layers "F.Cu" "F.Mask" "F.Paste")
			(roundrect_rratio 0.25)
			(net 895 "/SPI Flash + SD Card/SYSTEM_FLASH_CLK")
			(pintype "passive")
		)
	)
	(footprint "antmicro-footprints:R_0402_1005Metric"
		(layer "F.Cu")
		(at 214.9 165.4 90)
		(descr "Resistor SMD 0402")
		(tags "resistor SMD 0402")
		(property "Reference" "R84"
			(at -0.4 -5.25 90)
			(layer "F.SilkS")
			(effects
				(font
					(size 0.7 0.7)
					(thickness 0.15)
				)
				(justify left bottom)
			)
		)
		(property "Value" "R_0R_0402"
			(at 0 1.4 90)
			(layer "F.Fab")
			(effects
				(font
					(size 0.7 0.7)
					(thickness 0.15)
				)
				(justify left bottom)
			)
		)
		(property "Description" "SMD Chip Resistor, Jumper, 0 ohm, 100 mW, 0402 [1005 Metric], Thick Film, General Purpose"
			(at 0 0 90)
			(layer "F.Fab")
			(hide yes)
			(effects
				(font
					(size 1.27 1.27)
					(thickness 0.15)
				)
			)
		)
		(property "Author" "Antmicro"
			(at 380.3 -49.5 0)
			(layer "F.Fab")
			(hide yes)
			(effects
				(font
					(size 1 1)
					(thickness 0.15)
				)
			)
		)
		(property "Current" "1A"
			(at 380.3 -49.5 0)
			(layer "F.Fab")
			(hide yes)
			(effects
				(font
					(size 1 1)
					(thickness 0.15)
				)
			)
		)
		(property "License" "Apache-2.0"
			(at 380.3 -49.5 0)
			(layer "F.Fab")
			(hide yes)
			(effects
				(font
					(size 1 1)
					(thickness 0.15)
				)
			)
		)
		(property "MPN" "ERJ2GE0R00X"
			(at 380.3 -49.5 0)
			(layer "F.Fab")
			(hide yes)
			(effects
				(font
					(size 1 1)
					(thickness 0.15)
				)
			)
		)
		(property "Manufacturer" "Panasonic"
			(at 380.3 -49.5 0)
			(layer "F.Fab")
			(hide yes)
			(effects
				(font
					(size 1 1)
					(thickness 0.15)
				)
			)
		)
		(property "Tolerance" ""
			(at 380.3 -49.5 0)
			(layer "F.Fab")
			(hide yes)
			(effects
				(font
					(size 1 1)
					(thickness 0.15)
				)
			)
		)
		(property "Val" "0R"
			(at 380.3 -49.5 0)
			(layer "F.Fab")
			(hide yes)
			(effects
				(font
					(size 1 1)
					(thickness 0.15)
				)
			)
		)
		(sheetname "SPI Flash + SD Card")
		(sheetfile "spi-flash.kicad_sch")
		(attr smd)
		(fp_rect
			(start -0.925 -0.47)
			(end 0.925 0.47)
			(stroke
				(width 0.05)
				(type default)
			)
			(fill no)
			(layer "F.CrtYd")
		)
		(fp_rect
			(start -0.5 -0.25)
			(end 0.5 0.25)
			(stroke
				(width 0.15)
				(type solid)
			)
			(fill no)
			(layer "F.Fab")
		)
		(pad "1" smd roundrect
			(at -0.48 0 90)
			(size 0.59 0.64)
			(layers "F.Cu" "F.Mask" "F.Paste")
			(roundrect_rratio 0.25)
			(net 404 "/FPGA Bank 33 & 34/USR_FLASH_0.DQ2")
			(pintype "passive")
		)
		(pad "2" smd roundrect
			(at 0.48 0 90)
			(size 0.59 0.64)
			(layers "F.Cu" "F.Mask" "F.Paste")
			(roundrect_rratio 0.25)
			(net 904 "/SPI Flash + SD Card/USR_FLASH_0_DQ2")
			(pintype "passive")
		)
	)
	(footprint "antmicro-footprints:R_0402_1005Metric"
		(layer "F.Cu")
		(at 235.9 113.6 180)
		(descr "Resistor SMD 0402")
		(tags "resistor SMD 0402")
		(property "Reference" "R100"
			(at -0.8 -0.35 180)
			(layer "F.SilkS")
			(effects
				(font
					(size 0.7 0.7)
					(thickness 0.15)
				)
				(justify left bottom)
			)
		)
		(property "Value" "R_0R_0402"
			(at 0 1.4 180)
			(layer "F.Fab")
			(effects
				(font
					(size 0.7 0.7)
					(thickness 0.15)
				)
				(justify left bottom)
			)
		)
		(property "Description" "SMD Chip Resistor, Jumper, 0 ohm, 100 mW, 0402 [1005 Metric], Thick Film, General Purpose"
			(at 0 0 180)
			(layer "F.Fab")
			(hide yes)
			(effects
				(font
					(size 1.27 1.27)
					(thickness 0.15)
				)
			)
		)
		(property "Author" "Antmicro"
			(at 471.8 227.2 0)
			(layer "F.Fab")
			(hide yes)
			(effects
				(font
					(size 1 1)
					(thickness 0.15)
				)
			)
		)
		(property "Current" "1A"
			(at 471.8 227.2 0)
			(layer "F.Fab")
			(hide yes)
			(effects
				(font
					(size 1 1)
					(thickness 0.15)
				)
			)
		)
		(property "License" "Apache-2.0"
			(at 471.8 227.2 0)
			(layer "F.Fab")
			(hide yes)
			(effects
				(font
					(size 1 1)
					(thickness 0.15)
				)
			)
		)
		(property "MPN" "ERJ2GE0R00X"
			(at 471.8 227.2 0)
			(layer "F.Fab")
			(hide yes)
			(effects
				(font
					(size 1 1)
					(thickness 0.15)
				)
			)
		)
		(property "Manufacturer" "Panasonic"
			(at 471.8 227.2 0)
			(layer "F.Fab")
			(hide yes)
			(effects
				(font
					(size 1 1)
					(thickness 0.15)
				)
			)
		)
		(property "Tolerance" ""
			(at 471.8 227.2 0)
			(layer "F.Fab")
			(hide yes)
			(effects
				(font
					(size 1 1)
					(thickness 0.15)
				)
			)
		)
		(property "Val" "0R"
			(at 471.8 227.2 0)
			(layer "F.Fab")
			(hide yes)
			(effects
				(font
					(size 1 1)
					(thickness 0.15)
				)
			)
		)
		(sheetname "SPI Flash + SD Card")
		(sheetfile "spi-flash.kicad_sch")
		(attr smd)
		(fp_rect
			(start -0.925 -0.47)
			(end 0.925 0.47)
			(stroke
				(width 0.05)
				(type default)
			)
			(fill no)
			(layer "F.CrtYd")
		)
		(fp_rect
			(start -0.5 -0.25)
			(end 0.5 0.25)
			(stroke
				(width 0.15)
				(type solid)
			)
			(fill no)
			(layer "F.Fab")
		)
		(pad "1" smd roundrect
			(at -0.48 0 180)
			(size 0.59 0.64)
			(layers "F.Cu" "F.Mask" "F.Paste")
			(roundrect_rratio 0.25)
			(net 427 "/FPGA Bank 16 & 17/USR_FLASH_1.CLK")
			(pintype "passive")
		)
		(pad "2" smd roundrect
			(at 0.48 0 180)
			(size 0.59 0.64)
			(layers "F.Cu" "F.Mask" "F.Paste")
			(roundrect_rratio 0.25)
			(net 907 "/SPI Flash + SD Card/USR_FLASH_1_CLK")
			(pintype "passive")
		)
	)
	(footprint "antmicro-footprints:C_0603_1608Metric"
		(layer "F.Cu")
		(at 160.55 164.05)
		(descr "Capacitor SMD 0603")
		(tags "capacitor 0603")
		(property "Reference" "C327"
			(at 0.95 0.4 0)
			(layer "F.SilkS")
			(effects
				(font
					(size 0.7 0.7)
					(thickness 0.15)
				)
				(justify left bottom)
			)
		)
		(property "Value" "C_22u_0603"
			(at 0 1.6 0)
			(layer "F.Fab")
			(effects
				(font
					(size 0.7 0.7)
					(thickness 0.15)
				)
				(justify left bottom)
			)
		)
		(property "Description" "SMD Multilayer Ceramic Capacitor, 22 µF, 6.3 V, 0603 [1608 Metric], ± 20%, X5R, GRM Series"
			(at 0 0 0)
			(layer "F.Fab")
			(hide yes)
			(effects
				(font
					(size 1.27 1.27)
					(thickness 0.15)
				)
			)
		)
		(property "Author" "Antmicro"
			(at 0 0 0)
			(layer "F.Fab")
			(hide yes)
			(effects
				(font
					(size 1 1)
					(thickness 0.15)
				)
			)
		)
		(property "Dielectric" ""
			(at 0 0 0)
			(layer "F.Fab")
			(hide yes)
			(effects
				(font
					(size 1 1)
					(thickness 0.15)
				)
			)
		)
		(property "License" "Apache-2.0"
			(at 0 0 0)
			(layer "F.Fab")
			(hide yes)
			(effects
				(font
					(size 1 1)
					(thickness 0.15)
				)
			)
		)
		(property "MPN" "GRM188R60J226MEA0D"
			(at 0 0 0)
			(layer "F.Fab")
			(hide yes)
			(effects
				(font
					(size 1 1)
					(thickness 0.15)
				)
			)
		)
		(property "Manufacturer" "Murata"
			(at 0 0 0)
			(layer "F.Fab")
			(hide yes)
			(effects
				(font
					(size 1 1)
					(thickness 0.15)
				)
			)
		)
		(property "Val" "22u"
			(at 0 0 0)
			(layer "F.Fab")
			(hide yes)
			(effects
				(font
					(size 1 1)
					(thickness 0.15)
				)
			)
		)
		(property "Voltage" ""
			(at 0 0 0)
			(layer "F.Fab")
			(hide yes)
			(effects
				(font
					(size 1 1)
					(thickness 0.15)
				)
			)
		)
		(sheetname "DC-DC Converters")
		(sheetfile "dc-dc.kicad_sch")
		(attr smd)
		(fp_line
			(start -0.15 -0.4)
			(end 0.15 -0.4)
			(stroke
				(width 0.15)
				(type solid)
			)
			(layer "F.SilkS")
		)
		(fp_line
			(start -0.15 0.4)
			(end 0.15 0.4)
			(stroke
				(width 0.15)
				(type solid)
			)
			(layer "F.SilkS")
		)
		(fp_rect
			(start -1.25 -0.65)
			(end 1.25 0.65)
			(stroke
				(width 0.05)
				(type solid)
			)
			(fill no)
			(layer "F.CrtYd")
		)
		(fp_rect
			(start -0.8 -0.4)
			(end 0.8 0.4)
			(stroke
				(width 0.15)
				(type solid)
			)
			(fill no)
			(layer "F.Fab")
		)
		(pad "1" smd roundrect
			(at -0.7 0)
			(size 0.8 1)
			(layers "F.Cu" "F.Mask" "F.Paste")
			(roundrect_rratio 0.2)
			(net 1 "GND")
			(pintype "passive")
		)
		(pad "2" smd roundrect
			(at 0.7 0)
			(size 0.8 1)
			(layers "F.Cu" "F.Mask" "F.Paste")
			(roundrect_rratio 0.2)
			(net 734 "/DC-DC Converters/1V8_local")
			(pintype "passive")
		)
	)
	(footprint "antmicro-footprints:DHVQFN-14-1EP_2.5x3mm"
		(layer "F.Cu")
		(at 239.3 130.8 180)
		(property "Reference" "U22"
			(at -1.375 1.65 270)
			(layer "F.SilkS")
			(effects
				(font
					(size 0.7 0.7)
					(thickness 0.15)
				)
				(justify left bottom)
			)
		)
		(property "Value" "TXU0304BQAR"
			(at 0 2.898 180)
			(layer "F.Fab")
			(effects
				(font
					(size 0.7 0.7)
					(thickness 0.15)
				)
				(justify left bottom)
			)
		)
		(property "Description" "Logic translator/level shifter"
			(at 0 0 180)
			(layer "F.Fab")
			(hide yes)
			(effects
				(font
					(size 1.27 1.27)
					(thickness 0.15)
				)
			)
		)
		(property "Author" "Antmicro"
			(at 478.6 261.6 0)
			(layer "F.Fab")
			(hide yes)
			(effects
				(font
					(size 1 1)
					(thickness 0.15)
				)
			)
		)
		(property "License" "Apache-2.0"
			(at 478.6 261.6 0)
			(layer "F.Fab")
			(hide yes)
			(effects
				(font
					(size 1 1)
					(thickness 0.15)
				)
			)
		)
		(property "MPN" "TXU0304BQAR"
			(at 478.6 261.6 0)
			(layer "F.Fab")
			(hide yes)
			(effects
				(font
					(size 1 1)
					(thickness 0.15)
				)
			)
		)
		(property "Manufacturer" "Texas Instruments"
			(at 478.6 261.6 0)
			(layer "F.Fab")
			(hide yes)
			(effects
				(font
					(size 1 1)
					(thickness 0.15)
				)
			)
		)
		(sheetname "USB PHY")
		(sheetfile "usb-phy.kicad_sch")
		(attr smd)
		(fp_line
			(start 1.35 1.6)
			(end 1.35 1.249)
			(stroke
				(width 0.15)
				(type solid)
			)
			(layer "F.SilkS")
		)
		(fp_line
			(start 1.35 -1.601)
			(end 1.35 -1.25)
			(stroke
				(width 0.15)
				(type solid)
			)
			(layer "F.SilkS")
		)
		(fp_line
			(start 1.35 -1.601)
			(end 0.494 -1.601)
			(stroke
				(width 0.15)
				(type solid)
			)
			(layer "F.SilkS")
		)
		(fp_line
			(start 0.494 1.6)
			(end 1.35 1.6)
			(stroke
				(width 0.15)
				(type solid)
			)
			(layer "F.SilkS")
		)
		(fp_line
			(start -1.35 -1.601)
			(end -1.35 -1.25)
			(stroke
				(width 0.15)
				(type solid)
			)
			(layer "F.SilkS")
		)
		(fp_line
			(start -1.351 1.6)
			(end -0.5 1.6)
			(stroke
				(width 0.15)
				(type solid)
			)
			(layer "F.SilkS")
		)
		(fp_line
			(start -1.351 1.6)
			(end -1.351 1.249)
			(stroke
				(width 0.15)
				(type solid)
			)
			(layer "F.SilkS")
		)
		(fp_line
			(start -1.351 -1.601)
			(end -0.5 -1.601)
			(stroke
				(width 0.15)
				(type solid)
			)
			(layer "F.SilkS")
		)
		(fp_circle
			(center -0.7 -1.85)
			(end -0.653 -1.85)
			(stroke
				(width 0.15)
				(type solid)
			)
			(fill yes)
			(layer "F.SilkS")
		)
		(fp_rect
			(start -1.85 -2)
			(end 1.8 1.95)
			(stroke
				(width 0.05)
				(type solid)
			)
			(fill no)
			(layer "F.CrtYd")
		)
		(fp_line
			(start 1.249 1.499)
			(end -1.25 1.499)
			(stroke
				(width 0.15)
				(type solid)
			)
			(layer "F.Fab")
		)
		(fp_line
			(start 1.249 -1.5)
			(end 1.249 1.499)
			(stroke
				(width 0.15)
				(type solid)
			)
			(layer "F.Fab")
		)
		(fp_line
			(start -1 -1.5)
			(end 1.249 -1.5)
			(stroke
				(width 0.15)
				(type solid)
			)
			(layer "F.Fab")
		)
		(fp_line
			(start -1.25 1.499)
			(end -1.25 -1.25)
			(stroke
				(width 0.15)
				(type solid)
			)
			(layer "F.Fab")
		)
		(fp_line
			(start -1.25 -1.25)
			(end -1 -1.5)
			(stroke
				(width 0.15)
				(type solid)
			)
			(layer "F.Fab")
		)
		(pad "1" smd oval
			(at -0.25 -1.5 180)
			(size 0.3 0.8)
			(layers "F.Cu" "F.Mask" "F.Paste")
			(net 707 "/USB PHY/FTDI_3V3")
			(pinfunction "VCCA")
			(pintype "power_in")
		)
		(pad "2" smd oval
			(at -1.25 -1 270)
			(size 0.3 0.8)
			(layers "F.Cu" "F.Mask" "F.Paste")
			(net 1015 "/USB PHY/FTDI_JTAG_TCK")
			(pinfunction "A1")
			(pintype "input")
		)
		(pad "3" smd oval
			(at -1.25 -0.5 270)
			(size 0.3 0.8)
			(layers "F.Cu" "F.Mask" "F.Paste")
			(net 1018 "/USB PHY/FTDI_JTAG_TMS")
			(pinfunction "A2")
			(pintype "input")
		)
		(pad "4" smd oval
			(at -1.25 0 270)
			(size 0.3 0.8)
			(layers "F.Cu" "F.Mask" "F.Paste")
			(net 1016 "/USB PHY/FTDI_JTAG_TDI")
			(pinfunction "A3")
			(pintype "input")
		)
		(pad "5" smd oval
			(at -1.25 0.494 270)
			(size 0.3 0.8)
			(layers "F.Cu" "F.Mask" "F.Paste")
			(net 1017 "/USB PHY/FTDI_JTAG_TDO")
			(pinfunction "A4Y")
			(pintype "output")
		)
		(pad "6" smd oval
			(at -1.25 0.994 270)
			(size 0.3 0.8)
			(layers "F.Cu" "F.Mask" "F.Paste")
			(net 1206 "unconnected-(U22-NC-Pad6)")
			(pinfunction "NC")
			(pintype "no_connect")
		)
		(pad "7" smd oval
			(at -0.25 1.499 180)
			(size 0.3 0.8)
			(layers "F.Cu" "F.Mask" "F.Paste")
			(net 1 "GND")
			(pinfunction "GND")
			(pintype "passive")
		)
		(pad "8" smd oval
			(at 0.244 1.499 180)
			(size 0.3 0.8)
			(layers "F.Cu" "F.Mask" "F.Paste")
			(net 799 "FTDI_DIS")
			(pinfunction "OE")
			(pintype "tri_state")
		)
		(pad "9" smd oval
			(at 1.249 0.994 270)
			(size 0.3 0.8)
			(layers "F.Cu" "F.Mask" "F.Paste")
			(net 1207 "unconnected-(U22-NC-Pad9)")
			(pinfunction "NC")
			(pintype "no_connect")
		)
		(pad "10" smd oval
			(at 1.249 0.494 270)
			(size 0.3 0.8)
			(layers "F.Cu" "F.Mask" "F.Paste")
			(net 371 "Net-(U22-B4)")
			(pinfunction "B4")
			(pintype "input")
		)
		(pad "11" smd oval
			(at 1.249 0 270)
			(size 0.3 0.8)
			(layers "F.Cu" "F.Mask" "F.Paste")
			(net 370 "Net-(U22-B3Y)")
			(pinfunction "B3Y")
			(pintype "output")
		)
		(pad "12" smd oval
			(at 1.249 -0.5 270)
			(size 0.3 0.8)
			(layers "F.Cu" "F.Mask" "F.Paste")
			(net 369 "Net-(U22-B2Y)")
			(pinfunction "B2Y")
			(pintype "output")
		)
		(pad "13" smd oval
			(at 1.249 -1 270)
			(size 0.3 0.8)
			(layers "F.Cu" "F.Mask" "F.Paste")
			(net 368 "Net-(U22-B1Y)")
			(pinfunction "B1Y")
			(pintype "output")
		)
		(pad "14" smd oval
			(at 0.244 -1.5 180)
			(size 0.3 0.8)
			(layers "F.Cu" "F.Mask" "F.Paste")
			(net 24 "+3V3")
			(pinfunction "VCCB")
			(pintype "power_in")
		)
		(pad "15" smd rect
			(at 0 0 180)
			(size 1 1.5)
			(layers "F.Cu" "F.Mask" "F.Paste")
			(net 1 "GND")
			(pinfunction "GND")
			(pintype "power_in")
		)
	)
	(footprint "antmicro-footprints:R_0402_1005Metric"
		(layer "F.Cu")
		(at 232.6 161.75 90)
		(descr "Resistor SMD 0402")
		(tags "resistor SMD 0402")
		(property "Reference" "R45"
			(at -2.95 0.45 90)
			(layer "F.SilkS")
			(effects
				(font
					(size 0.7 0.7)
					(thickness 0.15)
				)
				(justify left bottom)
			)
		)
		(property "Value" "R_1k_0402"
			(at 0 1.4 90)
			(layer "F.Fab")
			(effects
				(font
					(size 0.7 0.7)
					(thickness 0.15)
				)
				(justify left bottom)
			)
		)
		(property "Description" "SMD Chip Resistor, 1 kohm, ± 1%, 63 mW, 0402 [1005 Metric], Thick Film, General Purpose"
			(at 0 0 90)
			(layer "F.Fab")
			(hide yes)
			(effects
				(font
					(size 1.27 1.27)
					(thickness 0.15)
				)
			)
		)
		(property "Author" "Antmicro"
			(at 394.35 -70.85 0)
			(layer "F.Fab")
			(hide yes)
			(effects
				(font
					(size 1 1)
					(thickness 0.15)
				)
			)
		)
		(property "License" "Apache-2.0"
			(at 394.35 -70.85 0)
			(layer "F.Fab")
			(hide yes)
			(effects
				(font
					(size 1 1)
					(thickness 0.15)
				)
			)
		)
		(property "MPN" "CR0402-FX-1001GLF"
			(at 394.35 -70.85 0)
			(layer "F.Fab")
			(hide yes)
			(effects
				(font
					(size 1 1)
					(thickness 0.15)
				)
			)
		)
		(property "Manufacturer" "Bourns"
			(at 394.35 -70.85 0)
			(layer "F.Fab")
			(hide yes)
			(effects
				(font
					(size 1 1)
					(thickness 0.15)
				)
			)
		)
		(property "Tolerance" "1%"
			(at 394.35 -70.85 0)
			(layer "F.Fab")
			(hide yes)
			(effects
				(font
					(size 1 1)
					(thickness 0.15)
				)
			)
		)
		(property "Val" "1k"
			(at 394.35 -70.85 0)
			(layer "F.Fab")
			(hide yes)
			(effects
				(font
					(size 1 1)
					(thickness 0.15)
				)
			)
		)
		(sheetname "Power supply")
		(sheetfile "power-supply.kicad_sch")
		(attr smd)
		(fp_rect
			(start -0.925 -0.47)
			(end 0.925 0.47)
			(stroke
				(width 0.05)
				(type default)
			)
			(fill no)
			(layer "F.CrtYd")
		)
		(fp_rect
			(start -0.5 -0.25)
			(end 0.5 0.25)
			(stroke
				(width 0.15)
				(type solid)
			)
			(fill no)
			(layer "F.Fab")
		)
		(pad "1" smd roundrect
			(at -0.48 0 90)
			(size 0.59 0.64)
			(layers "F.Cu" "F.Mask" "F.Paste")
			(roundrect_rratio 0.25)
			(net 880 "/Power supply/VBUS_DIS")
			(pintype "passive")
		)
		(pad "2" smd roundrect
			(at 0.48 0 90)
			(size 0.59 0.64)
			(layers "F.Cu" "F.Mask" "F.Paste")
			(roundrect_rratio 0.25)
			(net 704 "/Power supply/USB_DBG_PD.VBUS")
			(pintype "passive")
		)
	)
	(footprint "antmicro-footprints:C_0402_1005Metric"
		(layer "F.Cu")
		(at 225.7 147.5 90)
		(descr "Capacitor SMD 0402")
		(tags "capacitor SMD 0402")
		(property "Reference" "C268"
			(at 0.75 0.35 90)
			(layer "F.SilkS")
			(effects
				(font
					(size 0.7 0.7)
					(thickness 0.15)
				)
				(justify left bottom)
			)
		)
		(property "Value" "C_100n_0402"
			(at 0 1.169 90)
			(layer "F.Fab")
			(effects
				(font
					(size 0.7 0.7)
					(thickness 0.15)
				)
				(justify left bottom)
			)
		)
		(property "Description" "SMD Multilayer Ceramic Capacitor, 0.1 µF, 50 V, 0402 [1005 Metric], ± 10%, X5R, GRM Series"
			(at 0 0 90)
			(layer "F.Fab")
			(hide yes)
			(effects
				(font
					(size 1.27 1.27)
					(thickness 0.15)
				)
			)
		)
		(property "Author" "Antmicro"
			(at 373.2 -78.2 0)
			(layer "F.Fab")
			(hide yes)
			(effects
				(font
					(size 1 1)
					(thickness 0.15)
				)
			)
		)
		(property "Dielectric" "X5R"
			(at 373.2 -78.2 0)
			(layer "F.Fab")
			(hide yes)
			(effects
				(font
					(size 1 1)
					(thickness 0.15)
				)
			)
		)
		(property "License" "Apache-2.0"
			(at 373.2 -78.2 0)
			(layer "F.Fab")
			(hide yes)
			(effects
				(font
					(size 1 1)
					(thickness 0.15)
				)
			)
		)
		(property "MPN" "GRM155R61H104KE14D"
			(at 373.2 -78.2 0)
			(layer "F.Fab")
			(hide yes)
			(effects
				(font
					(size 1 1)
					(thickness 0.15)
				)
			)
		)
		(property "Manufacturer" "Murata"
			(at 373.2 -78.2 0)
			(layer "F.Fab")
			(hide yes)
			(effects
				(font
					(size 1 1)
					(thickness 0.15)
				)
			)
		)
		(property "Val" "100n"
			(at 373.2 -78.2 0)
			(layer "F.Fab")
			(hide yes)
			(effects
				(font
					(size 1 1)
					(thickness 0.15)
				)
			)
		)
		(property "Voltage" "50V"
			(at 373.2 -78.2 0)
			(layer "F.Fab")
			(hide yes)
			(effects
				(font
					(size 1 1)
					(thickness 0.15)
				)
			)
		)
		(sheetname "HDMI + Ethernet")
		(sheetfile "hdmi-ethernet.kicad_sch")
		(attr smd)
		(fp_rect
			(start -0.925 -0.47)
			(end 0.925 0.47)
			(stroke
				(width 0.05)
				(type default)
			)
			(fill no)
			(layer "F.CrtYd")
		)
		(fp_line
			(start 0.504 -0.25)
			(end 0.504 0.248)
			(stroke
				(width 0.15)
				(type solid)
			)
			(layer "F.Fab")
		)
		(fp_line
			(start -0.494 -0.25)
			(end 0.504 -0.25)
			(stroke
				(width 0.15)
				(type solid)
			)
			(layer "F.Fab")
		)
		(fp_line
			(start 0.504 0.248)
			(end -0.494 0.248)
			(stroke
				(width 0.15)
				(type solid)
			)
			(layer "F.Fab")
		)
		(fp_line
			(start -0.494 0.248)
			(end -0.494 -0.25)
			(stroke
				(width 0.15)
				(type solid)
			)
			(layer "F.Fab")
		)
		(pad "1" smd roundrect
			(at -0.48 0 90)
			(size 0.59 0.64)
			(layers "F.Cu" "F.Mask" "F.Paste")
			(roundrect_rratio 0.25)
			(net 722 "/HDMI + Ethernet/ETH_VDDCR")
			(pintype "passive")
		)
		(pad "2" smd roundrect
			(at 0.48 0 90)
			(size 0.59 0.64)
			(layers "F.Cu" "F.Mask" "F.Paste")
			(roundrect_rratio 0.25)
			(net 1 "GND")
			(pintype "passive")
		)
	)
	(footprint "antmicro-footprints:R_0402_1005Metric"
		(layer "F.Cu")
		(at 161 184 90)
		(descr "Resistor SMD 0402")
		(tags "resistor SMD 0402")
		(property "Reference" "R364"
			(at 0.7 0.4 90)
			(layer "F.SilkS")
			(effects
				(font
					(size 0.7 0.7)
					(thickness 0.15)
				)
				(justify left bottom)
			)
		)
		(property "Value" "R_0R_0402"
			(at 0 1.4 90)
			(layer "F.Fab")
			(effects
				(font
					(size 0.7 0.7)
					(thickness 0.15)
				)
				(justify left bottom)
			)
		)
		(property "Description" "SMD Chip Resistor, Jumper, 0 ohm, 100 mW, 0402 [1005 Metric], Thick Film, General Purpose"
			(at 0 0 90)
			(layer "F.Fab")
			(hide yes)
			(effects
				(font
					(size 1.27 1.27)
					(thickness 0.15)
				)
			)
		)
		(property "Author" "Antmicro"
			(at 345 23 0)
			(layer "F.Fab")
			(hide yes)
			(effects
				(font
					(size 1 1)
					(thickness 0.15)
				)
			)
		)
		(property "Current" "1A"
			(at 345 23 0)
			(layer "F.Fab")
			(hide yes)
			(effects
				(font
					(size 1 1)
					(thickness 0.15)
				)
			)
		)
		(property "DNP" "DNP"
			(at 345 23 0)
			(layer "F.Fab")
			(hide yes)
			(effects
				(font
					(size 1 1)
					(thickness 0.15)
				)
			)
		)
		(property "License" "Apache-2.0"
			(at 345 23 0)
			(layer "F.Fab")
			(hide yes)
			(effects
				(font
					(size 1 1)
					(thickness 0.15)
				)
			)
		)
		(property "MPN" "ERJ2GE0R00X"
			(at 345 23 0)
			(layer "F.Fab")
			(hide yes)
			(effects
				(font
					(size 1 1)
					(thickness 0.15)
				)
			)
		)
		(property "Manufacturer" "Panasonic"
			(at 345 23 0)
			(layer "F.Fab")
			(hide yes)
			(effects
				(font
					(size 1 1)
					(thickness 0.15)
				)
			)
		)
		(property "Tolerance" ""
			(at 345 23 0)
			(layer "F.Fab")
			(hide yes)
			(effects
				(font
					(size 1 1)
					(thickness 0.15)
				)
			)
		)
		(property "Val" "0R"
			(at 345 23 0)
			(layer "F.Fab")
			(hide yes)
			(effects
				(font
					(size 1 1)
					(thickness 0.15)
				)
			)
		)
		(property "dnp" ""
			(at 345 23 0)
			(layer "F.Fab")
			(hide yes)
			(effects
				(font
					(size 1 1)
					(thickness 0.15)
				)
			)
		)
		(property "exclude_from_bom" ""
			(at 345 23 0)
			(layer "F.Fab")
			(hide yes)
			(effects
				(font
					(size 1 1)
					(thickness 0.15)
				)
			)
		)
		(sheetname "DC-DC Converters")
		(sheetfile "dc-dc.kicad_sch")
		(attr smd exclude_from_bom)
		(fp_rect
			(start -0.925 -0.47)
			(end 0.925 0.47)
			(stroke
				(width 0.05)
				(type default)
			)
			(fill no)
			(layer "F.CrtYd")
		)
		(fp_rect
			(start -0.5 -0.25)
			(end 0.5 0.25)
			(stroke
				(width 0.15)
				(type solid)
			)
			(fill no)
			(layer "F.Fab")
		)
		(pad "1" smd roundrect
			(at -0.48 0 90)
			(size 0.59 0.64)
			(layers "F.Cu" "F.Mask" "F.Paste")
			(roundrect_rratio 0.25)
			(net 577 "/DC-DC Converters/PB_CTRL.~{PB_CTRL_INT}")
			(pintype "passive")
		)
		(pad "2" smd roundrect
			(at 0.48 0 90)
			(size 0.59 0.64)
			(layers "F.Cu" "F.Mask" "F.Paste")
			(roundrect_rratio 0.25)
			(net 1340 "/SUP_MCU.SW_STATE")
			(pintype "passive")
		)
	)
	(footprint "antmicro-footprints:R_0402_1005Metric"
		(layer "F.Cu")
		(at 236 136.4)
		(descr "Resistor SMD 0402")
		(tags "resistor SMD 0402")
		(property "Reference" "R189"
			(at -1.625 -1.45 0)
			(layer "F.SilkS")
			(effects
				(font
					(size 0.7 0.7)
					(thickness 0.15)
				)
				(justify left bottom)
			)
		)
		(property "Value" "R_0R_0402"
			(at 0 1.4 0)
			(layer "F.Fab")
			(effects
				(font
					(size 0.7 0.7)
					(thickness 0.15)
				)
				(justify left bottom)
			)
		)
		(property "Description" "SMD Chip Resistor, Jumper, 0 ohm, 100 mW, 0402 [1005 Metric], Thick Film, General Purpose"
			(at 0 0 0)
			(layer "F.Fab")
			(hide yes)
			(effects
				(font
					(size 1.27 1.27)
					(thickness 0.15)
				)
			)
		)
		(property "Author" "Antmicro"
			(at 0 0 0)
			(layer "F.Fab")
			(hide yes)
			(effects
				(font
					(size 1 1)
					(thickness 0.15)
				)
			)
		)
		(property "Current" "1A"
			(at 0 0 0)
			(layer "F.Fab")
			(hide yes)
			(effects
				(font
					(size 1 1)
					(thickness 0.15)
				)
			)
		)
		(property "License" "Apache-2.0"
			(at 0 0 0)
			(layer "F.Fab")
			(hide yes)
			(effects
				(font
					(size 1 1)
					(thickness 0.15)
				)
			)
		)
		(property "MPN" "ERJ2GE0R00X"
			(at 0 0 0)
			(layer "F.Fab")
			(hide yes)
			(effects
				(font
					(size 1 1)
					(thickness 0.15)
				)
			)
		)
		(property "Manufacturer" "Panasonic"
			(at 0 0 0)
			(layer "F.Fab")
			(hide yes)
			(effects
				(font
					(size 1 1)
					(thickness 0.15)
				)
			)
		)
		(property "Tolerance" ""
			(at 0 0 0)
			(layer "F.Fab")
			(hide yes)
			(effects
				(font
					(size 1 1)
					(thickness 0.15)
				)
			)
		)
		(property "Val" "0R"
			(at 0 0 0)
			(layer "F.Fab")
			(hide yes)
			(effects
				(font
					(size 1 1)
					(thickness 0.15)
				)
			)
		)
		(sheetname "USB PHY")
		(sheetfile "usb-phy.kicad_sch")
		(attr smd)
		(fp_rect
			(start -0.925 -0.47)
			(end 0.925 0.47)
			(stroke
				(width 0.05)
				(type default)
			)
			(fill no)
			(layer "F.CrtYd")
		)
		(fp_rect
			(start -0.5 -0.25)
			(end 0.5 0.25)
			(stroke
				(width 0.15)
				(type solid)
			)
			(fill no)
			(layer "F.Fab")
		)
		(pad "1" smd roundrect
			(at -0.48 0)
			(size 0.59 0.64)
			(layers "F.Cu" "F.Mask" "F.Paste")
			(roundrect_rratio 0.25)
			(net 1336 "/I2C.SDA")
			(pintype "passive")
		)
		(pad "2" smd roundrect
			(at 0.48 0)
			(size 0.59 0.64)
			(layers "F.Cu" "F.Mask" "F.Paste")
			(roundrect_rratio 0.25)
			(net 942 "/USB PHY/FTDI_SDA_IN")
			(pintype "passive")
		)
	)
	(footprint "antmicro-footprints:C_0402_1005Metric"
		(layer "F.Cu")
		(at 203.653752 105.0365 180)
		(descr "Capacitor SMD 0402")
		(tags "capacitor SMD 0402")
		(property "Reference" "C263"
			(at -6.546248 -7.7635 0)
			(layer "F.SilkS")
			(effects
				(font
					(size 0.7 0.7)
					(thickness 0.15)
				)
				(justify right bottom)
			)
		)
		(property "Value" "C_22p_0402"
			(at 0 1.4 0)
			(layer "F.Fab")
			(effects
				(font
					(size 0.7 0.7)
					(thickness 0.15)
				)
				(justify right bottom)
			)
		)
		(property "Description" "SMD Multilayer Ceramic Capacitor, 22 pF, 50 V, 0402 [1005 Metric], ± 5%, C0G / NP0, CC Series"
			(at 0 0 180)
			(layer "F.Fab")
			(hide yes)
			(effects
				(font
					(size 1.27 1.27)
					(thickness 0.15)
				)
			)
		)
		(property "Author" "Antmicro"
			(at 407.307504 210.073 0)
			(layer "F.Fab")
			(hide yes)
			(effects
				(font
					(size 1 1)
					(thickness 0.15)
				)
			)
		)
		(property "Dielectric" ""
			(at 407.307504 210.073 0)
			(layer "F.Fab")
			(hide yes)
			(effects
				(font
					(size 1 1)
					(thickness 0.15)
				)
			)
		)
		(property "License" "Apache-2.0"
			(at 407.307504 210.073 0)
			(layer "F.Fab")
			(hide yes)
			(effects
				(font
					(size 1 1)
					(thickness 0.15)
				)
			)
		)
		(property "MPN" "CC0402JRNPO9BN220"
			(at 407.307504 210.073 0)
			(layer "F.Fab")
			(hide yes)
			(effects
				(font
					(size 1 1)
					(thickness 0.15)
				)
			)
		)
		(property "Manufacturer" "YAGEO"
			(at 407.307504 210.073 0)
			(layer "F.Fab")
			(hide yes)
			(effects
				(font
					(size 1 1)
					(thickness 0.15)
				)
			)
		)
		(property "Val" "22p"
			(at 407.307504 210.073 0)
			(layer "F.Fab")
			(hide yes)
			(effects
				(font
					(size 1 1)
					(thickness 0.15)
				)
			)
		)
		(property "Voltage" ""
			(at 407.307504 210.073 0)
			(layer "F.Fab")
			(hide yes)
			(effects
				(font
					(size 1 1)
					(thickness 0.15)
				)
			)
		)
		(sheetname "HDMI + Ethernet")
		(sheetfile "hdmi-ethernet.kicad_sch")
		(attr smd)
		(fp_rect
			(start -0.925 -0.47)
			(end 0.925 0.47)
			(stroke
				(width 0.05)
				(type default)
			)
			(fill no)
			(layer "F.CrtYd")
		)
		(fp_line
			(start 0.504 0.248)
			(end -0.494 0.248)
			(stroke
				(width 0.15)
				(type solid)
			)
			(layer "F.Fab")
		)
		(fp_line
			(start 0.504 -0.25)
			(end 0.504 0.248)
			(stroke
				(width 0.15)
				(type solid)
			)
			(layer "F.Fab")
		)
		(fp_line
			(start -0.494 0.248)
			(end -0.494 -0.25)
			(stroke
				(width 0.15)
				(type solid)
			)
			(layer "F.Fab")
		)
		(fp_line
			(start -0.494 -0.25)
			(end 0.504 -0.25)
			(stroke
				(width 0.15)
				(type solid)
			)
			(layer "F.Fab")
		)
		(pad "1" smd roundrect
			(at -0.48 0 180)
			(size 0.59 0.64)
			(layers "F.Cu" "F.Mask" "F.Paste")
			(roundrect_rratio 0.25)
			(net 1 "GND")
			(pintype "passive")
		)
		(pad "2" smd roundrect
			(at 0.48 0 180)
			(size 0.59 0.64)
			(layers "F.Cu" "F.Mask" "F.Paste")
			(roundrect_rratio 0.25)
			(net 720 "/HDMI + Ethernet/GBE_XO")
			(pintype "passive")
		)
	)
	(footprint "antmicro-footprints:Vishay_PowerPAK_1212-8_Single"
		(layer "F.Cu")
		(at 190.0675 172.399)
		(descr "PowerPAK 1212-8 Single")
		(tags "Vishay PowerPAK 1212-8 Single")
		(property "Reference" "Q6"
			(at 2.9325 1.901 90)
			(layer "F.SilkS")
			(effects
				(font
					(size 0.7 0.7)
					(thickness 0.15)
				)
				(justify left bottom)
			)
		)
		(property "Value" "SI7613DN-T1-GE3"
			(at -8 2.7 0)
			(layer "F.Fab")
			(effects
				(font
					(size 0.7 0.7)
					(thickness 0.15)
				)
				(justify left bottom)
			)
		)
		(property "Description" "Power MOSFET, P Channel, 20 V, 35 A, 0.0072 ohm, PowerPAK 1212, Surface Mount"
			(at 0 0 0)
			(layer "F.Fab")
			(hide yes)
			(effects
				(font
					(size 1.27 1.27)
					(thickness 0.15)
				)
			)
		)
		(property "Author" "Antmicro"
			(at 0 0 0)
			(layer "F.Fab")
			(hide yes)
			(effects
				(font
					(size 1 1)
					(thickness 0.15)
				)
			)
		)
		(property "License" "Apache-2.0"
			(at 0 0 0)
			(layer "F.Fab")
			(hide yes)
			(effects
				(font
					(size 1 1)
					(thickness 0.15)
				)
			)
		)
		(property "MPN" "SI7613DN-T1-GE3"
			(at 0 0 0)
			(layer "F.Fab")
			(hide yes)
			(effects
				(font
					(size 1 1)
					(thickness 0.15)
				)
			)
		)
		(property "Manufacturer" "Vishay"
			(at 0 0 0)
			(layer "F.Fab")
			(hide yes)
			(effects
				(font
					(size 1 1)
					(thickness 0.15)
				)
			)
		)
		(sheetname "Power supply")
		(sheetfile "power-supply.kicad_sch")
		(attr smd)
		(fp_line
			(start -1.651 -1.651)
			(end -1.651 -1.317)
			(stroke
				(width 0.15)
				(type solid)
			)
			(layer "F.SilkS")
		)
		(fp_line
			(start -1.651 -1.651)
			(end 1.648 -1.651)
			(stroke
				(width 0.15)
				(type solid)
			)
			(layer "F.SilkS")
		)
		(fp_line
			(start -1.635 1.3)
			(end -1.635 1.634)
			(stroke
				(width 0.15)
				(type solid)
			)
			(layer "F.SilkS")
		)
		(fp_line
			(start -1.635 1.634)
			(end 1.634 1.634)
			(stroke
				(width 0.15)
				(type solid)
			)
			(layer "F.SilkS")
		)
		(fp_line
			(start 1.634 1.3)
			(end 1.634 1.634)
			(stroke
				(width 0.15)
				(type solid)
			)
			(layer "F.SilkS")
		)
		(fp_line
			(start 1.648 -1.651)
			(end 1.648 -1.317)
			(stroke
				(width 0.15)
				(type solid)
			)
			(layer "F.SilkS")
		)
		(fp_circle
			(center -1.9 -1.4)
			(end -1.85 -1.4)
			(stroke
				(width 0.15)
				(type solid)
			)
			(fill yes)
			(layer "F.SilkS")
		)
		(fp_rect
			(start -2 -1.8)
			(end 2 1.798)
			(stroke
				(width 0.05)
				(type solid)
			)
			(fill no)
			(layer "F.CrtYd")
		)
		(fp_line
			(start -1.6425 -1.4175)
			(end -1.4175 -1.6425)
			(stroke
				(width 0.15)
				(type solid)
			)
			(layer "F.Fab")
		)
		(fp_rect
			(start -1.651 -1.651)
			(end 1.648 1.648)
			(stroke
				(width 0.15)
				(type solid)
			)
			(fill no)
			(layer "F.Fab")
		)
		(pad "1" smd rect
			(at -1.436 -0.99)
			(size 0.99 0.405)
			(layers "F.Cu" "F.Mask" "F.Paste")
			(net 702 "VDC")
			(pinfunction "S")
			(pintype "passive")
		)
		(pad "2" smd rect
			(at -1.436 -0.332)
			(size 0.99 0.405)
			(layers "F.Cu" "F.Mask" "F.Paste")
			(net 702 "VDC")
			(pinfunction "S")
			(pintype "passive")
		)
		(pad "3" smd rect
			(at -1.436 0.33)
			(size 0.99 0.405)
			(layers "F.Cu" "F.Mask" "F.Paste")
			(net 702 "VDC")
			(pinfunction "S")
			(pintype "passive")
		)
		(pad "4" smd rect
			(at -1.436 0.988)
			(size 0.99 0.405)
			(layers "F.Cu" "F.Mask" "F.Paste")
			(net 341 "Net-(Q6-G)")
			(pinfunction "G")
			(pintype "passive")
		)
		(pad "5" smd custom
			(at 0.557 0)
			(size 1.725 2.235)
			(layers "F.Cu" "F.Mask" "F.Paste")
			(net 700 "/Power supply/USB_PD_VBUS")
			(pinfunction "D")
			(pintype "passive")
			(zone_connect 2)
			(options
				(clearance outline)
				(anchor rect)
			)
			(primitives
				(gr_poly
					(pts
						(xy 0.8625 0.1275) (xy 0.8625 -0.1275) (xy 1.3725 -0.1275) (xy 1.3725 -0.5325) (xy 0.8625 -0.5325)
						(xy 0.8625 -0.7875) (xy 1.3725 -0.7875) (xy 1.3725 -1.195) (xy 0.6125 -1.195) (xy 0.6125 1.195)
						(xy 1.3725 1.195) (xy 1.3725 0.7875) (xy 0.8625 0.7875) (xy 0.8625 0.5325) (xy 1.3725 0.5325)
						(xy 1.3725 0.1275)
					)
					(width 0)
					(fill yes)
				)
			)
		)
	)
	(footprint "antmicro-footprints:SOT-23-6"
		(layer "F.Cu")
		(at 189.089 176.147 90)
		(property "Reference" "U11"
			(at 1.197 -3.939 180)
			(layer "F.SilkS")
			(effects
				(font
					(size 0.7 0.7)
					(thickness 0.15)
				)
				(justify left bottom)
			)
		)
		(property "Value" "LTC4412IS6"
			(at -1.75 2.75 90)
			(layer "F.Fab")
			(effects
				(font
					(size 0.7 0.7)
					(thickness 0.15)
				)
				(justify left bottom)
			)
		)
		(property "Description" "Ideal diode controller"
			(at 0 0 90)
			(layer "F.Fab")
			(hide yes)
			(effects
				(font
					(size 1.27 1.27)
					(thickness 0.15)
				)
			)
		)
		(property "Author" "Antmicro"
			(at 365.236 -12.942 0)
			(layer "F.Fab")
			(hide yes)
			(effects
				(font
					(size 1 1)
					(thickness 0.15)
				)
			)
		)
		(property "License" "Apache-2.0"
			(at 365.236 -12.942 0)
			(layer "F.Fab")
			(hide yes)
			(effects
				(font
					(size 1 1)
					(thickness 0.15)
				)
			)
		)
		(property "MPN" "LTC4412IS6#TRMPBF"
			(at 365.236 -12.942 0)
			(layer "F.Fab")
			(hide yes)
			(effects
				(font
					(size 1 1)
					(thickness 0.15)
				)
			)
		)
		(property "Manufacturer" "Analog Devices"
			(at 365.236 -12.942 0)
			(layer "F.Fab")
			(hide yes)
			(effects
				(font
					(size 1 1)
					(thickness 0.15)
				)
			)
		)
		(sheetname "Power supply")
		(sheetfile "power-supply.kicad_sch")
		(attr smd)
		(fp_line
			(start 1.45 -0.7)
			(end 1.45 -0.4)
			(stroke
				(width 0.12)
				(type solid)
			)
			(layer "F.SilkS")
		)
		(fp_line
			(start 1.3 -0.7)
			(end 1.45 -0.7)
			(stroke
				(width 0.12)
				(type solid)
			)
			(layer "F.SilkS")
		)
		(fp_line
			(start -1.3 -0.7)
			(end -1.45 -0.7)
			(stroke
				(width 0.12)
				(type solid)
			)
			(layer "F.SilkS")
		)
		(fp_line
			(start -1.45 -0.7)
			(end -1.45 -0.4)
			(stroke
				(width 0.12)
				(type solid)
			)
			(layer "F.SilkS")
		)
		(fp_line
			(start 1.45 0.7)
			(end 1.45 0.4)
			(stroke
				(width 0.12)
				(type solid)
			)
			(layer "F.SilkS")
		)
		(fp_line
			(start 1.3 0.7)
			(end 1.45 0.7)
			(stroke
				(width 0.12)
				(type solid)
			)
			(layer "F.SilkS")
		)
		(fp_line
			(start -1.45 0.7)
			(end -1.45 0.4)
			(stroke
				(width 0.12)
				(type solid)
			)
			(layer "F.SilkS")
		)
		(fp_rect
			(start -1.55 -1.85)
			(end 1.55 1.75)
			(stroke
				(width 0.05)
				(type solid)
			)
			(fill no)
			(layer "F.CrtYd")
		)
		(fp_line
			(start 1.5 -0.7)
			(end 1.5 0.7)
			(stroke
				(width 0.1)
				(type solid)
			)
			(layer "F.Fab")
		)
		(fp_line
			(start -1.5 -0.7)
			(end 1.5 -0.7)
			(stroke
				(width 0.1)
				(type solid)
			)
			(layer "F.Fab")
		)
		(fp_line
			(start 1.5 0.7)
			(end -1.5 0.7)
			(stroke
				(width 0.1)
				(type solid)
			)
			(layer "F.Fab")
		)
		(fp_line
			(start -1.5 0.7)
			(end -1.5 -0.7)
			(stroke
				(width 0.1)
				(type solid)
			)
			(layer "F.Fab")
		)
		(fp_text user "."
			(at -1.4 1.2 270)
			(layer "F.SilkS")
			(effects
				(font
					(size 1 1)
					(thickness 0.15)
				)
			)
		)
		(pad "1" smd roundrect
			(at -0.954 1.1 90)
			(size 0.55 1)
			(layers "F.Cu" "F.Mask" "F.Paste")
			(roundrect_rratio 0.15)
			(net 956 "/DC-DC Converters/POE_DC")
			(pinfunction "IN")
			(pintype "power_in")
		)
		(pad "2" smd roundrect
			(at -0.003 1.1 90)
			(size 0.55 1)
			(layers "F.Cu" "F.Mask" "F.Paste")
			(roundrect_rratio 0.15)
			(net 1 "GND")
			(pinfunction "GND")
			(pintype "power_in")
		)
		(pad "3" smd roundrect
			(at 0.947 1.1 90)
			(size 0.55 1)
			(layers "F.Cu" "F.Mask" "F.Paste")
			(roundrect_rratio 0.15)
			(net 1 "GND")
			(pinfunction "CTL")
			(pintype "input")
		)
		(pad "4" smd roundrect
			(at 0.947 -1.214 90)
			(size 0.55 1)
			(layers "F.Cu" "F.Mask" "F.Paste")
			(roundrect_rratio 0.15)
			(net 1158 "unconnected-(U11-STAT-Pad4)")
			(pinfunction "STAT")
			(pintype "output+no_connect")
		)
		(pad "5" smd roundrect
			(at -0.003 -1.214 90)
			(size 0.55 1)
			(layers "F.Cu" "F.Mask" "F.Paste")
			(roundrect_rratio 0.15)
			(net 342 "Net-(Q7-G)")
			(pinfunction "GATE")
			(pintype "output")
		)
		(pad "6" smd roundrect
			(at -0.954 -1.214 90)
			(size 0.55 1)
			(layers "F.Cu" "F.Mask" "F.Paste")
			(roundrect_rratio 0.15)
			(net 702 "VDC")
			(pinfunction "SENSE")
			(pintype "input")
		)
	)
	(footprint "antmicro-footprints:SW_KMR211NGLFS_SMD"
		(layer "F.Cu")
		(at 260.5 186.5 90)
		(property "Reference" "S6"
			(at 1.05 2.65 90)
			(layer "F.SilkS")
			(effects
				(font
					(size 0.7 0.7)
					(thickness 0.15)
				)
				(justify left bottom)
			)
		)
		(property "Value" "SW_KMR211NGLFS_SMD"
			(at -3 3 90)
			(layer "F.Fab")
			(effects
				(font
					(size 0.7 0.7)
					(thickness 0.15)
				)
				(justify left bottom)
			)
		)
		(property "Description" "Tactile Switch, KMR 2 Series, Top Actuated, Surface Mount, Oval Button, 120 gf, 50mA at 32VDC"
			(at 0 0 90)
			(layer "F.Fab")
			(hide yes)
			(effects
				(font
					(size 1.27 1.27)
					(thickness 0.15)
				)
			)
		)
		(property "Author" "Antmicro"
			(at 447 -74 0)
			(layer "F.Fab")
			(hide yes)
			(effects
				(font
					(size 1 1)
					(thickness 0.15)
				)
			)
		)
		(property "License" "Apache-2.0"
			(at 447 -74 0)
			(layer "F.Fab")
			(hide yes)
			(effects
				(font
					(size 1 1)
					(thickness 0.15)
				)
			)
		)
		(property "MPN" "KMR211NGLFS"
			(at 447 -74 0)
			(layer "F.Fab")
			(hide yes)
			(effects
				(font
					(size 1 1)
					(thickness 0.15)
				)
			)
		)
		(property "Manufacturer" "C&K"
			(at 447 -74 0)
			(layer "F.Fab")
			(hide yes)
			(effects
				(font
					(size 1 1)
					(thickness 0.15)
				)
			)
		)
		(sheetname "DC-DC Converters")
		(sheetfile "dc-dc.kicad_sch")
		(attr smd)
		(fp_line
			(start 2.101 -1.6)
			(end -2.1 -1.6)
			(stroke
				(width 0.15)
				(type solid)
			)
			(layer "F.SilkS")
		)
		(fp_line
			(start -2.1 -1.6)
			(end -2.1 -1.499)
			(stroke
				(width 0.15)
				(type solid)
			)
			(layer "F.SilkS")
		)
		(fp_line
			(start 2.101 -1.58)
			(end 2.101 -1.459)
			(stroke
				(width 0.15)
				(type solid)
			)
			(layer "F.SilkS")
		)
		(fp_line
			(start 2.101 1.601)
			(end 2.101 1.48)
			(stroke
				(width 0.15)
				(type solid)
			)
			(layer "F.SilkS")
		)
		(fp_line
			(start 2.101 1.601)
			(end -2.1 1.601)
			(stroke
				(width 0.15)
				(type solid)
			)
			(layer "F.SilkS")
		)
		(fp_line
			(start -2.1 1.601)
			(end -2.1 1.48)
			(stroke
				(width 0.15)
				(type solid)
			)
			(layer "F.SilkS")
		)
		(fp_rect
			(start 2.751 1.75)
			(end -2.748 -1.749)
			(stroke
				(width 0.05)
				(type solid)
			)
			(fill no)
			(layer "F.CrtYd")
		)
		(fp_line
			(start 2.101 -1.6)
			(end -2.1 -1.6)
			(stroke
				(width 0.15)
				(type solid)
			)
			(layer "F.Fab")
		)
		(fp_line
			(start -2.1 -1.6)
			(end -2.1 1.601)
			(stroke
				(width 0.15)
				(type solid)
			)
			(layer "F.Fab")
		)
		(fp_line
			(start -0.248 -0.8)
			(end 0.25 -0.8)
			(stroke
				(width 0.15)
				(type solid)
			)
			(layer "F.Fab")
		)
		(fp_line
			(start 0.25 0.802)
			(end -0.248 0.802)
			(stroke
				(width 0.15)
				(type solid)
			)
			(layer "F.Fab")
		)
		(fp_line
			(start 2.101 1.601)
			(end 2.101 -1.6)
			(stroke
				(width 0.15)
				(type solid)
			)
			(layer "F.Fab")
		)
		(fp_line
			(start -2.1 1.601)
			(end 2.101 1.601)
			(stroke
				(width 0.15)
				(type solid)
			)
			(layer "F.Fab")
		)
		(fp_arc
			(start 0.25 -0.8)
			(mid 1.051001 0.001)
			(end 0.25 0.802)
			(stroke
				(width 0.15)
				(type solid)
			)
			(layer "F.Fab")
		)
		(fp_arc
			(start -0.248 0.802)
			(mid -1.050001 0.001)
			(end -0.248 -0.8)
			(stroke
				(width 0.15)
				(type solid)
			)
			(layer "F.Fab")
		)
		(pad "1" smd rect
			(at -2.048 -0.8 270)
			(size 0.9 1)
			(layers "F.Cu" "F.Mask" "F.Paste")
			(net 1 "GND")
			(pinfunction "1")
			(pintype "passive")
		)
		(pad "2" smd rect
			(at 2.05 -0.8 270)
			(size 0.9 1)
			(layers "F.Cu" "F.Mask" "F.Paste")
			(net 1 "GND")
			(pinfunction "2")
			(pintype "passive")
		)
		(pad "3" smd rect
			(at -2.048 0.802 270)
			(size 0.9 1)
			(layers "F.Cu" "F.Mask" "F.Paste")
			(net 974 "/DC-DC Converters/~{PB_CTRL_IN}")
			(pinfunction "3")
			(pintype "passive")
		)
		(pad "4" smd rect
			(at 2.05 0.802 270)
			(size 0.9 1)
			(layers "F.Cu" "F.Mask" "F.Paste")
			(net 974 "/DC-DC Converters/~{PB_CTRL_IN}")
			(pinfunction "4")
			(pintype "passive")
		)
	)
	(footprint "antmicro-footprints:Resonator_SMD_Abracon_ABM8G_3.2x2.5mm"
		(layer "F.Cu")
		(at 196.701 103.099 90)
		(property "Reference" "Y1"
			(at 1.999 -0.701 0)
			(layer "F.SilkS")
			(effects
				(font
					(size 0.7 0.7)
					(thickness 0.15)
				)
				(justify left bottom)
			)
		)
		(property "Value" "Resonator_12MHz_ABM8G"
			(at -1.75 2.548 90)
			(layer "F.Fab")
			(effects
				(font
					(size 0.7 0.7)
					(thickness 0.15)
				)
				(justify left bottom)
			)
		)
		(property "Description" "Crystal, 12 MHz, SMT, 3.2mm x 2.5mm, 30 ppm, 18 pF, 20 ppm, ABM8G"
			(at 0 0 90)
			(layer "F.Fab")
			(hide yes)
			(effects
				(font
					(size 1.27 1.27)
					(thickness 0.15)
				)
			)
		)
		(property "Author" "Antmicro"
			(at 299.8 -93.602 0)
			(layer "F.Fab")
			(hide yes)
			(effects
				(font
					(size 1 1)
					(thickness 0.15)
				)
			)
		)
		(property "License" "Apache-2.0"
			(at 299.8 -93.602 0)
			(layer "F.Fab")
			(hide yes)
			(effects
				(font
					(size 1 1)
					(thickness 0.15)
				)
			)
		)
		(property "MPN" "ABM8G-12.000MHZ-18-D2Y-T"
			(at 299.8 -93.602 0)
			(layer "F.Fab")
			(hide yes)
			(effects
				(font
					(size 1 1)
					(thickness 0.15)
				)
			)
		)
		(property "Manufacturer" "Abracon"
			(at 299.8 -93.602 0)
			(layer "F.Fab")
			(hide yes)
			(effects
				(font
					(size 1 1)
					(thickness 0.15)
				)
			)
		)
		(property "Val" "12 MHz"
			(at 299.8 -93.602 0)
			(layer "F.Fab")
			(hide yes)
			(effects
				(font
					(size 1 1)
					(thickness 0.15)
				)
			)
		)
		(sheetname "USB PHY")
		(sheetfile "usb-phy.kicad_sch")
		(attr smd)
		(fp_line
			(start -0.35 -1.25)
			(end 0.45 -1.25)
			(stroke
				(width 0.15)
				(type solid)
			)
			(layer "F.SilkS")
		)
		(fp_line
			(start 1.6 0.3)
			(end 1.6 -0.2)
			(stroke
				(width 0.15)
				(type solid)
			)
			(layer "F.SilkS")
		)
		(fp_line
			(start -1.6 0.3)
			(end -1.6 -0.2)
			(stroke
				(width 0.15)
				(type solid)
			)
			(layer "F.SilkS")
		)
		(fp_line
			(start -0.35 1.25)
			(end 0.45 1.25)
			(stroke
				(width 0.15)
				(type solid)
			)
			(layer "F.SilkS")
		)
		(fp_circle
			(center -1.75 1.5)
			(end -1.7 1.5)
			(stroke
				(width 0.15)
				(type solid)
			)
			(fill no)
			(layer "F.SilkS")
		)
		(fp_rect
			(start -1.907 -1.55)
			(end 2.006 1.649)
			(stroke
				(width 0.05)
				(type solid)
			)
			(fill no)
			(layer "F.CrtYd")
		)
		(pad "1" smd roundrect
			(at -1.101 0.949 90)
			(size 1.3 1.1)
			(layers "F.Cu" "F.Mask" "F.Paste")
			(roundrect_rratio 0)
			(chamfer_ratio 0.2)
			(chamfer bottom_left)
			(net 706 "/USB PHY/USB_HOST_XI")
			(pintype "passive")
		)
		(pad "2" smd rect
			(at 1.199 0.949 90)
			(size 1.3 1.1)
			(layers "F.Cu" "F.Mask" "F.Paste")
			(net 1 "GND")
			(pinfunction "SH")
			(pintype "passive")
		)
		(pad "3" smd rect
			(at 1.199 -0.85 90)
			(size 1.3 1.1)
			(layers "F.Cu" "F.Mask" "F.Paste")
			(net 708 "/USB PHY/USB_HOST_XO")
			(pintype "passive")
		)
		(pad "4" smd rect
			(at -1.101 -0.85 90)
			(size 1.3 1.1)
			(layers "F.Cu" "F.Mask" "F.Paste")
			(net 1 "GND")
			(pinfunction "SH")
			(pintype "passive")
		)
	)
	(footprint "antmicro-footprints:C_0402_1005Metric"
		(layer "F.Cu")
		(at 244.6 141.6 90)
		(descr "Capacitor SMD 0402")
		(tags "capacitor SMD 0402")
		(property "Reference" "C225"
			(at -1.7 6.45 90)
			(layer "F.SilkS")
			(effects
				(font
					(size 0.7 0.7)
					(thickness 0.15)
				)
				(justify left bottom)
			)
		)
		(property "Value" "C_10u_0402"
			(at 0 1.4 90)
			(layer "F.Fab")
			(effects
				(font
					(size 0.7 0.7)
					(thickness 0.15)
				)
				(justify left bottom)
			)
		)
		(property "Description" "SMD Multilayer Ceramic Capacitor, 10 µF, 6.3 V, 0402 [1005 Metric], ± 20%, X5R, CC Series"
			(at 0 0 90)
			(layer "F.Fab")
			(hide yes)
			(effects
				(font
					(size 1.27 1.27)
					(thickness 0.15)
				)
			)
		)
		(property "Author" "Antmicro"
			(at 386.2 -103 0)
			(layer "F.Fab")
			(hide yes)
			(effects
				(font
					(size 1 1)
					(thickness 0.15)
				)
			)
		)
		(property "Dielectric" ""
			(at 386.2 -103 0)
			(layer "F.Fab")
			(hide yes)
			(effects
				(font
					(size 1 1)
					(thickness 0.15)
				)
			)
		)
		(property "License" "Apache-2.0"
			(at 386.2 -103 0)
			(layer "F.Fab")
			(hide yes)
			(effects
				(font
					(size 1 1)
					(thickness 0.15)
				)
			)
		)
		(property "MPN" "CC0402MRX5R5BB106"
			(at 386.2 -103 0)
			(layer "F.Fab")
			(hide yes)
			(effects
				(font
					(size 1 1)
					(thickness 0.15)
				)
			)
		)
		(property "Manufacturer" "YAGEO"
			(at 386.2 -103 0)
			(layer "F.Fab")
			(hide yes)
			(effects
				(font
					(size 1 1)
					(thickness 0.15)
				)
			)
		)
		(property "Val" "10u"
			(at 386.2 -103 0)
			(layer "F.Fab")
			(hide yes)
			(effects
				(font
					(size 1 1)
					(thickness 0.15)
				)
			)
		)
		(property "Voltage" ""
			(at 386.2 -103 0)
			(layer "F.Fab")
			(hide yes)
			(effects
				(font
					(size 1 1)
					(thickness 0.15)
				)
			)
		)
		(sheetname "USB PHY")
		(sheetfile "usb-phy.kicad_sch")
		(attr smd)
		(fp_rect
			(start -0.925 -0.47)
			(end 0.925 0.47)
			(stroke
				(width 0.05)
				(type default)
			)
			(fill no)
			(layer "F.CrtYd")
		)
		(fp_line
			(start 0.504 -0.25)
			(end 0.504 0.248)
			(stroke
				(width 0.15)
				(type solid)
			)
			(layer "F.Fab")
		)
		(fp_line
			(start -0.494 -0.25)
			(end 0.504 -0.25)
			(stroke
				(width 0.15)
				(type solid)
			)
			(layer "F.Fab")
		)
		(fp_line
			(start 0.504 0.248)
			(end -0.494 0.248)
			(stroke
				(width 0.15)
				(type solid)
			)
			(layer "F.Fab")
		)
		(fp_line
			(start -0.494 0.248)
			(end -0.494 -0.25)
			(stroke
				(width 0.15)
				(type solid)
			)
			(layer "F.Fab")
		)
		(pad "1" smd roundrect
			(at -0.48 0 90)
			(size 0.59 0.64)
			(layers "F.Cu" "F.Mask" "F.Paste")
			(roundrect_rratio 0.25)
			(net 1 "GND")
			(pintype "passive")
		)
		(pad "2" smd roundrect
			(at 0.48 0 90)
			(size 0.59 0.64)
			(layers "F.Cu" "F.Mask" "F.Paste")
			(roundrect_rratio 0.25)
			(net 707 "/USB PHY/FTDI_3V3")
			(pintype "passive")
		)
	)
	(footprint "antmicro-footprints:QFN-24-1EP_4x4mm_P0.5mm_EP2.6x2.6mm"
		(layer "F.Cu")
		(at 222.4 150.3 180)
		(descr "QFN, 24 Pin (http://ww1.microchip.com/downloads/en/PackagingSpec/00000049BQ.pdf#page=278), generated with kicad-footprint-generator ipc_noLead_generator.py")
		(tags "QFN NoLead")
		(property "Reference" "U26"
			(at 3.95 2.92 180)
			(layer "F.SilkS")
			(effects
				(font
					(size 0.7 0.7)
					(thickness 0.15)
				)
				(justify left bottom)
			)
		)
		(property "Value" "LAN8720A-CP-TR-ABC"
			(at 0 3.4 180)
			(layer "F.Fab")
			(effects
				(font
					(size 0.7 0.7)
					(thickness 0.15)
				)
				(justify left bottom)
			)
		)
		(property "Description" "Ethernet Controller, 100 Mbps, IEEE 802.3, IEEE 802.3u, 3 V, 3.6 V, SQFN, 24 Pins"
			(at 0 0 180)
			(layer "F.Fab")
			(hide yes)
			(effects
				(font
					(size 1.27 1.27)
					(thickness 0.15)
				)
			)
		)
		(property "Author" "Antmicro"
			(at 444.8 300.6 0)
			(layer "F.Fab")
			(hide yes)
			(effects
				(font
					(size 1 1)
					(thickness 0.15)
				)
			)
		)
		(property "License" "Apache-2.0"
			(at 444.8 300.6 0)
			(layer "F.Fab")
			(hide yes)
			(effects
				(font
					(size 1 1)
					(thickness 0.15)
				)
			)
		)
		(property "MPN" "LAN8720A-CP-TR-ABC"
			(at 444.8 300.6 0)
			(layer "F.Fab")
			(hide yes)
			(effects
				(font
					(size 1 1)
					(thickness 0.15)
				)
			)
		)
		(property "Manufacturer" "Microchip Technology"
			(at 444.8 300.6 0)
			(layer "F.Fab")
			(hide yes)
			(effects
				(font
					(size 1 1)
					(thickness 0.15)
				)
			)
		)
		(sheetname "HDMI + Ethernet")
		(sheetfile "hdmi-ethernet.kicad_sch")
		(attr smd)
		(fp_line
			(start 2.108 2.108)
			(end 2.108 1.634)
			(stroke
				(width 0.15)
				(type solid)
			)
			(layer "F.SilkS")
		)
		(fp_line
			(start 2.108 -2.11)
			(end 2.108 -1.635)
			(stroke
				(width 0.15)
				(type solid)
			)
			(layer "F.SilkS")
		)
		(fp_line
			(start 1.634 2.108)
			(end 2.108 2.108)
			(stroke
				(width 0.15)
				(type solid)
			)
			(layer "F.SilkS")
		)
		(fp_line
			(start 1.634 -2.11)
			(end 2.108 -2.11)
			(stroke
				(width 0.15)
				(type solid)
			)
			(layer "F.SilkS")
		)
		(fp_line
			(start -1.635 2.108)
			(end -2.11 2.108)
			(stroke
				(width 0.15)
				(type solid)
			)
			(layer "F.SilkS")
		)
		(fp_line
			(start -1.635 -2.11)
			(end -2.11 -2.11)
			(stroke
				(width 0.15)
				(type solid)
			)
			(layer "F.SilkS")
		)
		(fp_line
			(start -2.11 2.108)
			(end -2.11 1.634)
			(stroke
				(width 0.15)
				(type solid)
			)
			(layer "F.SilkS")
		)
		(fp_line
			(start -2.11 -1.636)
			(end -2.11 -2.11)
			(stroke
				(width 0.15)
				(type solid)
			)
			(layer "F.SilkS")
		)
		(fp_circle
			(center -2.3 -2.3)
			(end -2.25 -2.3)
			(stroke
				(width 0.15)
				(type solid)
			)
			(fill yes)
			(layer "F.SilkS")
		)
		(fp_rect
			(start -2.503 -2.503)
			(end 2.5 2.5)
			(stroke
				(width 0.05)
				(type solid)
			)
			(fill no)
			(layer "F.CrtYd")
		)
		(fp_line
			(start 1.999 1.999)
			(end -2 1.999)
			(stroke
				(width 0.15)
				(type solid)
			)
			(layer "F.Fab")
		)
		(fp_line
			(start 1.999 -2)
			(end 1.999 1.999)
			(stroke
				(width 0.15)
				(type solid)
			)
			(layer "F.Fab")
		)
		(fp_line
			(start -1 -2)
			(end 1.999 -2)
			(stroke
				(width 0.15)
				(type solid)
			)
			(layer "F.Fab")
		)
		(fp_line
			(start -2 1.999)
			(end -2 -1)
			(stroke
				(width 0.15)
				(type solid)
			)
			(layer "F.Fab")
		)
		(fp_line
			(start -2 -1)
			(end -1 -2)
			(stroke
				(width 0.15)
				(type solid)
			)
			(layer "F.Fab")
		)
		(pad "" smd roundrect
			(at -0.652 -0.652 180)
			(size 1.05 1.05)
			(layers "F.Paste")
			(roundrect_rratio 0.238095)
		)
		(pad "" smd roundrect
			(at -0.652 0.65 180)
			(size 1.05 1.05)
			(layers "F.Paste")
			(roundrect_rratio 0.238095)
		)
		(pad "" smd roundrect
			(at 0.65 -0.652 180)
			(size 1.05 1.05)
			(layers "F.Paste")
			(roundrect_rratio 0.238095)
		)
		(pad "" smd roundrect
			(at 0.65 0.65 180)
			(size 1.05 1.05)
			(layers "F.Paste")
			(roundrect_rratio 0.238095)
		)
		(pad "1" smd roundrect
			(at -1.938 -1.25 180)
			(size 0.825 0.25)
			(layers "F.Cu" "F.Mask" "F.Paste")
			(roundrect_rratio 0.25)
			(net 721 "/HDMI + Ethernet/ETH_3V3")
			(pinfunction "VDD2A")
			(pintype "power_in")
		)
		(pad "2" smd roundrect
			(at -1.938 -0.75 180)
			(size 0.825 0.25)
			(layers "F.Cu" "F.Mask" "F.Paste")
			(roundrect_rratio 0.25)
			(net 846 "/HDMI + Ethernet/ETH_LED_SPD-")
			(pinfunction "LED2/NINTSEL")
			(pintype "bidirectional")
		)
		(pad "3" smd roundrect
			(at -1.938 -0.25 180)
			(size 0.825 0.25)
			(layers "F.Cu" "F.Mask" "F.Paste")
			(roundrect_rratio 0.25)
			(net 847 "/HDMI + Ethernet/ETH_LED_LINK-")
			(pinfunction "LED1/REGOFF")
			(pintype "bidirectional")
		)
		(pad "4" smd roundrect
			(at -1.938 0.248 180)
			(size 0.825 0.25)
			(layers "F.Cu" "F.Mask" "F.Paste")
			(roundrect_rratio 0.25)
			(net 719 "/HDMI + Ethernet/ETH_XO")
			(pinfunction "XTAL2")
			(pintype "passive")
		)
		(pad "5" smd roundrect
			(at -1.938 0.748 180)
			(size 0.825 0.25)
			(layers "F.Cu" "F.Mask" "F.Paste")
			(roundrect_rratio 0.25)
			(net 716 "/HDMI + Ethernet/ETH_XI")
			(pinfunction "XTAL1/CLKIN")
			(pintype "passive")
		)
		(pad "6" smd roundrect
			(at -1.938 1.249 180)
			(size 0.825 0.25)
			(layers "F.Cu" "F.Mask" "F.Paste")
			(roundrect_rratio 0.25)
			(net 722 "/HDMI + Ethernet/ETH_VDDCR")
			(pinfunction "VDDCR")
			(pintype "power_in")
		)
		(pad "7" smd roundrect
			(at -1.25 1.937 180)
			(size 0.25 0.825)
			(layers "F.Cu" "F.Mask" "F.Paste")
			(roundrect_rratio 0.25)
			(net 945 "/HDMI + Ethernet/ETH_PHY_RXD1")
			(pinfunction "RXD1/MODE1")
			(pintype "output")
		)
		(pad "8" smd roundrect
			(at -0.75 1.937 180)
			(size 0.25 0.825)
			(layers "F.Cu" "F.Mask" "F.Paste")
			(roundrect_rratio 0.25)
			(net 946 "/HDMI + Ethernet/ETH_PHY_RXDO")
			(pinfunction "RXD0/MODE0")
			(pintype "output")
		)
		(pad "9" smd roundrect
			(at -0.25 1.937 180)
			(size 0.25 0.825)
			(layers "F.Cu" "F.Mask" "F.Paste")
			(roundrect_rratio 0.25)
			(net 26 "+1V8")
			(pinfunction "VDDIO")
			(pintype "power_in")
		)
		(pad "10" smd roundrect
			(at 0.248 1.937 180)
			(size 0.25 0.825)
			(layers "F.Cu" "F.Mask" "F.Paste")
			(roundrect_rratio 0.25)
			(net 947 "/HDMI + Ethernet/ETH_PHY_RXER")
			(pinfunction "RXER/PHYAD0")
			(pintype "output")
		)
		(pad "11" smd roundrect
			(at 0.748 1.937 180)
			(size 0.25 0.825)
			(layers "F.Cu" "F.Mask" "F.Paste")
			(roundrect_rratio 0.25)
			(net 944 "/HDMI + Ethernet/ETH_PHY_RX_DV")
			(pinfunction "CRS_DV/MODE2")
			(pintype "output")
		)
		(pad "12" smd roundrect
			(at 1.249 1.937 180)
			(size 0.25 0.825)
			(layers "F.Cu" "F.Mask" "F.Paste")
			(roundrect_rratio 0.25)
			(net 502 "/FPGA Bank 18 & 32/ETH_RMII.MDIO")
			(pinfunction "MDIO")
			(pintype "bidirectional")
		)
		(pad "13" smd roundrect
			(at 1.937 1.249 180)
			(size 0.825 0.25)
			(layers "F.Cu" "F.Mask" "F.Paste")
			(roundrect_rratio 0.25)
			(net 589 "/FPGA Bank 18 & 32/ETH_RMII.MDC")
			(pinfunction "MDC")
			(pintype "input")
		)
		(pad "14" smd roundrect
			(at 1.937 0.748 180)
			(size 0.825 0.25)
			(layers "F.Cu" "F.Mask" "F.Paste")
			(roundrect_rratio 0.25)
			(net 951 "/HDMI + Ethernet/ETH_PHY_REFCLK")
			(pinfunction "INT/REFCLKO")
			(pintype "output")
		)
		(pad "15" smd roundrect
			(at 1.937 0.248 180)
			(size 0.825 0.25)
			(layers "F.Cu" "F.Mask" "F.Paste")
			(roundrect_rratio 0.25)
			(net 501 "/FPGA Bank 18 & 32/ETH_RMII.~{RESET}")
			(pinfunction "RST")
			(pintype "input")
		)
		(pad "16" smd roundrect
			(at 1.937 -0.25 180)
			(size 0.825 0.25)
			(layers "F.Cu" "F.Mask" "F.Paste")
			(roundrect_rratio 0.25)
			(net 948 "/HDMI + Ethernet/ETH_PHY_TXEN")
			(pinfunction "TXEN")
			(pintype "input")
		)
		(pad "17" smd roundrect
			(at 1.937 -0.75 180)
			(size 0.825 0.25)
			(layers "F.Cu" "F.Mask" "F.Paste")
			(roundrect_rratio 0.25)
			(net 949 "/HDMI + Ethernet/ETH_PHY_TXDO")
			(pinfunction "TXD0")
			(pintype "input")
		)
		(pad "18" smd roundrect
			(at 1.937 -1.25 180)
			(size 0.825 0.25)
			(layers "F.Cu" "F.Mask" "F.Paste")
			(roundrect_rratio 0.25)
			(net 950 "/HDMI + Ethernet/ETH_PHY_TXD1")
			(pinfunction "TXD1")
			(pintype "input")
		)
		(pad "19" smd roundrect
			(at 1.249 -1.938 180)
			(size 0.25 0.825)
			(layers "F.Cu" "F.Mask" "F.Paste")
			(roundrect_rratio 0.25)
			(net 721 "/HDMI + Ethernet/ETH_3V3")
			(pinfunction "VDD1A")
			(pintype "power_in")
		)
		(pad "20" smd roundrect
			(at 0.748 -1.938 180)
			(size 0.25 0.825)
			(layers "F.Cu" "F.Mask" "F.Paste")
			(roundrect_rratio 0.25)
			(net 725 "/HDMI + Ethernet/ETH1_N")
			(pinfunction "TXN")
			(pintype "output")
		)
		(pad "21" smd roundrect
			(at 0.248 -1.938 180)
			(size 0.25 0.825)
			(layers "F.Cu" "F.Mask" "F.Paste")
			(roundrect_rratio 0.25)
			(net 724 "/HDMI + Ethernet/ETH1_P")
			(pinfunction "TXP")
			(pintype "output")
		)
		(pad "22" smd roundrect
			(at -0.25 -1.938 180)
			(size 0.25 0.825)
			(layers "F.Cu" "F.Mask" "F.Paste")
			(roundrect_rratio 0.25)
			(net 729 "/HDMI + Ethernet/ETH2_N")
			(pinfunction "RXN")
			(pintype "output")
		)
		(pad "23" smd roundrect
			(at -0.75 -1.938 180)
			(size 0.25 0.825)
			(layers "F.Cu" "F.Mask" "F.Paste")
			(roundrect_rratio 0.25)
			(net 726 "/HDMI + Ethernet/ETH2_P")
			(pinfunction "RXP")
			(pintype "output")
		)
		(pad "24" smd roundrect
			(at -1.25 -1.938 180)
			(size 0.25 0.825)
			(layers "F.Cu" "F.Mask" "F.Paste")
			(roundrect_rratio 0.25)
			(net 952 "/HDMI + Ethernet/ETH_ISET")
			(pinfunction "RBIAS")
			(pintype "input")
		)
		(pad "25" smd rect
			(at 0 0 180)
			(size 2.6 2.6)
			(layers "F.Cu" "F.Mask")
			(net 1 "GND")
			(pinfunction "VSS")
			(pintype "power_in")
		)
	)
	(footprint "antmicro-footprints:USON-10_2.5x1mm_P0.5mm"
		(layer "F.Cu")
		(at 260.1 101.25 180)
		(descr "USON-10 2.5x1mm_ Pitch 0.5mm")
		(tags "USON-10 2.5x1mm Pitch 0.5mm")
		(property "Reference" "U16"
			(at 0.95 -1.15 270)
			(layer "F.SilkS")
			(effects
				(font
					(size 0.7 0.7)
					(thickness 0.15)
				)
				(justify left bottom)
			)
		)
		(property "Value" "TPD4E05U06QDQARQ1"
			(at 0.018 2.499 180)
			(layer "F.Fab")
			(effects
				(font
					(size 0.7 0.7)
					(thickness 0.15)
				)
				(justify left bottom)
			)
		)
		(property "Description" "ESD protection"
			(at 0 0 180)
			(layer "F.Fab")
			(hide yes)
			(effects
				(font
					(size 1.27 1.27)
					(thickness 0.15)
				)
			)
		)
		(property "Author" "Antmicro"
			(at 520.2 202.5 0)
			(layer "F.Fab")
			(hide yes)
			(effects
				(font
					(size 1 1)
					(thickness 0.15)
				)
			)
		)
		(property "License" "Apache-2.0"
			(at 520.2 202.5 0)
			(layer "F.Fab")
			(hide yes)
			(effects
				(font
					(size 1 1)
					(thickness 0.15)
				)
			)
		)
		(property "MPN" "TPD4E05U06QDQARQ1"
			(at 520.2 202.5 0)
			(layer "F.Fab")
			(hide yes)
			(effects
				(font
					(size 1 1)
					(thickness 0.15)
				)
			)
		)
		(property "Manufacturer" "Texas Instruments"
			(at 520.2 202.5 0)
			(layer "F.Fab")
			(hide yes)
			(effects
				(font
					(size 1 1)
					(thickness 0.15)
				)
			)
		)
		(sheetname "USB PHY")
		(sheetfile "usb-phy.kicad_sch")
		(attr smd)
		(fp_line
			(start 0.498 1.398)
			(end -0.5 1.398)
			(stroke
				(width 0.15)
				(type solid)
			)
			(layer "F.SilkS")
		)
		(fp_line
			(start 0.498 -1.401)
			(end -0.5 -1.401)
			(stroke
				(width 0.15)
				(type solid)
			)
			(layer "F.SilkS")
		)
		(fp_circle
			(center -0.68 -1.27)
			(end -0.63 -1.27)
			(stroke
				(width 0.15)
				(type solid)
			)
			(fill yes)
			(layer "F.SilkS")
		)
		(fp_rect
			(start -0.8 -1.5)
			(end 0.8 1.499)
			(stroke
				(width 0.05)
				(type solid)
			)
			(fill no)
			(layer "F.CrtYd")
		)
		(fp_line
			(start 0.498 -1.25)
			(end 0.498 1.249)
			(stroke
				(width 0.15)
				(type solid)
			)
			(layer "F.Fab")
		)
		(fp_line
			(start 0.498 -1.25)
			(end -0.25 -1.25)
			(stroke
				(width 0.15)
				(type solid)
			)
			(layer "F.Fab")
		)
		(fp_line
			(start -0.25 -1.25)
			(end -0.5 -1)
			(stroke
				(width 0.15)
				(type solid)
			)
			(layer "F.Fab")
		)
		(fp_line
			(start -0.5 1.249)
			(end 0.498 1.249)
			(stroke
				(width 0.15)
				(type solid)
			)
			(layer "F.Fab")
		)
		(fp_line
			(start -0.5 -1)
			(end -0.5 1.249)
			(stroke
				(width 0.15)
				(type solid)
			)
			(layer "F.Fab")
		)
		(pad "1" smd roundrect
			(at -0.387 -1 90)
			(size 0.25 0.55)
			(layers "F.Cu" "F.Mask" "F.Paste")
			(roundrect_rratio 0.25)
			(net 835 "/USB PHY/USB_HOST_CONN_D-")
			(pintype "passive")
		)
		(pad "2" smd roundrect
			(at -0.387 -0.5 90)
			(size 0.25 0.55)
			(layers "F.Cu" "F.Mask" "F.Paste")
			(roundrect_rratio 0.25)
			(net 836 "/USB PHY/USB_HOST_CONN_D+")
			(pintype "passive")
		)
		(pad "3" smd roundrect
			(at -0.387 0 90)
			(size 0.4 0.55)
			(layers "F.Cu" "F.Mask" "F.Paste")
			(roundrect_rratio 0.25)
			(net 1 "GND")
			(pintype "power_in")
		)
		(pad "4" smd roundrect
			(at -0.387 0.498 90)
			(size 0.25 0.55)
			(layers "F.Cu" "F.Mask" "F.Paste")
			(roundrect_rratio 0.25)
			(net 705 "/USB PHY/USB_HOST_VBUS")
			(pintype "passive")
		)
		(pad "5" smd roundrect
			(at -0.387 0.998 90)
			(size 0.25 0.55)
			(layers "F.Cu" "F.Mask" "F.Paste")
			(roundrect_rratio 0.25)
			(net 1144 "unconnected-(U16-Pad5)")
			(pintype "passive+no_connect")
		)
		(pad "6" smd roundrect
			(at 0.385 0.998 90)
			(size 0.25 0.55)
			(layers "F.Cu" "F.Mask" "F.Paste")
			(roundrect_rratio 0.25)
			(net 1144 "unconnected-(U16-Pad5)")
			(pintype "passive+no_connect")
		)
		(pad "7" smd roundrect
			(at 0.385 0.498 90)
			(size 0.25 0.55)
			(layers "F.Cu" "F.Mask" "F.Paste")
			(roundrect_rratio 0.25)
			(net 705 "/USB PHY/USB_HOST_VBUS")
			(pintype "passive")
		)
		(pad "8" smd roundrect
			(at 0.385 0 90)
			(size 0.4 0.55)
			(layers "F.Cu" "F.Mask" "F.Paste")
			(roundrect_rratio 0.25)
			(net 1 "GND")
			(pintype "passive")
		)
		(pad "9" smd roundrect
			(at 0.385 -0.5 90)
			(size 0.25 0.55)
			(layers "F.Cu" "F.Mask" "F.Paste")
			(roundrect_rratio 0.25)
			(net 836 "/USB PHY/USB_HOST_CONN_D+")
			(pintype "passive")
		)
		(pad "10" smd roundrect
			(at 0.385 -1 90)
			(size 0.25 0.55)
			(layers "F.Cu" "F.Mask" "F.Paste")
			(roundrect_rratio 0.25)
			(net 835 "/USB PHY/USB_HOST_CONN_D-")
			(pintype "passive")
		)
	)
	(footprint "antmicro-footprints:Resonator_SMD_Abracon_ABM8G_3.2x2.5mm"
		(layer "F.Cu")
		(at 229.4 149.7 180)
		(property "Reference" "Y3"
			(at -0.5 -2.4 0)
			(layer "F.SilkS")
			(effects
				(font
					(size 0.7 0.7)
					(thickness 0.15)
				)
				(justify left bottom)
			)
		)
		(property "Value" "Resonator_25MHz_ABM8G"
			(at -1.75 2.548 180)
			(layer "F.Fab")
			(effects
				(font
					(size 0.7 0.7)
					(thickness 0.15)
				)
				(justify left bottom)
			)
		)
		(property "Description" "Crystal, 25 MHz, SMD, 3.2mm x 2.5mm, 30 ppm, 18 pF, 20 ppm, ABM8G"
			(at 0 0 180)
			(layer "F.Fab")
			(hide yes)
			(effects
				(font
					(size 1.27 1.27)
					(thickness 0.15)
				)
			)
		)
		(property "Author" "Antmicro"
			(at 458.8 299.4 0)
			(layer "F.Fab")
			(hide yes)
			(effects
				(font
					(size 1 1)
					(thickness 0.15)
				)
			)
		)
		(property "License" "Apache-2.0"
			(at 458.8 299.4 0)
			(layer "F.Fab")
			(hide yes)
			(effects
				(font
					(size 1 1)
					(thickness 0.15)
				)
			)
		)
		(property "MPN" "ABM8G-25.000MHZ-18-D2Y-T3"
			(at 458.8 299.4 0)
			(layer "F.Fab")
			(hide yes)
			(effects
				(font
					(size 1 1)
					(thickness 0.15)
				)
			)
		)
		(property "Manufacturer" "Abracon"
			(at 458.8 299.4 0)
			(layer "F.Fab")
			(hide yes)
			(effects
				(font
					(size 1 1)
					(thickness 0.15)
				)
			)
		)
		(property "Val" "25 MHz"
			(at 458.8 299.4 0)
			(layer "F.Fab")
			(hide yes)
			(effects
				(font
					(size 1 1)
					(thickness 0.15)
				)
			)
		)
		(sheetname "HDMI + Ethernet")
		(sheetfile "hdmi-ethernet.kicad_sch")
		(attr smd)
		(fp_line
			(start 1.6 0.3)
			(end 1.6 -0.2)
			(stroke
				(width 0.15)
				(type solid)
			)
			(layer "F.SilkS")
		)
		(fp_line
			(start -0.35 1.25)
			(end 0.45 1.25)
			(stroke
				(width 0.15)
				(type solid)
			)
			(layer "F.SilkS")
		)
		(fp_line
			(start -0.35 -1.25)
			(end 0.45 -1.25)
			(stroke
				(width 0.15)
				(type solid)
			)
			(layer "F.SilkS")
		)
		(fp_line
			(start -1.6 0.3)
			(end -1.6 -0.2)
			(stroke
				(width 0.15)
				(type solid)
			)
			(layer "F.SilkS")
		)
		(fp_circle
			(center -1.75 1.5)
			(end -1.7 1.5)
			(stroke
				(width 0.15)
				(type solid)
			)
			(fill no)
			(layer "F.SilkS")
		)
		(fp_rect
			(start -1.907 -1.55)
			(end 2.006 1.649)
			(stroke
				(width 0.05)
				(type solid)
			)
			(fill no)
			(layer "F.CrtYd")
		)
		(pad "1" smd roundrect
			(at -1.101 0.949 180)
			(size 1.3 1.1)
			(layers "F.Cu" "F.Mask" "F.Paste")
			(roundrect_rratio 0)
			(chamfer_ratio 0.2)
			(chamfer bottom_left)
			(net 716 "/HDMI + Ethernet/ETH_XI")
			(pintype "passive")
		)
		(pad "2" smd rect
			(at 1.199 0.949 180)
			(size 1.3 1.1)
			(layers "F.Cu" "F.Mask" "F.Paste")
			(net 1 "GND")
			(pinfunction "SH")
			(pintype "passive")
		)
		(pad "3" smd rect
			(at 1.199 -0.85 180)
			(size 1.3 1.1)
			(layers "F.Cu" "F.Mask" "F.Paste")
			(net 719 "/HDMI + Ethernet/ETH_XO")
			(pintype "passive")
		)
		(pad "4" smd rect
			(at -1.101 -0.85 180)
			(size 1.3 1.1)
			(layers "F.Cu" "F.Mask" "F.Paste")
			(net 1 "GND")
			(pinfunction "SH")
			(pintype "passive")
		)
	)
	(footprint "antmicro-footprints:R_0402_1005Metric"
		(layer "F.Cu")
		(at 259.6 129.7)
		(descr "Resistor SMD 0402")
		(tags "resistor SMD 0402")
		(property "Reference" "R192"
			(at -1.05 -6.05 0)
			(layer "F.SilkS")
			(effects
				(font
					(size 0.7 0.7)
					(thickness 0.15)
				)
				(justify left bottom)
			)
		)
		(property "Value" "R_10k_0402"
			(at 0 1.4 0)
			(layer "F.Fab")
			(effects
				(font
					(size 0.7 0.7)
					(thickness 0.15)
				)
				(justify left bottom)
			)
		)
		(property "Description" "SMD Chip Resistor, 10 kohm, ± 1%, 62.5 mW, 0402 [1005 Metric], Thick Film, General Purpose"
			(at 0 0 0)
			(layer "F.Fab")
			(hide yes)
			(effects
				(font
					(size 1.27 1.27)
					(thickness 0.15)
				)
			)
		)
		(property "Author" "Antmicro"
			(at 0 0 0)
			(layer "F.Fab")
			(hide yes)
			(effects
				(font
					(size 1 1)
					(thickness 0.15)
				)
			)
		)
		(property "License" "Apache-2.0"
			(at 0 0 0)
			(layer "F.Fab")
			(hide yes)
			(effects
				(font
					(size 1 1)
					(thickness 0.15)
				)
			)
		)
		(property "MPN" "CR0402-FX-1002GLF"
			(at 0 0 0)
			(layer "F.Fab")
			(hide yes)
			(effects
				(font
					(size 1 1)
					(thickness 0.15)
				)
			)
		)
		(property "Manufacturer" "Bourns"
			(at 0 0 0)
			(layer "F.Fab")
			(hide yes)
			(effects
				(font
					(size 1 1)
					(thickness 0.15)
				)
			)
		)
		(property "Tolerance" "1%"
			(at 0 0 0)
			(layer "F.Fab")
			(hide yes)
			(effects
				(font
					(size 1 1)
					(thickness 0.15)
				)
			)
		)
		(property "Val" "10k"
			(at 0 0 0)
			(layer "F.Fab")
			(hide yes)
			(effects
				(font
					(size 1 1)
					(thickness 0.15)
				)
			)
		)
		(sheetname "USB PHY")
		(sheetfile "usb-phy.kicad_sch")
		(attr smd)
		(fp_rect
			(start -0.925 -0.47)
			(end 0.925 0.47)
			(stroke
				(width 0.05)
				(type default)
			)
			(fill no)
			(layer "F.CrtYd")
		)
		(fp_rect
			(start -0.5 -0.25)
			(end 0.5 0.25)
			(stroke
				(width 0.15)
				(type solid)
			)
			(fill no)
			(layer "F.Fab")
		)
		(pad "1" smd roundrect
			(at -0.48 0)
			(size 0.59 0.64)
			(layers "F.Cu" "F.Mask" "F.Paste")
			(roundrect_rratio 0.25)
			(net 1 "GND")
			(pintype "passive")
		)
		(pad "2" smd roundrect
			(at 0.48 0)
			(size 0.59 0.64)
			(layers "F.Cu" "F.Mask" "F.Paste")
			(roundrect_rratio 0.25)
			(net 943 "Net-(R191-Pad1)")
			(pintype "passive")
		)
	)
	(footprint "antmicro-footprints:R_0402_1005Metric"
		(layer "F.Cu")
		(at 173.570001 84.257501)
		(descr "Resistor SMD 0402")
		(tags "resistor SMD 0402")
		(property "Reference" "R269"
			(at 0.929999 0.342499 0)
			(layer "F.SilkS")
			(effects
				(font
					(size 0.7 0.7)
					(thickness 0.15)
				)
				(justify left bottom)
			)
		)
		(property "Value" "R_33R_0402"
			(at 0 1.4 0)
			(layer "F.Fab")
			(effects
				(font
					(size 0.7 0.7)
					(thickness 0.15)
				)
				(justify left bottom)
			)
		)
		(property "Description" "SMD Chip Resistor, 33 ohm, ± 1%, 62.5 mW, 0402 [1005 Metric], Thick Film, General Purpose"
			(at 0 0 0)
			(layer "F.Fab")
			(hide yes)
			(effects
				(font
					(size 1.27 1.27)
					(thickness 0.15)
				)
			)
		)
		(property "Author" "Antmicro"
			(at 0 0 0)
			(layer "F.Fab")
			(hide yes)
			(effects
				(font
					(size 1 1)
					(thickness 0.15)
				)
			)
		)
		(property "License" "Apache-2.0"
			(at 0 0 0)
			(layer "F.Fab")
			(hide yes)
			(effects
				(font
					(size 1 1)
					(thickness 0.15)
				)
			)
		)
		(property "MPN" "CR0402-FX-33R0GLF"
			(at 0 0 0)
			(layer "F.Fab")
			(hide yes)
			(effects
				(font
					(size 1 1)
					(thickness 0.15)
				)
			)
		)
		(property "Manufacturer" "Bourns"
			(at 0 0 0)
			(layer "F.Fab")
			(hide yes)
			(effects
				(font
					(size 1 1)
					(thickness 0.15)
				)
			)
		)
		(property "Tolerance" "1%"
			(at 0 0 0)
			(layer "F.Fab")
			(hide yes)
			(effects
				(font
					(size 1 1)
					(thickness 0.15)
				)
			)
		)
		(property "Val" "33R"
			(at 0 0 0)
			(layer "F.Fab")
			(hide yes)
			(effects
				(font
					(size 1 1)
					(thickness 0.15)
				)
			)
		)
		(sheetname "FMC+ HSPC")
		(sheetfile "fmc-hspc.kicad_sch")
		(attr smd)
		(fp_rect
			(start -0.925 -0.47)
			(end 0.925 0.47)
			(stroke
				(width 0.05)
				(type default)
			)
			(fill no)
			(layer "F.CrtYd")
		)
		(fp_rect
			(start -0.5 -0.25)
			(end 0.5 0.25)
			(stroke
				(width 0.15)
				(type solid)
			)
			(fill no)
			(layer "F.Fab")
		)
		(pad "1" smd roundrect
			(at -0.48 0)
			(size 0.59 0.64)
			(layers "F.Cu" "F.Mask" "F.Paste")
			(roundrect_rratio 0.25)
			(net 627 "/FMC+ HSPC/GTR_REFCLK0_R_P")
			(pintype "passive")
		)
		(pad "2" smd roundrect
			(at 0.48 0)
			(size 0.59 0.64)
			(layers "F.Cu" "F.Mask" "F.Paste")
			(roundrect_rratio 0.25)
			(net 628 "/FMC+ HSPC/GTX115.REFCLK0_P")
			(pintype "passive")
		)
	)
	(footprint "antmicro-footprints:R_0402_1005Metric"
		(layer "F.Cu")
		(at 212.88 154.7 -90)
		(descr "Resistor SMD 0402")
		(tags "resistor SMD 0402")
		(property "Reference" "R72"
			(at -0.96 0.35 270)
			(layer "F.SilkS")
			(effects
				(font
					(size 0.7 0.7)
					(thickness 0.15)
				)
				(justify left bottom)
			)
		)
		(property "Value" "R_100R_0402"
			(at 0 1.4 270)
			(layer "F.Fab")
			(effects
				(font
					(size 0.7 0.7)
					(thickness 0.15)
				)
				(justify left bottom)
			)
		)
		(property "Description" "SMD Chip Resistor, 100 ohm, ± 1%, 62.5 mW, 0402 [1005 Metric], Thick Film, General Purpose"
			(at 0 0 270)
			(layer "F.Fab")
			(hide yes)
			(effects
				(font
					(size 1.27 1.27)
					(thickness 0.15)
				)
			)
		)
		(property "Author" "Antmicro"
			(at 58.18 367.58 0)
			(layer "F.Fab")
			(hide yes)
			(effects
				(font
					(size 1 1)
					(thickness 0.15)
				)
			)
		)
		(property "DNP" "DNP"
			(at 58.18 367.58 0)
			(layer "F.Fab")
			(hide yes)
			(effects
				(font
					(size 1 1)
					(thickness 0.15)
				)
			)
		)
		(property "License" "Apache-2.0"
			(at 58.18 367.58 0)
			(layer "F.Fab")
			(hide yes)
			(effects
				(font
					(size 1 1)
					(thickness 0.15)
				)
			)
		)
		(property "MPN" "CR0402-FX-1000GLF"
			(at 58.18 367.58 0)
			(layer "F.Fab")
			(hide yes)
			(effects
				(font
					(size 1 1)
					(thickness 0.15)
				)
			)
		)
		(property "Manufacturer" "Bourns"
			(at 58.18 367.58 0)
			(layer "F.Fab")
			(hide yes)
			(effects
				(font
					(size 1 1)
					(thickness 0.15)
				)
			)
		)
		(property "Tolerance" "1%"
			(at 58.18 367.58 0)
			(layer "F.Fab")
			(hide yes)
			(effects
				(font
					(size 1 1)
					(thickness 0.15)
				)
			)
		)
		(property "Val" "100R"
			(at 58.18 367.58 0)
			(layer "F.Fab")
			(hide yes)
			(effects
				(font
					(size 1 1)
					(thickness 0.15)
				)
			)
		)
		(property "dnp" ""
			(at 58.18 367.58 0)
			(layer "F.Fab")
			(hide yes)
			(effects
				(font
					(size 1 1)
					(thickness 0.15)
				)
			)
		)
		(property "exclude_from_bom" ""
			(at 58.18 367.58 0)
			(layer "F.Fab")
			(hide yes)
			(effects
				(font
					(size 1 1)
					(thickness 0.15)
				)
			)
		)
		(sheetname "SPI Flash + SD Card")
		(sheetfile "spi-flash.kicad_sch")
		(attr smd exclude_from_bom)
		(fp_rect
			(start -0.925 -0.47)
			(end 0.925 0.47)
			(stroke
				(width 0.05)
				(type default)
			)
			(fill no)
			(layer "F.CrtYd")
		)
		(fp_rect
			(start -0.5 -0.25)
			(end 0.5 0.25)
			(stroke
				(width 0.15)
				(type solid)
			)
			(fill no)
			(layer "F.Fab")
		)
		(pad "1" smd roundrect
			(at -0.48 0 270)
			(size 0.59 0.64)
			(layers "F.Cu" "F.Mask" "F.Paste")
			(roundrect_rratio 0.25)
			(net 408 "/FPGA Bank 33 & 34/USR_FLASH_0.CLK")
			(pintype "passive")
		)
		(pad "2" smd roundrect
			(at 0.48 0 270)
			(size 0.59 0.64)
			(layers "F.Cu" "F.Mask" "F.Paste")
			(roundrect_rratio 0.25)
			(net 26 "+1V8")
			(pintype "passive")
		)
	)
	(footprint "antmicro-footprints:R_0603_1608Metric"
		(layer "F.Cu")
		(at 174.9 162.5)
		(descr "Resistor SMD 0603")
		(tags "resistor SMD 0603")
		(property "Reference" "R289"
			(at -3.85 0.35 0)
			(layer "F.SilkS")
			(effects
				(font
					(size 0.7 0.7)
					(thickness 0.15)
				)
				(justify left bottom)
			)
		)
		(property "Value" "R_0R_22.4A_0603"
			(at 0 1.6 0)
			(layer "F.Fab")
			(effects
				(font
					(size 0.7 0.7)
					(thickness 0.15)
				)
				(justify left bottom)
			)
		)
		(property "Description" "SMD Chip Resistor"
			(at 0 0 0)
			(layer "F.Fab")
			(hide yes)
			(effects
				(font
					(size 1.27 1.27)
					(thickness 0.15)
				)
			)
		)
		(property "Author" "Antmicro"
			(at 0 0 0)
			(layer "F.Fab")
			(hide yes)
			(effects
				(font
					(size 1 1)
					(thickness 0.15)
				)
			)
		)
		(property "License" "Apache-2.0"
			(at 0 0 0)
			(layer "F.Fab")
			(hide yes)
			(effects
				(font
					(size 1 1)
					(thickness 0.15)
				)
			)
		)
		(property "MPN" "PMR03EZPJ000"
			(at 0 0 0)
			(layer "F.Fab")
			(hide yes)
			(effects
				(font
					(size 1 1)
					(thickness 0.15)
				)
			)
		)
		(property "Manufacturer" "ROHM Semiconductor"
			(at 0 0 0)
			(layer "F.Fab")
			(hide yes)
			(effects
				(font
					(size 1 1)
					(thickness 0.15)
				)
			)
		)
		(property "Max. Curr." "22.4A"
			(at 0 0 0)
			(layer "F.Fab")
			(hide yes)
			(effects
				(font
					(size 1 1)
					(thickness 0.15)
				)
			)
		)
		(property "Tolerance" "template_tolerance"
			(at 0 0 0)
			(layer "F.Fab")
			(hide yes)
			(effects
				(font
					(size 1 1)
					(thickness 0.15)
				)
			)
		)
		(property "Val" "0R"
			(at 0 0 0)
			(layer "F.Fab")
			(hide yes)
			(effects
				(font
					(size 1 1)
					(thickness 0.15)
				)
			)
		)
		(sheetname "DC-DC Converters")
		(sheetfile "dc-dc.kicad_sch")
		(attr smd)
		(fp_line
			(start -0.15 -0.4)
			(end 0.15 -0.4)
			(stroke
				(width 0.15)
				(type solid)
			)
			(layer "F.SilkS")
		)
		(fp_line
			(start -0.15 0.4)
			(end 0.15 0.4)
			(stroke
				(width 0.15)
				(type solid)
			)
			(layer "F.SilkS")
		)
		(fp_rect
			(start -1.25 -0.65)
			(end 1.25 0.65)
			(stroke
				(width 0.05)
				(type solid)
			)
			(fill no)
			(layer "F.CrtYd")
		)
		(fp_rect
			(start -0.8 -0.4)
			(end 0.8 0.4)
			(stroke
				(width 0.15)
				(type solid)
			)
			(fill no)
			(layer "F.Fab")
		)
		(pad "1" smd roundrect
			(at -0.7 0)
			(size 0.8 1)
			(layers "F.Cu" "F.Mask" "F.Paste")
			(roundrect_rratio 0.2)
			(net 735 "/DC-DC Converters/3V3_local")
			(pintype "passive")
		)
		(pad "2" smd roundrect
			(at 0.7 0)
			(size 0.8 1)
			(layers "F.Cu" "F.Mask" "F.Paste")
			(roundrect_rratio 0.2)
			(net 24 "+3V3")
			(pintype "passive")
		)
	)
	(footprint "antmicro-footprints:C_0402_1005Metric"
		(layer "F.Cu")
		(at 194.501 101.949 90)
		(descr "Capacitor SMD 0402")
		(tags "capacitor SMD 0402")
		(property "Reference" "C223"
			(at -1.351 -0.501 90)
			(layer "F.SilkS")
			(effects
				(font
					(size 0.7 0.7)
					(thickness 0.15)
				)
				(justify left bottom)
			)
		)
		(property "Value" "C_22p_0402"
			(at 0 1.4 90)
			(layer "F.Fab")
			(effects
				(font
					(size 0.7 0.7)
					(thickness 0.15)
				)
				(justify left bottom)
			)
		)
		(property "Description" "SMD Multilayer Ceramic Capacitor, 22 pF, 50 V, 0402 [1005 Metric], ± 5%, C0G / NP0, CC Series"
			(at 0 0 90)
			(layer "F.Fab")
			(hide yes)
			(effects
				(font
					(size 1.27 1.27)
					(thickness 0.15)
				)
			)
		)
		(property "Author" "Antmicro"
			(at 296.45 -92.552 0)
			(layer "F.Fab")
			(hide yes)
			(effects
				(font
					(size 1 1)
					(thickness 0.15)
				)
			)
		)
		(property "Dielectric" ""
			(at 296.45 -92.552 0)
			(layer "F.Fab")
			(hide yes)
			(effects
				(font
					(size 1 1)
					(thickness 0.15)
				)
			)
		)
		(property "License" "Apache-2.0"
			(at 296.45 -92.552 0)
			(layer "F.Fab")
			(hide yes)
			(effects
				(font
					(size 1 1)
					(thickness 0.15)
				)
			)
		)
		(property "MPN" "CC0402JRNPO9BN220"
			(at 296.45 -92.552 0)
			(layer "F.Fab")
			(hide yes)
			(effects
				(font
					(size 1 1)
					(thickness 0.15)
				)
			)
		)
		(property "Manufacturer" "YAGEO"
			(at 296.45 -92.552 0)
			(layer "F.Fab")
			(hide yes)
			(effects
				(font
					(size 1 1)
					(thickness 0.15)
				)
			)
		)
		(property "Val" "22p"
			(at 296.45 -92.552 0)
			(layer "F.Fab")
			(hide yes)
			(effects
				(font
					(size 1 1)
					(thickness 0.15)
				)
			)
		)
		(property "Voltage" ""
			(at 296.45 -92.552 0)
			(layer "F.Fab")
			(hide yes)
			(effects
				(font
					(size 1 1)
					(thickness 0.15)
				)
			)
		)
		(sheetname "USB PHY")
		(sheetfile "usb-phy.kicad_sch")
		(attr smd)
		(fp_rect
			(start -0.925 -0.47)
			(end 0.925 0.47)
			(stroke
				(width 0.05)
				(type default)
			)
			(fill no)
			(layer "F.CrtYd")
		)
		(fp_line
			(start 0.504 -0.25)
			(end 0.504 0.248)
			(stroke
				(width 0.15)
				(type solid)
			)
			(layer "F.Fab")
		)
		(fp_line
			(start -0.494 -0.25)
			(end 0.504 -0.25)
			(stroke
				(width 0.15)
				(type solid)
			)
			(layer "F.Fab")
		)
		(fp_line
			(start 0.504 0.248)
			(end -0.494 0.248)
			(stroke
				(width 0.15)
				(type solid)
			)
			(layer "F.Fab")
		)
		(fp_line
			(start -0.494 0.248)
			(end -0.494 -0.25)
			(stroke
				(width 0.15)
				(type solid)
			)
			(layer "F.Fab")
		)
		(pad "1" smd roundrect
			(at -0.48 0 90)
			(size 0.59 0.64)
			(layers "F.Cu" "F.Mask" "F.Paste")
			(roundrect_rratio 0.25)
			(net 1 "GND")
			(pintype "passive")
		)
		(pad "2" smd roundrect
			(at 0.48 0 90)
			(size 0.59 0.64)
			(layers "F.Cu" "F.Mask" "F.Paste")
			(roundrect_rratio 0.25)
			(net 708 "/USB PHY/USB_HOST_XO")
			(pintype "passive")
		)
	)
	(footprint "antmicro-footprints:SOT-886"
		(layer "F.Cu")
		(at 155.6 149.9)
		(property "Reference" "U47"
			(at -0.45 1.55 0)
			(layer "F.SilkS")
			(effects
				(font
					(size 0.7 0.7)
					(thickness 0.15)
				)
				(justify left bottom)
			)
		)
		(property "Value" "74LVC1T45GM"
			(at -2.492 1.647 0)
			(layer "F.Fab")
			(effects
				(font
					(size 0.7 0.7)
					(thickness 0.15)
				)
				(justify left bottom)
			)
		)
		(property "Description" "Transceiver, Translating, 74LVC1T45, 74LVC Family, 1.2V to 5.5V Supply, XSON-6"
			(at 0 0 0)
			(layer "F.Fab")
			(hide yes)
			(effects
				(font
					(size 1.27 1.27)
					(thickness 0.15)
				)
			)
		)
		(property "Author" "Antmicro"
			(at 0 0 0)
			(layer "F.Fab")
			(hide yes)
			(effects
				(font
					(size 1 1)
					(thickness 0.15)
				)
			)
		)
		(property "License" "Apache-2.0"
			(at 0 0 0)
			(layer "F.Fab")
			(hide yes)
			(effects
				(font
					(size 1 1)
					(thickness 0.15)
				)
			)
		)
		(property "MPN" "74LVC1T45GM-Q100X"
			(at 0 0 0)
			(layer "F.Fab")
			(hide yes)
			(effects
				(font
					(size 1 1)
					(thickness 0.15)
				)
			)
		)
		(property "Manufacturer" "Nexperia"
			(at 0 0 0)
			(layer "F.Fab")
			(hide yes)
			(effects
				(font
					(size 1 1)
					(thickness 0.15)
				)
			)
		)
		(sheetname "DC-DC Converters")
		(sheetfile "dc-dc.kicad_sch")
		(attr smd)
		(fp_line
			(start -0.843 -0.491)
			(end -0.843 0.183)
			(stroke
				(width 0.15)
				(type solid)
			)
			(layer "F.SilkS")
		)
		(fp_line
			(start 0.858 -0.491)
			(end 0.858 0.509)
			(stroke
				(width 0.15)
				(type solid)
			)
			(layer "F.SilkS")
		)
		(fp_circle
			(center -0.493 0.847)
			(end -0.443 0.847)
			(stroke
				(width 0.15)
				(type solid)
			)
			(fill yes)
			(layer "F.SilkS")
		)
		(fp_rect
			(start -1.23 -1)
			(end 1.22 0.99)
			(stroke
				(width 0.05)
				(type solid)
			)
			(fill no)
			(layer "F.CrtYd")
		)
		(fp_line
			(start -0.843 -0.616)
			(end -0.843 0.634)
			(stroke
				(width 0.15)
				(type solid)
			)
			(layer "F.Fab")
		)
		(fp_line
			(start -0.843 -0.616)
			(end 0.858 -0.616)
			(stroke
				(width 0.15)
				(type solid)
			)
			(layer "F.Fab")
		)
		(fp_line
			(start -0.843 0.434)
			(end -0.644 0.634)
			(stroke
				(width 0.15)
				(type solid)
			)
			(layer "F.Fab")
		)
		(fp_line
			(start 0.858 -0.616)
			(end 0.858 0.634)
			(stroke
				(width 0.15)
				(type solid)
			)
			(layer "F.Fab")
		)
		(fp_line
			(start 0.858 0.634)
			(end -0.843 0.634)
			(stroke
				(width 0.15)
				(type solid)
			)
			(layer "F.Fab")
		)
		(pad "1" smd rect
			(at -0.493 0.347)
			(size 0.27 0.325)
			(layers "F.Cu" "F.Mask" "F.Paste")
			(net 24 "+3V3")
			(pinfunction "VCCA")
			(pintype "power_in")
			(solder_mask_margin 0.05)
		)
		(pad "2" smd rect
			(at 0.005 0.347)
			(size 0.27 0.325)
			(layers "F.Cu" "F.Mask" "F.Paste")
			(net 1 "GND")
			(pinfunction "GND")
			(pintype "power_in")
			(solder_mask_margin 0.05)
		)
		(pad "3" smd rect
			(at 0.505 0.347)
			(size 0.27 0.325)
			(layers "F.Cu" "F.Mask" "F.Paste")
			(net 1191 "/DC-DC Converters/+0V675_EN")
			(pinfunction "A")
			(pintype "bidirectional")
			(solder_mask_margin 0.05)
		)
		(pad "4" smd rect
			(at 0.505 -0.33 180)
			(size 0.27 0.325)
			(layers "F.Cu" "F.Mask" "F.Paste")
			(net 25 "+1V35")
			(pinfunction "B")
			(pintype "bidirectional")
			(solder_mask_margin 0.05)
		)
		(pad "5" smd rect
			(at 0.005 -0.33 180)
			(size 0.27 0.325)
			(layers "F.Cu" "F.Mask" "F.Paste")
			(net 1 "GND")
			(pinfunction "DIR")
			(pintype "input")
			(solder_mask_margin 0.05)
		)
		(pad "6" smd rect
			(at -0.493 -0.33 180)
			(size 0.27 0.325)
			(layers "F.Cu" "F.Mask" "F.Paste")
			(net 25 "+1V35")
			(pinfunction "VCCB")
			(pintype "power_in")
			(solder_mask_margin 0.05)
		)
	)
	(footprint "antmicro-footprints:LED_0603_1608Metric_G"
		(layer "F.Cu")
		(at 261.5 86.2)
		(descr "LED SMD 0603 Green")
		(tags "LED SMD 0603 Green")
		(property "Reference" "D19"
			(at -1.05 1.5 0)
			(layer "F.SilkS")
			(effects
				(font
					(size 0.7 0.7)
					(thickness 0.15)
				)
				(justify left bottom)
			)
		)
		(property "Value" "LED_G_0603_KP-1608CGCK"
			(at 0 1.6 0)
			(layer "F.Fab")
			(effects
				(font
					(size 0.7 0.7)
					(thickness 0.15)
				)
				(justify left bottom)
			)
		)
		(property "Description" "LED, Green, SMD, 0603, 20 mA, 2.1 V, 570 nm"
			(at 0 0 0)
			(layer "F.Fab")
			(hide yes)
			(effects
				(font
					(size 1.27 1.27)
					(thickness 0.15)
				)
			)
		)
		(property "Author" "Antmicro"
			(at 0 0 0)
			(layer "F.Fab")
			(hide yes)
			(effects
				(font
					(size 1 1)
					(thickness 0.15)
				)
			)
		)
		(property "Color" "Green"
			(at 0 0 0)
			(layer "F.Fab")
			(hide yes)
			(effects
				(font
					(size 1 1)
					(thickness 0.15)
				)
			)
		)
		(property "License" "Apache-2.0"
			(at 0 0 0)
			(layer "F.Fab")
			(hide yes)
			(effects
				(font
					(size 1 1)
					(thickness 0.15)
				)
			)
		)
		(property "MPN" "KP-1608CGCK"
			(at 0 0 0)
			(layer "F.Fab")
			(hide yes)
			(effects
				(font
					(size 1 1)
					(thickness 0.15)
				)
			)
		)
		(property "Manufacturer" "Kingbright"
			(at 0 0 0)
			(layer "F.Fab")
			(hide yes)
			(effects
				(font
					(size 1 1)
					(thickness 0.15)
				)
			)
		)
		(sheetname "User GPIO + LED + button + DIP switch")
		(sheetfile "user-gpio.kicad_sch")
		(attr smd)
		(fp_line
			(start -1.18 -0.319)
			(end -1.18 0.321)
			(stroke
				(width 0.15)
				(type solid)
			)
			(layer "F.SilkS")
		)
		(fp_line
			(start -0.094672 0.001008)
			(end -0.24 0.001008)
			(stroke
				(width 0.1)
				(type solid)
			)
			(layer "F.SilkS")
		)
		(fp_line
			(start -0.094672 0.001008)
			(end 0.105328 -0.198992)
			(stroke
				(width 0.1)
				(type solid)
			)
			(layer "F.SilkS")
		)
		(fp_line
			(start -0.094672 0.201008)
			(end -0.094672 -0.198992)
			(stroke
				(width 0.1)
				(type solid)
			)
			(layer "F.SilkS")
		)
		(fp_line
			(start 0.105328 0.001008)
			(end 0.24 0.001)
			(stroke
				(width 0.1)
				(type solid)
			)
			(layer "F.SilkS")
		)
		(fp_line
			(start 0.105328 0.201008)
			(end -0.094672 0.001008)
			(stroke
				(width 0.1)
				(type solid)
			)
			(layer "F.SilkS")
		)
		(fp_line
			(start 0.105328 0.201008)
			(end 0.105328 -0.198992)
			(stroke
				(width 0.1)
				(type solid)
			)
			(layer "F.SilkS")
		)
		(fp_line
			(start 0.22 -0.35)
			(end -0.22 -0.35)
			(stroke
				(width 0.15)
				(type solid)
			)
			(layer "F.SilkS")
		)
		(fp_line
			(start 0.22 0.35)
			(end -0.22 0.35)
			(stroke
				(width 0.15)
				(type solid)
			)
			(layer "F.SilkS")
		)
		(fp_rect
			(start 1.25 0.65)
			(end -1.25 -0.65)
			(stroke
				(width 0.05)
				(type solid)
			)
			(fill no)
			(layer "F.CrtYd")
		)
		(fp_line
			(start -0.199 -0.202)
			(end -0.199 0.1)
			(stroke
				(width 0.15)
				(type solid)
			)
			(layer "F.Fab")
		)
		(fp_line
			(start -0.199 0)
			(end -0.597 0)
			(stroke
				(width 0.15)
				(type solid)
			)
			(layer "F.Fab")
		)
		(fp_line
			(start -0.199 0.2)
			(end -0.199 0.1)
			(stroke
				(width 0.15)
				(type solid)
			)
			(layer "F.Fab")
		)
		(fp_line
			(start -0.101 0)
			(end 0.201 0.2)
			(stroke
				(width 0.15)
				(type solid)
			)
			(layer "F.Fab")
		)
		(fp_line
			(start 0.201 -0.202)
			(end -0.101 0)
			(stroke
				(width 0.15)
				(type solid)
			)
			(layer "F.Fab")
		)
		(fp_line
			(start 0.201 0)
			(end 0.201 -0.202)
			(stroke
				(width 0.15)
				(type solid)
			)
			(layer "F.Fab")
		)
		(fp_line
			(start 0.201 0.2)
			(end 0.201 0)
			(stroke
				(width 0.15)
				(type solid)
			)
			(layer "F.Fab")
		)
		(fp_line
			(start 0.599 0)
			(end 0.201 0)
			(stroke
				(width 0.15)
				(type solid)
			)
			(layer "F.Fab")
		)
		(fp_rect
			(start 0.848 0.4)
			(end -0.85 -0.402)
			(stroke
				(width 0.15)
				(type solid)
			)
			(fill no)
			(layer "F.Fab")
		)
		(pad "1" smd roundrect
			(at -0.7 0 180)
			(size 0.8 1)
			(layers "F.Cu" "F.Mask" "F.Paste")
			(roundrect_rratio 0.2)
			(net 21 "Net-(D19-C)")
			(pinfunction "C")
			(pintype "passive")
		)
		(pad "2" smd roundrect
			(at 0.7 0 180)
			(size 0.8 1)
			(layers "F.Cu" "F.Mask" "F.Paste")
			(roundrect_rratio 0.2)
			(net 777 "Net-(D19-A)")
			(pinfunction "A")
			(pintype "passive")
		)
	)
	(footprint "antmicro-footprints:R_0402_1005Metric"
		(layer "F.Cu")
		(at 219.2 142.4 180)
		(descr "Resistor SMD 0402")
		(tags "resistor SMD 0402")
		(property "Reference" "R337"
			(at 3.65 -0.4 180)
			(layer "F.SilkS")
			(effects
				(font
					(size 0.7 0.7)
					(thickness 0.15)
				)
				(justify left bottom)
			)
		)
		(property "Value" "R_22R_0402"
			(at 0 1.4 180)
			(layer "F.Fab")
			(effects
				(font
					(size 0.7 0.7)
					(thickness 0.15)
				)
				(justify left bottom)
			)
		)
		(property "Description" "SMD Chip Resistor, 22 ohm, ± 1%, 62.5 mW, 0402 [1005 Metric], Thick Film, General Purpose"
			(at 0 0 180)
			(layer "F.Fab")
			(hide yes)
			(effects
				(font
					(size 1.27 1.27)
					(thickness 0.15)
				)
			)
		)
		(property "Author" "Antmicro"
			(at 438.4 284.8 0)
			(layer "F.Fab")
			(hide yes)
			(effects
				(font
					(size 1 1)
					(thickness 0.15)
				)
			)
		)
		(property "License" "Apache-2.0"
			(at 438.4 284.8 0)
			(layer "F.Fab")
			(hide yes)
			(effects
				(font
					(size 1 1)
					(thickness 0.15)
				)
			)
		)
		(property "MPN" "CR0402-FX-22R0GLF"
			(at 438.4 284.8 0)
			(layer "F.Fab")
			(hide yes)
			(effects
				(font
					(size 1 1)
					(thickness 0.15)
				)
			)
		)
		(property "Manufacturer" "Bourns"
			(at 438.4 284.8 0)
			(layer "F.Fab")
			(hide yes)
			(effects
				(font
					(size 1 1)
					(thickness 0.15)
				)
			)
		)
		(property "Tolerance" "1%"
			(at 438.4 284.8 0)
			(layer "F.Fab")
			(hide yes)
			(effects
				(font
					(size 1 1)
					(thickness 0.15)
				)
			)
		)
		(property "Val" "22R"
			(at 438.4 284.8 0)
			(layer "F.Fab")
			(hide yes)
			(effects
				(font
					(size 1 1)
					(thickness 0.15)
				)
			)
		)
		(sheetname "Clocks")
		(sheetfile "clocks.kicad_sch")
		(attr smd)
		(fp_rect
			(start -0.925 -0.47)
			(end 0.925 0.47)
			(stroke
				(width 0.05)
				(type default)
			)
			(fill no)
			(layer "F.CrtYd")
		)
		(fp_rect
			(start -0.5 -0.25)
			(end 0.5 0.25)
			(stroke
				(width 0.15)
				(type solid)
			)
			(fill no)
			(layer "F.Fab")
		)
		(pad "1" smd roundrect
			(at -0.48 0 180)
			(size 0.59 0.64)
			(layers "F.Cu" "F.Mask" "F.Paste")
			(roundrect_rratio 0.25)
			(net 973 "/Clocks/PLL_Y4")
			(pintype "passive")
		)
		(pad "2" smd roundrect
			(at 0.48 0 180)
			(size 0.59 0.64)
			(layers "F.Cu" "F.Mask" "F.Paste")
			(roundrect_rratio 0.25)
			(net 1403 "/PLL.CLK1")
			(pintype "passive")
		)
	)
	(footprint "antmicro-footprints:C_0603_1608Metric"
		(layer "F.Cu")
		(at 157.95 165.55 180)
		(descr "Capacitor SMD 0603")
		(tags "capacitor 0603")
		(property "Reference" "C322"
			(at 1.05 -0.4 0)
			(layer "F.SilkS")
			(effects
				(font
					(size 0.7 0.7)
					(thickness 0.15)
				)
				(justify right bottom)
			)
		)
		(property "Value" "C_22u_0603"
			(at 0 1.6 0)
			(layer "F.Fab")
			(effects
				(font
					(size 0.7 0.7)
					(thickness 0.15)
				)
				(justify right bottom)
			)
		)
		(property "Description" "SMD Multilayer Ceramic Capacitor, 22 µF, 6.3 V, 0603 [1608 Metric], ± 20%, X5R, GRM Series"
			(at 0 0 180)
			(layer "F.Fab")
			(hide yes)
			(effects
				(font
					(size 1.27 1.27)
					(thickness 0.15)
				)
			)
		)
		(property "Author" "Antmicro"
			(at 315.9 331.1 0)
			(layer "F.Fab")
			(hide yes)
			(effects
				(font
					(size 1 1)
					(thickness 0.15)
				)
			)
		)
		(property "Dielectric" ""
			(at 315.9 331.1 0)
			(layer "F.Fab")
			(hide yes)
			(effects
				(font
					(size 1 1)
					(thickness 0.15)
				)
			)
		)
		(property "License" "Apache-2.0"
			(at 315.9 331.1 0)
			(layer "F.Fab")
			(hide yes)
			(effects
				(font
					(size 1 1)
					(thickness 0.15)
				)
			)
		)
		(property "MPN" "GRM188R60J226MEA0D"
			(at 315.9 331.1 0)
			(layer "F.Fab")
			(hide yes)
			(effects
				(font
					(size 1 1)
					(thickness 0.15)
				)
			)
		)
		(property "Manufacturer" "Murata"
			(at 315.9 331.1 0)
			(layer "F.Fab")
			(hide yes)
			(effects
				(font
					(size 1 1)
					(thickness 0.15)
				)
			)
		)
		(property "Val" "22u"
			(at 315.9 331.1 0)
			(layer "F.Fab")
			(hide yes)
			(effects
				(font
					(size 1 1)
					(thickness 0.15)
				)
			)
		)
		(property "Voltage" ""
			(at 315.9 331.1 0)
			(layer "F.Fab")
			(hide yes)
			(effects
				(font
					(size 1 1)
					(thickness 0.15)
				)
			)
		)
		(sheetname "DC-DC Converters")
		(sheetfile "dc-dc.kicad_sch")
		(attr smd)
		(fp_line
			(start -0.15 0.4)
			(end 0.15 0.4)
			(stroke
				(width 0.15)
				(type solid)
			)
			(layer "F.SilkS")
		)
		(fp_line
			(start -0.15 -0.4)
			(end 0.15 -0.4)
			(stroke
				(width 0.15)
				(type solid)
			)
			(layer "F.SilkS")
		)
		(fp_rect
			(start -1.25 -0.65)
			(end 1.25 0.65)
			(stroke
				(width 0.05)
				(type solid)
			)
			(fill no)
			(layer "F.CrtYd")
		)
		(fp_rect
			(start -0.8 -0.4)
			(end 0.8 0.4)
			(stroke
				(width 0.15)
				(type solid)
			)
			(fill no)
			(layer "F.Fab")
		)
		(pad "1" smd roundrect
			(at -0.7 0 180)
			(size 0.8 1)
			(layers "F.Cu" "F.Mask" "F.Paste")
			(roundrect_rratio 0.2)
			(net 1 "GND")
			(pintype "passive")
		)
		(pad "2" smd roundrect
			(at 0.7 0 180)
			(size 0.8 1)
			(layers "F.Cu" "F.Mask" "F.Paste")
			(roundrect_rratio 0.2)
			(net 733 "/DC-DC Converters/MGTAVCC_local")
			(pintype "passive")
		)
	)
	(footprint "antmicro-footprints:C_0402_1005Metric"
		(layer "F.Cu")
		(at 200.253752 99.3615 90)
		(descr "Capacitor SMD 0402")
		(tags "capacitor SMD 0402")
		(property "Reference" "C259"
			(at -9.3385 5.546248 90)
			(layer "F.SilkS")
			(effects
				(font
					(size 0.7 0.7)
					(thickness 0.15)
				)
				(justify left bottom)
			)
		)
		(property "Value" "C_100n_0402"
			(at 0 1.169 90)
			(layer "F.Fab")
			(effects
				(font
					(size 0.7 0.7)
					(thickness 0.15)
				)
				(justify left bottom)
			)
		)
		(property "Description" "SMD Multilayer Ceramic Capacitor, 0.1 µF, 50 V, 0402 [1005 Metric], ± 10%, X5R, GRM Series"
			(at 0 0 90)
			(layer "F.Fab")
			(hide yes)
			(effects
				(font
					(size 1.27 1.27)
					(thickness 0.15)
				)
			)
		)
		(property "Author" "Antmicro"
			(at 299.615252 -100.892252 0)
			(layer "F.Fab")
			(hide yes)
			(effects
				(font
					(size 1 1)
					(thickness 0.15)
				)
			)
		)
		(property "Dielectric" "X5R"
			(at 299.615252 -100.892252 0)
			(layer "F.Fab")
			(hide yes)
			(effects
				(font
					(size 1 1)
					(thickness 0.15)
				)
			)
		)
		(property "License" "Apache-2.0"
			(at 299.615252 -100.892252 0)
			(layer "F.Fab")
			(hide yes)
			(effects
				(font
					(size 1 1)
					(thickness 0.15)
				)
			)
		)
		(property "MPN" "GRM155R61H104KE14D"
			(at 299.615252 -100.892252 0)
			(layer "F.Fab")
			(hide yes)
			(effects
				(font
					(size 1 1)
					(thickness 0.15)
				)
			)
		)
		(property "Manufacturer" "Murata"
			(at 299.615252 -100.892252 0)
			(layer "F.Fab")
			(hide yes)
			(effects
				(font
					(size 1 1)
					(thickness 0.15)
				)
			)
		)
		(property "Val" "100n"
			(at 299.615252 -100.892252 0)
			(layer "F.Fab")
			(hide yes)
			(effects
				(font
					(size 1 1)
					(thickness 0.15)
				)
			)
		)
		(property "Voltage" "50V"
			(at 299.615252 -100.892252 0)
			(layer "F.Fab")
			(hide yes)
			(effects
				(font
					(size 1 1)
					(thickness 0.15)
				)
			)
		)
		(sheetname "HDMI + Ethernet")
		(sheetfile "hdmi-ethernet.kicad_sch")
		(attr smd)
		(fp_rect
			(start -0.925 -0.47)
			(end 0.925 0.47)
			(stroke
				(width 0.05)
				(type default)
			)
			(fill no)
			(layer "F.CrtYd")
		)
		(fp_line
			(start 0.504 -0.25)
			(end 0.504 0.248)
			(stroke
				(width 0.15)
				(type solid)
			)
			(layer "F.Fab")
		)
		(fp_line
			(start -0.494 -0.25)
			(end 0.504 -0.25)
			(stroke
				(width 0.15)
				(type solid)
			)
			(layer "F.Fab")
		)
		(fp_line
			(start 0.504 0.248)
			(end -0.494 0.248)
			(stroke
				(width 0.15)
				(type solid)
			)
			(layer "F.Fab")
		)
		(fp_line
			(start -0.494 0.248)
			(end -0.494 -0.25)
			(stroke
				(width 0.15)
				(type solid)
			)
			(layer "F.Fab")
		)
		(pad "1" smd roundrect
			(at -0.48 0 90)
			(size 0.59 0.64)
			(layers "F.Cu" "F.Mask" "F.Paste")
			(roundrect_rratio 0.25)
			(net 1 "GND")
			(pintype "passive")
		)
		(pad "2" smd roundrect
			(at 0.48 0 90)
			(size 0.59 0.64)
			(layers "F.Cu" "F.Mask" "F.Paste")
			(roundrect_rratio 0.25)
			(net 24 "+3V3")
			(pintype "passive")
		)
	)
	(footprint "antmicro-footprints:QFN-48-1EP_7x7x0.9mm_P0.5mm_EP5x5mm"
		(layer "F.Cu")
		(at 201.449 93.849 180)
		(property "Reference" "U27"
			(at 4.939 -5.411 180)
			(layer "F.SilkS")
			(effects
				(font
					(size 0.7 0.7)
					(thickness 0.15)
				)
				(justify left bottom)
			)
		)
		(property "Value" "KSZ9131RNXC"
			(at -10.55 5.55 180)
			(layer "F.Fab")
			(effects
				(font
					(size 0.7 0.7)
					(thickness 0.15)
				)
				(justify left bottom)
			)
		)
		(property "Description" "Ethernet ICs Gigabit Ethernet Transceiver with RGMII support"
			(at 0 0 180)
			(layer "F.Fab")
			(hide yes)
			(effects
				(font
					(size 1.27 1.27)
					(thickness 0.15)
				)
			)
		)
		(property "Author" "Antmicro"
			(at 402.898 187.698 0)
			(layer "F.Fab")
			(hide yes)
			(effects
				(font
					(size 1 1)
					(thickness 0.15)
				)
			)
		)
		(property "License" "Apache-2.0"
			(at 402.898 187.698 0)
			(layer "F.Fab")
			(hide yes)
			(effects
				(font
					(size 1 1)
					(thickness 0.15)
				)
			)
		)
		(property "MPN" "KSZ9131RNXC"
			(at 402.898 187.698 0)
			(layer "F.Fab")
			(hide yes)
			(effects
				(font
					(size 1 1)
					(thickness 0.15)
				)
			)
		)
		(property "Manufacturer" "Microchip Technology"
			(at 402.898 187.698 0)
			(layer "F.Fab")
			(hide yes)
			(effects
				(font
					(size 1 1)
					(thickness 0.15)
				)
			)
		)
		(sheetname "HDMI + Ethernet")
		(sheetfile "hdmi-ethernet.kicad_sch")
		(attr smd)
		(fp_line
			(start 3.648 3.648)
			(end 3.648 3.249)
			(stroke
				(width 0.15)
				(type solid)
			)
			(layer "F.SilkS")
		)
		(fp_line
			(start 3.648 -3.65)
			(end 3.648 -3.25)
			(stroke
				(width 0.15)
				(type solid)
			)
			(layer "F.SilkS")
		)
		(fp_line
			(start 3.249 3.648)
			(end 3.648 3.648)
			(stroke
				(width 0.15)
				(type solid)
			)
			(layer "F.SilkS")
		)
		(fp_line
			(start 3.249 -3.65)
			(end 3.648 -3.65)
			(stroke
				(width 0.15)
				(type solid)
			)
			(layer "F.SilkS")
		)
		(fp_line
			(start -3.25 3.648)
			(end -3.65 3.648)
			(stroke
				(width 0.15)
				(type solid)
			)
			(layer "F.SilkS")
		)
		(fp_line
			(start -3.25 -3.65)
			(end -3.951 -3.65)
			(stroke
				(width 0.15)
				(type solid)
			)
			(layer "F.SilkS")
		)
		(fp_line
			(start -3.65 3.648)
			(end -3.65 3.249)
			(stroke
				(width 0.15)
				(type solid)
			)
			(layer "F.SilkS")
		)
		(fp_line
			(start 4.2 4.2)
			(end -4.21 4.2)
			(stroke
				(width 0.05)
				(type solid)
			)
			(layer "F.CrtYd")
		)
		(fp_line
			(start 4.2 -4.21)
			(end 4.2 4.2)
			(stroke
				(width 0.05)
				(type solid)
			)
			(layer "F.CrtYd")
		)
		(fp_line
			(start -4.21 4.2)
			(end -4.21 -4.21)
			(stroke
				(width 0.05)
				(type solid)
			)
			(layer "F.CrtYd")
		)
		(fp_line
			(start -4.21 -4.21)
			(end 4.2 -4.21)
			(stroke
				(width 0.05)
				(type solid)
			)
			(layer "F.CrtYd")
		)
		(fp_line
			(start 3.499 3.499)
			(end 3.499 -3.5)
			(stroke
				(width 0.15)
				(type solid)
			)
			(layer "F.Fab")
		)
		(fp_line
			(start 3.499 -3.5)
			(end -2.5 -3.5)
			(stroke
				(width 0.15)
				(type solid)
			)
			(layer "F.Fab")
		)
		(fp_line
			(start -2.5 -3.5)
			(end -3.5 -2.5)
			(stroke
				(width 0.15)
				(type solid)
			)
			(layer "F.Fab")
		)
		(fp_line
			(start -3.5 3.499)
			(end 3.499 3.499)
			(stroke
				(width 0.15)
				(type solid)
			)
			(layer "F.Fab")
		)
		(fp_line
			(start -3.5 -2.5)
			(end -3.5 3.499)
			(stroke
				(width 0.15)
				(type solid)
			)
			(layer "F.Fab")
		)
		(fp_text user "."
			(at -4.4 -3.05 180)
			(layer "F.SilkS")
			(effects
				(font
					(size 0.7 0.7)
					(thickness 0.15)
				)
			)
		)
		(pad "1" smd oval
			(at -3.5 -2.75 270)
			(size 0.3 0.9)
			(layers "F.Cu" "F.Mask" "F.Paste")
			(net 717 "/HDMI + Ethernet/GBE_AVDDH")
			(pinfunction "AVDDH")
			(pintype "power_in")
		)
		(pad "2" smd oval
			(at -3.5 -2.25 270)
			(size 0.3 0.9)
			(layers "F.Cu" "F.Mask" "F.Paste")
			(net 860 "/HDMI + Ethernet/GBE1_P")
			(pinfunction "TXRXP_A")
			(pintype "input")
		)
		(pad "3" smd oval
			(at -3.5 -1.75 270)
			(size 0.3 0.9)
			(layers "F.Cu" "F.Mask" "F.Paste")
			(net 859 "/HDMI + Ethernet/GBE1_N")
			(pinfunction "TXRXM_A")
			(pintype "input")
		)
		(pad "4" smd oval
			(at -3.5 -1.25 270)
			(size 0.3 0.9)
			(layers "F.Cu" "F.Mask" "F.Paste")
			(net 728 "/HDMI + Ethernet/GBE_AVDDL{slash}PLL")
			(pinfunction "AVDDL")
			(pintype "power_in")
		)
		(pad "5" smd oval
			(at -3.5 -0.75 270)
			(size 0.3 0.9)
			(layers "F.Cu" "F.Mask" "F.Paste")
			(net 858 "/HDMI + Ethernet/GBE2_P")
			(pinfunction "TXRXP_B")
			(pintype "input")
		)
		(pad "6" smd oval
			(at -3.5 -0.25 270)
			(size 0.3 0.9)
			(layers "F.Cu" "F.Mask" "F.Paste")
			(net 857 "/HDMI + Ethernet/GBE2_N")
			(pinfunction "TXRXM_B")
			(pintype "input")
		)
		(pad "7" smd oval
			(at -3.5 0.248 270)
			(size 0.3 0.9)
			(layers "F.Cu" "F.Mask" "F.Paste")
			(net 856 "/HDMI + Ethernet/GBE3_P")
			(pinfunction "TXRXP_C")
			(pintype "input")
		)
		(pad "8" smd oval
			(at -3.5 0.748 270)
			(size 0.3 0.9)
			(layers "F.Cu" "F.Mask" "F.Paste")
			(net 855 "/HDMI + Ethernet/GBE3_N")
			(pinfunction "TXRXM_C")
			(pintype "input")
		)
		(pad "9" smd oval
			(at -3.5 1.249 270)
			(size 0.3 0.9)
			(layers "F.Cu" "F.Mask" "F.Paste")
			(net 728 "/HDMI + Ethernet/GBE_AVDDL{slash}PLL")
			(pinfunction "AVDDL")
			(pintype "passive")
		)
		(pad "10" smd oval
			(at -3.5 1.749 270)
			(size 0.3 0.9)
			(layers "F.Cu" "F.Mask" "F.Paste")
			(net 854 "/HDMI + Ethernet/GBE4_P")
			(pinfunction "TXRXP_D")
			(pintype "input")
		)
		(pad "11" smd oval
			(at -3.5 2.249 270)
			(size 0.3 0.9)
			(layers "F.Cu" "F.Mask" "F.Paste")
			(net 853 "/HDMI + Ethernet/GBE4_N")
			(pinfunction "TXRXM_D")
			(pintype "input")
		)
		(pad "12" smd oval
			(at -3.5 2.749 270)
			(size 0.3 0.9)
			(layers "F.Cu" "F.Mask" "F.Paste")
			(net 717 "/HDMI + Ethernet/GBE_AVDDH")
			(pinfunction "AVDDH")
			(pintype "passive")
		)
		(pad "13" smd oval
			(at -2.75 3.499 180)
			(size 0.3 0.9)
			(layers "F.Cu" "F.Mask" "F.Paste")
			(net 1 "GND")
			(pinfunction "NC_(GND)")
			(pintype "passive")
		)
		(pad "14" smd oval
			(at -2.25 3.499 180)
			(size 0.3 0.9)
			(layers "F.Cu" "F.Mask" "F.Paste")
			(net 727 "+1V2")
			(pinfunction "NC_(DVDDL)")
			(pintype "passive")
		)
		(pad "15" smd oval
			(at -1.75 3.499 180)
			(size 0.3 0.9)
			(layers "F.Cu" "F.Mask" "F.Paste")
			(net 850 "/HDMI + Ethernet/GBE_LED_SPD-")
			(pinfunction "LED2/PHYAD1")
			(pintype "bidirectional")
		)
		(pad "16" smd oval
			(at -1.25 3.499 180)
			(size 0.3 0.9)
			(layers "F.Cu" "F.Mask" "F.Paste")
			(net 24 "+3V3")
			(pinfunction "DVDDH")
			(pintype "power_in")
		)
		(pad "17" smd oval
			(at -0.75 3.499 180)
			(size 0.3 0.9)
			(layers "F.Cu" "F.Mask" "F.Paste")
			(net 851 "/HDMI + Ethernet/GBE_LED_LINK-")
			(pinfunction "LED1/PHAD0/PME_N1")
			(pintype "bidirectional")
		)
		(pad "18" smd oval
			(at -0.25 3.499 180)
			(size 0.3 0.9)
			(layers "F.Cu" "F.Mask" "F.Paste")
			(net 727 "+1V2")
			(pinfunction "DVDDL")
			(pintype "power_in")
		)
		(pad "19" smd oval
			(at 0.248 3.499 180)
			(size 0.3 0.9)
			(layers "F.Cu" "F.Mask" "F.Paste")
			(net 939 "/FPGA Bank 16 & 17/GBE_RGMII.TXD0")
			(pinfunction "TXD0")
			(pintype "input")
		)
		(pad "20" smd oval
			(at 0.748 3.499 180)
			(size 0.3 0.9)
			(layers "F.Cu" "F.Mask" "F.Paste")
			(net 1021 "/FPGA Bank 16 & 17/GBE_RGMII.TXD1")
			(pinfunction "TXD1")
			(pintype "input")
		)
		(pad "21" smd oval
			(at 1.249 3.499 180)
			(size 0.3 0.9)
			(layers "F.Cu" "F.Mask" "F.Paste")
			(net 1002 "/FPGA Bank 16 & 17/GBE_RGMII.TXD2")
			(pinfunction "TXD2")
			(pintype "input")
		)
		(pad "22" smd oval
			(at 1.749 3.499 180)
			(size 0.3 0.9)
			(layers "F.Cu" "F.Mask" "F.Paste")
			(net 993 "/FPGA Bank 16 & 17/GBE_RGMII.TXD3")
			(pinfunction "TXD3")
			(pintype "input")
		)
		(pad "23" smd oval
			(at 2.249 3.499 180)
			(size 0.3 0.9)
			(layers "F.Cu" "F.Mask" "F.Paste")
			(net 727 "+1V2")
			(pinfunction "DVDDL")
			(pintype "passive")
		)
		(pad "24" smd oval
			(at 2.749 3.499 180)
			(size 0.3 0.9)
			(layers "F.Cu" "F.Mask" "F.Paste")
			(net 1019 "/FPGA Bank 16 & 17/GBE_RGMII.GTX_CLK")
			(pinfunction "GTX_CLK")
			(pintype "input")
		)
		(pad "25" smd oval
			(at 3.499 2.749 270)
			(size 0.3 0.9)
			(layers "F.Cu" "F.Mask" "F.Paste")
			(net 1008 "/FPGA Bank 16 & 17/GBE_RGMII.TX_EN")
			(pinfunction "TX_EN")
			(pintype "input")
		)
		(pad "26" smd oval
			(at 3.499 2.249 270)
			(size 0.3 0.9)
			(layers "F.Cu" "F.Mask" "F.Paste")
			(net 727 "+1V2")
			(pinfunction "DVDDL")
			(pintype "passive")
		)
		(pad "27" smd oval
			(at 3.499 1.749 270)
			(size 0.3 0.9)
			(layers "F.Cu" "F.Mask" "F.Paste")
			(net 503 "/FPGA Bank 16 & 17/GBE_RGMII.RXD3")
			(pinfunction "RXD3/MODE3")
			(pintype "input")
		)
		(pad "28" smd oval
			(at 3.499 1.249 270)
			(size 0.3 0.9)
			(layers "F.Cu" "F.Mask" "F.Paste")
			(net 504 "/FPGA Bank 16 & 17/GBE_RGMII.RXD2")
			(pinfunction "RXD2/MODE2")
			(pintype "input")
		)
		(pad "29" smd oval
			(at 3.499 0.748 270)
			(size 0.3 0.9)
			(layers "F.Cu" "F.Mask" "F.Paste")
			(net 1 "GND")
			(pinfunction "GND")
			(pintype "power_out")
		)
		(pad "30" smd oval
			(at 3.499 0.248 270)
			(size 0.3 0.9)
			(layers "F.Cu" "F.Mask" "F.Paste")
			(net 727 "+1V2")
			(pinfunction "DVDDL")
			(pintype "passive")
		)
		(pad "31" smd oval
			(at 3.499 -0.25 270)
			(size 0.3 0.9)
			(layers "F.Cu" "F.Mask" "F.Paste")
			(net 505 "/FPGA Bank 16 & 17/GBE_RGMII.RXD1")
			(pinfunction "RXD1/MODE1")
			(pintype "input")
		)
		(pad "32" smd oval
			(at 3.499 -0.75 270)
			(size 0.3 0.9)
			(layers "F.Cu" "F.Mask" "F.Paste")
			(net 506 "/FPGA Bank 16 & 17/GBE_RGMII.RXD0")
			(pinfunction "RXD0/MODE0")
			(pintype "input")
		)
		(pad "33" smd oval
			(at 3.499 -1.25 270)
			(size 0.3 0.9)
			(layers "F.Cu" "F.Mask" "F.Paste")
			(net 509 "/FPGA Bank 16 & 17/GBE_RGMII.RX_DV")
			(pinfunction "RX_DV/CLK125_EN")
			(pintype "input")
		)
		(pad "34" smd oval
			(at 3.499 -1.75 270)
			(size 0.3 0.9)
			(layers "F.Cu" "F.Mask" "F.Paste")
			(net 24 "+3V3")
			(pinfunction "DVDDH")
			(pintype "passive")
		)
		(pad "35" smd oval
			(at 3.499 -2.25 270)
			(size 0.3 0.9)
			(layers "F.Cu" "F.Mask" "F.Paste")
			(net 507 "/FPGA Bank 16 & 17/GBE_RGMII.GTR_CLK")
			(pinfunction "RX_CLK/PHYAD2")
			(pintype "input")
		)
		(pad "36" smd oval
			(at 3.499 -2.75 270)
			(size 0.3 0.9)
			(layers "F.Cu" "F.Mask" "F.Paste")
			(net 1001 "/FPGA Bank 16 & 17/GBE_RGMII.MDC")
			(pinfunction "MDC")
			(pintype "input")
		)
		(pad "37" smd oval
			(at 2.749 -3.5 180)
			(size 0.3 0.9)
			(layers "F.Cu" "F.Mask" "F.Paste")
			(net 523 "/FPGA Bank 16 & 17/GBE_RGMII.MDIO")
			(pinfunction "MDIO")
			(pintype "input")
		)
		(pad "38" smd oval
			(at 2.249 -3.5 180)
			(size 0.3 0.9)
			(layers "F.Cu" "F.Mask" "F.Paste")
			(net 508 "/FPGA Bank 16 & 17/GBE_RGMII.~{INT}")
			(pinfunction "INT_N/PME_N2")
			(pintype "input")
		)
		(pad "39" smd oval
			(at 1.749 -3.5 180)
			(size 0.3 0.9)
			(layers "F.Cu" "F.Mask" "F.Paste")
			(net 727 "+1V2")
			(pinfunction "DVDDL")
			(pintype "passive")
		)
		(pad "40" smd oval
			(at 1.249 -3.5 180)
			(size 0.3 0.9)
			(layers "F.Cu" "F.Mask" "F.Paste")
			(net 24 "+3V3")
			(pinfunction "DVDDH")
			(pintype "passive")
		)
		(pad "41" smd oval
			(at 0.748 -3.5 180)
			(size 0.3 0.9)
			(layers "F.Cu" "F.Mask" "F.Paste")
			(net 510 "/FPGA Bank 16 & 17/GBE_RGMII.REFCLK")
			(pinfunction "CLK125_NDO/LED_MODE")
			(pintype "input")
		)
		(pad "42" smd oval
			(at 0.248 -3.5 180)
			(size 0.3 0.9)
			(layers "F.Cu" "F.Mask" "F.Paste")
			(net 522 "/FPGA Bank 16 & 17/GBE_RGMII.~{RESET}")
			(pinfunction "RESET_N")
			(pintype "input")
		)
		(pad "43" smd oval
			(at -0.25 -3.5 180)
			(size 0.3 0.9)
			(layers "F.Cu" "F.Mask" "F.Paste")
			(net 1404 "unconnected-(U27-LDO_O-Pad43)")
			(pinfunction "LDO_O")
			(pintype "input+no_connect")
		)
		(pad "44" smd oval
			(at -0.75 -3.5 180)
			(size 0.3 0.9)
			(layers "F.Cu" "F.Mask" "F.Paste")
			(net 728 "/HDMI + Ethernet/GBE_AVDDL{slash}PLL")
			(pinfunction "AVDDL_PLL")
			(pintype "power_in")
		)
		(pad "45" smd oval
			(at -1.25 -3.5 180)
			(size 0.3 0.9)
			(layers "F.Cu" "F.Mask" "F.Paste")
			(net 720 "/HDMI + Ethernet/GBE_XO")
			(pinfunction "XO")
			(pintype "input")
		)
		(pad "46" smd oval
			(at -1.75 -3.5 180)
			(size 0.3 0.9)
			(layers "F.Cu" "F.Mask" "F.Paste")
			(net 718 "/HDMI + Ethernet/GBE_XI")
			(pinfunction "XI")
			(pintype "input")
		)
		(pad "47" smd oval
			(at -2.25 -3.5 180)
			(size 0.3 0.9)
			(layers "F.Cu" "F.Mask" "F.Paste")
			(net 717 "/HDMI + Ethernet/GBE_AVDDH")
			(pinfunction "NC_(AVDDH)")
			(pintype "passive")
		)
		(pad "48" smd oval
			(at -2.75 -3.5 180)
			(size 0.3 0.9)
			(layers "F.Cu" "F.Mask" "F.Paste")
			(net 953 "/HDMI + Ethernet/GBE_ISET")
			(pinfunction "ISET")
			(pintype "output")
		)
		(pad "49" smd rect
			(at 0 0 180)
			(size 5 5)
			(layers "F.Cu" "F.Mask" "F.Paste")
			(net 1 "GND")
			(pinfunction "GND")
			(pintype "passive")
		)
	)
	(footprint "antmicro-footprints:C_0402_1005Metric"
		(layer "F.Cu")
		(at 173.570001 117.557501 180)
		(descr "Capacitor SMD 0402")
		(tags "capacitor SMD 0402")
		(property "Reference" "C304"
			(at -3.729999 -0.342499 0)
			(layer "F.SilkS")
			(effects
				(font
					(size 0.7 0.7)
					(thickness 0.15)
				)
				(justify right bottom)
			)
		)
		(property "Value" "C_100n_0402"
			(at 0 1.4 0)
			(layer "F.Fab")
			(effects
				(font
					(size 0.7 0.7)
					(thickness 0.15)
				)
				(justify right bottom)
			)
		)
		(property "Description" "SMD Multilayer Ceramic Capacitor, 0.1 µF, 50 V, 0402 [1005 Metric], ± 10%, X5R, GRM Series"
			(at 0 0 180)
			(layer "F.Fab")
			(hide yes)
			(effects
				(font
					(size 1.27 1.27)
					(thickness 0.15)
				)
			)
		)
		(property "Author" "Antmicro"
			(at 347.140002 235.115002 0)
			(layer "F.Fab")
			(hide yes)
			(effects
				(font
					(size 1 1)
					(thickness 0.15)
				)
			)
		)
		(property "Dielectric" "X5R"
			(at 347.140002 235.115002 0)
			(layer "F.Fab")
			(hide yes)
			(effects
				(font
					(size 1 1)
					(thickness 0.15)
				)
			)
		)
		(property "License" "Apache-2.0"
			(at 347.140002 235.115002 0)
			(layer "F.Fab")
			(hide yes)
			(effects
				(font
					(size 1 1)
					(thickness 0.15)
				)
			)
		)
		(property "MPN" "GRM155R61H104KE14D"
			(at 347.140002 235.115002 0)
			(layer "F.Fab")
			(hide yes)
			(effects
				(font
					(size 1 1)
					(thickness 0.15)
				)
			)
		)
		(property "Manufacturer" "Murata"
			(at 347.140002 235.115002 0)
			(layer "F.Fab")
			(hide yes)
			(effects
				(font
					(size 1 1)
					(thickness 0.15)
				)
			)
		)
		(property "Val" "100n"
			(at 347.140002 235.115002 0)
			(layer "F.Fab")
			(hide yes)
			(effects
				(font
					(size 1 1)
					(thickness 0.15)
				)
			)
		)
		(property "Voltage" "50V"
			(at 347.140002 235.115002 0)
			(layer "F.Fab")
			(hide yes)
			(effects
				(font
					(size 1 1)
					(thickness 0.15)
				)
			)
		)
		(sheetname "FMC+ HSPC")
		(sheetfile "fmc-hspc.kicad_sch")
		(attr smd)
		(fp_rect
			(start -0.925 -0.47)
			(end 0.925 0.47)
			(stroke
				(width 0.05)
				(type default)
			)
			(fill no)
			(layer "F.CrtYd")
		)
		(fp_line
			(start 0.504 0.248)
			(end -0.494 0.248)
			(stroke
				(width 0.15)
				(type solid)
			)
			(layer "F.Fab")
		)
		(fp_line
			(start 0.504 -0.25)
			(end 0.504 0.248)
			(stroke
				(width 0.15)
				(type solid)
			)
			(layer "F.Fab")
		)
		(fp_line
			(start -0.494 0.248)
			(end -0.494 -0.25)
			(stroke
				(width 0.15)
				(type solid)
			)
			(layer "F.Fab")
		)
		(fp_line
			(start -0.494 -0.25)
			(end 0.504 -0.25)
			(stroke
				(width 0.15)
				(type solid)
			)
			(layer "F.Fab")
		)
		(pad "1" smd roundrect
			(at -0.48 0 180)
			(size 0.59 0.64)
			(layers "F.Cu" "F.Mask" "F.Paste")
			(roundrect_rratio 0.25)
			(net 80 "/FMC+ HSPC/GTX116.TX0_P")
			(pintype "passive")
		)
		(pad "2" smd roundrect
			(at 0.48 0 180)
			(size 0.59 0.64)
			(layers "F.Cu" "F.Mask" "F.Paste")
			(roundrect_rratio 0.25)
			(net 79 "/FMC+ HSPC/GTX_TX3_C_P")
			(pintype "passive")
		)
	)
	(footprint "antmicro-footprints:R_Array_4x0201_Panasonic_EXB18V"
		(layer "F.Cu")
		(at 245.4 122)
		(property "Reference" "R24"
			(at 0.85 -0.75 0)
			(layer "F.SilkS")
			(effects
				(font
					(size 0.7 0.7)
					(thickness 0.15)
				)
				(justify right bottom)
			)
		)
		(property "Value" "R_4x33R_0201_array"
			(at -1.1 1.8 0)
			(layer "F.Fab")
			(effects
				(font
					(size 0.7 0.7)
					(thickness 0.15)
				)
				(justify left bottom)
			)
		)
		(property "Description" "Fixed Network Resistor, 33 ohm, Isolated, 4 Resistors, 0502 [1406 Metric], Flat, ± 5%"
			(at 0 0 0)
			(layer "F.Fab")
			(hide yes)
			(effects
				(font
					(size 1.27 1.27)
					(thickness 0.15)
				)
			)
		)
		(property "Author" "Antmicro"
			(at 0 0 0)
			(layer "F.Fab")
			(hide yes)
			(effects
				(font
					(size 1 1)
					(thickness 0.15)
				)
			)
		)
		(property "License" "Apache-2.0"
			(at 0 0 0)
			(layer "F.Fab")
			(hide yes)
			(effects
				(font
					(size 1 1)
					(thickness 0.15)
				)
			)
		)
		(property "MPN" "EXB-18V330JX"
			(at 0 0 0)
			(layer "F.Fab")
			(hide yes)
			(effects
				(font
					(size 1 1)
					(thickness 0.15)
				)
			)
		)
		(property "Manufacturer" "Panasonic"
			(at 0 0 0)
			(layer "F.Fab")
			(hide yes)
			(effects
				(font
					(size 1 1)
					(thickness 0.15)
				)
			)
		)
		(property "Val" "R_4x33R_0201"
			(at 0 0 0)
			(layer "F.Fab")
			(hide yes)
			(effects
				(font
					(size 1 1)
					(thickness 0.15)
				)
			)
		)
		(sheetname "Supervisior MCU")
		(sheetfile "supervisor-mcu.kicad_sch")
		(attr smd)
		(fp_line
			(start -0.8 -0.45)
			(end -0.8 0.45)
			(stroke
				(width 0.12)
				(type solid)
			)
			(layer "F.SilkS")
		)
		(fp_line
			(start 0.8 -0.45)
			(end 0.8 0.45)
			(stroke
				(width 0.12)
				(type solid)
			)
			(layer "F.SilkS")
		)
		(fp_rect
			(start -0.898 -0.66)
			(end 0.898 0.65)
			(stroke
				(width 0.05)
				(type solid)
			)
			(fill no)
			(layer "F.CrtYd")
		)
		(pad "1" smd roundrect
			(at -0.6 0.298)
			(size 0.2 0.4)
			(layers "F.Cu" "F.Mask" "F.Paste")
			(roundrect_rratio 0.25)
			(net 355 "unconnected-(R24-R1.1-Pad1)")
			(pinfunction "R1.1")
			(pintype "passive+no_connect")
		)
		(pad "2" smd roundrect
			(at -0.202 0.298)
			(size 0.2 0.4)
			(layers "F.Cu" "F.Mask" "F.Paste")
			(roundrect_rratio 0.25)
			(net 1076 "/Supervisior MCU/USB_A15")
			(pinfunction "R2.1")
			(pintype "passive")
		)
		(pad "3" smd roundrect
			(at 0.2 0.298)
			(size 0.2 0.4)
			(layers "F.Cu" "F.Mask" "F.Paste")
			(roundrect_rratio 0.25)
			(net 1078 "/Supervisior MCU/USB_A17")
			(pinfunction "R3.1")
			(pintype "passive")
		)
		(pad "4" smd roundrect
			(at 0.598 0.298)
			(size 0.2 0.4)
			(layers "F.Cu" "F.Mask" "F.Paste")
			(roundrect_rratio 0.25)
			(net 1067 "/Supervisior MCU/USB_A6")
			(pinfunction "R4.1")
			(pintype "passive")
		)
		(pad "5" smd roundrect
			(at 0.598 -0.3)
			(size 0.2 0.4)
			(layers "F.Cu" "F.Mask" "F.Paste")
			(roundrect_rratio 0.25)
			(net 1362 "/SUP_MCU.A6")
			(pinfunction "R4.2")
			(pintype "passive")
		)
		(pad "6" smd roundrect
			(at 0.2 -0.3)
			(size 0.2 0.4)
			(layers "F.Cu" "F.Mask" "F.Paste")
			(roundrect_rratio 0.25)
			(net 1363 "/SUP_MCU.A17")
			(pinfunction "R3.2")
			(pintype "passive")
		)
		(pad "7" smd roundrect
			(at -0.202 -0.3)
			(size 0.2 0.4)
			(layers "F.Cu" "F.Mask" "F.Paste")
			(roundrect_rratio 0.25)
			(net 1364 "/SUP_MCU.A15")
			(pinfunction "R2.2")
			(pintype "passive")
		)
		(pad "8" smd roundrect
			(at -0.6 -0.3)
			(size 0.2 0.4)
			(layers "F.Cu" "F.Mask" "F.Paste")
			(roundrect_rratio 0.25)
			(net 356 "unconnected-(R24-R1.2-Pad8)")
			(pinfunction "R1.2")
			(pintype "passive+no_connect")
		)
	)
	(footprint "antmicro-footprints:HDMI-A_Receptacle_TE_2007435-1"
		(layer "F.Cu")
		(at 261.75 113.5 90)
		(property "Reference" "J16"
			(at 3.73 -7.3 180)
			(layer "F.SilkS")
			(effects
				(font
					(size 0.7 0.7)
					(thickness 0.15)
				)
				(justify left bottom)
			)
		)
		(property "Value" "HDMI-A_TE_2007435-1"
			(at 0 11.7 90)
			(layer "F.Fab")
			(effects
				(font
					(size 0.7 0.7)
					(thickness 0.15)
				)
				(justify left bottom)
			)
		)
		(property "Description" "HDMI Receptacle Connector 19 Position Panel Mount, Through Hole, Right Angle"
			(at 0 0 90)
			(layer "F.Fab")
			(hide yes)
			(effects
				(font
					(size 1.27 1.27)
					(thickness 0.15)
				)
			)
		)
		(property "Author" "Antmicro"
			(at 375.25 -148.25 0)
			(layer "F.Fab")
			(hide yes)
			(effects
				(font
					(size 1 1)
					(thickness 0.15)
				)
			)
		)
		(property "License" "Apache-2.0"
			(at 375.25 -148.25 0)
			(layer "F.Fab")
			(hide yes)
			(effects
				(font
					(size 1 1)
					(thickness 0.15)
				)
			)
		)
		(property "MPN" "2007435-1"
			(at 375.25 -148.25 0)
			(layer "F.Fab")
			(hide yes)
			(effects
				(font
					(size 1 1)
					(thickness 0.15)
				)
			)
		)
		(property "Manufacturer" "TE Connectivity"
			(at 375.25 -148.25 0)
			(layer "F.Fab")
			(hide yes)
			(effects
				(font
					(size 1 1)
					(thickness 0.15)
				)
			)
		)
		(sheetname "HDMI + Ethernet")
		(sheetfile "hdmi-ethernet.kicad_sch")
		(attr through_hole)
		(fp_line
			(start -4.351 -12.702)
			(end 1.85 -12.702)
			(stroke
				(width 0.15)
				(type solid)
			)
			(layer "F.SilkS")
		)
		(fp_line
			(start -4.351 -12.702)
			(end -4.351 -9.85)
			(stroke
				(width 0.15)
				(type solid)
			)
			(layer "F.SilkS")
		)
		(fp_line
			(start 3.35 -9.35)
			(end 3.35 -3.75)
			(stroke
				(width 0.15)
				(type solid)
			)
			(layer "F.SilkS")
		)
		(fp_line
			(start -4.351 -6.601)
			(end -4.351 -1.151)
			(stroke
				(width 0.15)
				(type solid)
			)
			(layer "F.SilkS")
		)
		(fp_line
			(start -4.351 2.749)
			(end -4.351 9.4)
			(stroke
				(width 0.15)
				(type solid)
			)
			(layer "F.SilkS")
		)
		(fp_line
			(start 3.35 9.4)
			(end 3.35 -0.103)
			(stroke
				(width 0.15)
				(type solid)
			)
			(layer "F.SilkS")
		)
		(fp_rect
			(start -4.641 -13.127)
			(end 3.638 10.749)
			(stroke
				(width 0.05)
				(type solid)
			)
			(fill no)
			(layer "F.CrtYd")
		)
		(pad "" np_thru_hole circle
			(at -2.5 -11.35 90)
			(size 1.7 1.7)
			(drill 1.7)
			(layers "F&B.Cu" "*.Mask")
		)
		(pad "" np_thru_hole circle
			(at 0.996 1.896 90)
			(size 1.7 1.7)
			(drill 1.7)
			(layers "F&B.Cu" "*.Mask")
		)
		(pad "1" thru_hole rect
			(at 0 0 90)
			(size 0.8 0.8)
			(drill 0.45)
			(layers "*.Cu" "*.Mask")
			(remove_unused_layers no)
			(net 867 "/HDMI + Ethernet/HDMI_CONN_D2_P")
			(pinfunction "D2+")
			(pintype "bidirectional")
		)
		(pad "2" thru_hole circle
			(at -1 -0.578 90)
			(size 0.8 0.8)
			(drill 0.45)
			(layers "*.Cu" "*.Mask")
			(remove_unused_layers no)
			(net 1 "GND")
			(pinfunction "D2S")
			(pintype "passive")
		)
		(pad "3" thru_hole circle
			(at 0 -1.156 90)
			(size 0.8 0.8)
			(drill 0.45)
			(layers "*.Cu" "*.Mask")
			(remove_unused_layers no)
			(net 866 "/HDMI + Ethernet/HDMI_CONN_D2_N")
			(pinfunction "D2-")
			(pintype "bidirectional")
		)
		(pad "4" thru_hole circle
			(at -1 -1.734 90)
			(size 0.8 0.8)
			(drill 0.45)
			(layers "*.Cu" "*.Mask")
			(remove_unused_layers no)
			(net 865 "/HDMI + Ethernet/HDMI_CONN_D1_P")
			(pinfunction "D1+")
			(pintype "bidirectional")
		)
		(pad "5" thru_hole circle
			(at 0 -2.311 90)
			(size 0.8 0.8)
			(drill 0.45)
			(layers "*.Cu" "*.Mask")
			(remove_unused_layers no)
			(net 1 "GND")
			(pinfunction "D1S")
			(pintype "passive")
		)
		(pad "6" thru_hole circle
			(at -1 -2.888 90)
			(size 0.8 0.8)
			(drill 0.45)
			(layers "*.Cu" "*.Mask")
			(remove_unused_layers no)
			(net 864 "/HDMI + Ethernet/HDMI_CONN_D1_N")
			(pinfunction "D1-")
			(pintype "bidirectional")
		)
		(pad "7" thru_hole circle
			(at 0 -3.465 90)
			(size 0.8 0.8)
			(drill 0.45)
			(layers "*.Cu" "*.Mask")
			(remove_unused_layers no)
			(net 863 "/HDMI + Ethernet/HDMI_CONN_D0_P")
			(pinfunction "D0+")
			(pintype "bidirectional")
		)
		(pad "8" thru_hole circle
			(at -1 -4.045 90)
			(size 0.8 0.8)
			(drill 0.45)
			(layers "*.Cu" "*.Mask")
			(remove_unused_layers no)
			(net 1 "GND")
			(pinfunction "D0S")
			(pintype "passive")
		)
		(pad "9" thru_hole circle
			(at 0 -4.622 90)
			(size 0.8 0.8)
			(drill 0.45)
			(layers "*.Cu" "*.Mask")
			(remove_unused_layers no)
			(net 862 "/HDMI + Ethernet/HDMI_CONN_D0_N")
			(pinfunction "D0-")
			(pintype "bidirectional")
		)
		(pad "10" thru_hole circle
			(at -1 -5.199 90)
			(size 0.8 0.8)
			(drill 0.45)
			(layers "*.Cu" "*.Mask")
			(remove_unused_layers no)
			(net 861 "/HDMI + Ethernet/HDMI_CONN_CLK_P")
			(pinfunction "CK+")
			(pintype "bidirectional")
		)
		(pad "11" thru_hole circle
			(at 0 -5.776 90)
			(size 0.8 0.8)
			(drill 0.45)
			(layers "*.Cu" "*.Mask")
			(remove_unused_layers no)
			(net 1 "GND")
			(pinfunction "CKS")
			(pintype "passive")
		)
		(pad "12" thru_hole circle
			(at -1 -6.353 90)
			(size 0.8 0.8)
			(drill 0.45)
			(layers "*.Cu" "*.Mask")
			(remove_unused_layers no)
			(net 868 "/HDMI + Ethernet/HDMI_CONN_CLK_N")
			(pinfunction "CK-")
			(pintype "bidirectional")
		)
		(pad "13" thru_hole circle
			(at 0 -6.93 90)
			(size 0.8 0.8)
			(drill 0.45)
			(layers "*.Cu" "*.Mask")
			(remove_unused_layers no)
			(net 42 "unconnected-(J16-CEC-Pad13)")
			(pinfunction "CEC")
			(pintype "bidirectional+no_connect")
		)
		(pad "14" thru_hole circle
			(at -1 -7.508 90)
			(size 0.8 0.8)
			(drill 0.45)
			(layers "*.Cu" "*.Mask")
			(remove_unused_layers no)
			(net 44 "unconnected-(J16-UTILITY{slash}HEAC+-Pad14)")
			(pinfunction "UTILITY/HEAC+")
			(pintype "bidirectional+no_connect")
		)
		(pad "15" thru_hole circle
			(at 0 -8.087 90)
			(size 0.8 0.8)
			(drill 0.45)
			(layers "*.Cu" "*.Mask")
			(remove_unused_layers no)
			(net 47 "unconnected-(J16-SCL-Pad15)")
			(pinfunction "SCL")
			(pintype "bidirectional+no_connect")
		)
		(pad "16" thru_hole circle
			(at -1 -8.664 90)
			(size 0.8 0.8)
			(drill 0.45)
			(layers "*.Cu" "*.Mask")
			(remove_unused_layers no)
			(net 48 "unconnected-(J16-SDA-Pad16)")
			(pinfunction "SDA")
			(pintype "bidirectional+no_connect")
		)
		(pad "17" thru_hole circle
			(at 0 -9.241 90)
			(size 0.8 0.8)
			(drill 0.45)
			(layers "*.Cu" "*.Mask")
			(remove_unused_layers no)
			(net 1 "GND")
			(pinfunction "GND")
			(pintype "power_in")
		)
		(pad "18" thru_hole circle
			(at -1 -9.818 90)
			(size 0.8 0.8)
			(drill 0.45)
			(layers "*.Cu" "*.Mask")
			(remove_unused_layers no)
			(net 794 "/HDMI + Ethernet/HDMI_CONN_5V")
			(pinfunction "+5V")
			(pintype "power_in")
		)
		(pad "19" thru_hole circle
			(at 0 -10.395 90)
			(size 0.8 0.8)
			(drill 0.45)
			(layers "*.Cu" "*.Mask")
			(remove_unused_layers no)
			(net 49 "unconnected-(J16-HPD{slash}HEAC--Pad19)")
			(pinfunction "HPD/HEAC-")
			(pintype "bidirectional+no_connect")
		)
		(pad "SH" thru_hole oval
			(at -3.75 -8.25 180)
			(size 3.5 1.7)
			(drill oval 2.5 0.9)
			(layers "*.Cu" "*.Mask")
			(remove_unused_layers no)
			(net 1 "GND")
			(pinfunction "SH")
			(pintype "passive")
		)
		(pad "SH" thru_hole oval
			(at -3.75 0.746 180)
			(size 3.5 1.7)
			(drill oval 2.5 0.9)
			(layers "*.Cu" "*.Mask")
			(remove_unused_layers no)
			(net 1 "GND")
			(pinfunction "SH")
			(pintype "passive")
		)
		(pad "SH" thru_hole oval
			(at 2.749 -11.35 180)
			(size 3.5 1.7)
			(drill oval 2.5 0.9)
			(layers "*.Cu" "*.Mask")
			(remove_unused_layers no)
			(net 1 "GND")
			(pinfunction "SH")
			(pintype "passive")
		)
		(pad "SH" thru_hole oval
			(at 2.749 -1.851 180)
			(size 3.5 1.7)
			(drill oval 2.5 0.9)
			(layers "*.Cu" "*.Mask")
			(remove_unused_layers no)
			(net 1 "GND")
			(pinfunction "SH")
			(pintype "passive")
		)
	)
	(footprint "antmicro-footprints:C_0402_1005Metric"
		(layer "F.Cu")
		(at 159.8 153.76 90)
		(descr "Capacitor SMD 0402")
		(tags "capacitor SMD 0402")
		(property "Reference" "C361"
			(at 0.8 0.35 90)
			(layer "F.SilkS")
			(effects
				(font
					(size 0.7 0.7)
					(thickness 0.15)
				)
				(justify left bottom)
			)
		)
		(property "Value" "C_10u_0402"
			(at 0 1.4 90)
			(layer "F.Fab")
			(effects
				(font
					(size 0.7 0.7)
					(thickness 0.15)
				)
				(justify left bottom)
			)
		)
		(property "Description" "SMD Multilayer Ceramic Capacitor, 10 µF, 6.3 V, 0402 [1005 Metric], ± 20%, X5R, CC Series"
			(at 0 0 90)
			(layer "F.Fab")
			(hide yes)
			(effects
				(font
					(size 1.27 1.27)
					(thickness 0.15)
				)
			)
		)
		(property "Author" "Antmicro"
			(at 313.56 -6.04 0)
			(layer "F.Fab")
			(hide yes)
			(effects
				(font
					(size 1 1)
					(thickness 0.15)
				)
			)
		)
		(property "Dielectric" ""
			(at 313.56 -6.04 0)
			(layer "F.Fab")
			(hide yes)
			(effects
				(font
					(size 1 1)
					(thickness 0.15)
				)
			)
		)
		(property "License" "Apache-2.0"
			(at 313.56 -6.04 0)
			(layer "F.Fab")
			(hide yes)
			(effects
				(font
					(size 1 1)
					(thickness 0.15)
				)
			)
		)
		(property "MPN" "CC0402MRX5R5BB106"
			(at 313.56 -6.04 0)
			(layer "F.Fab")
			(hide yes)
			(effects
				(font
					(size 1 1)
					(thickness 0.15)
				)
			)
		)
		(property "Manufacturer" "YAGEO"
			(at 313.56 -6.04 0)
			(layer "F.Fab")
			(hide yes)
			(effects
				(font
					(size 1 1)
					(thickness 0.15)
				)
			)
		)
		(property "Val" "10u"
			(at 313.56 -6.04 0)
			(layer "F.Fab")
			(hide yes)
			(effects
				(font
					(size 1 1)
					(thickness 0.15)
				)
			)
		)
		(property "Voltage" ""
			(at 313.56 -6.04 0)
			(layer "F.Fab")
			(hide yes)
			(effects
				(font
					(size 1 1)
					(thickness 0.15)
				)
			)
		)
		(sheetname "DC-DC Converters")
		(sheetfile "dc-dc.kicad_sch")
		(attr smd)
		(fp_rect
			(start -0.925 -0.47)
			(end 0.925 0.47)
			(stroke
				(width 0.05)
				(type default)
			)
			(fill no)
			(layer "F.CrtYd")
		)
		(fp_line
			(start 0.504 -0.25)
			(end 0.504 0.248)
			(stroke
				(width 0.15)
				(type solid)
			)
			(layer "F.Fab")
		)
		(fp_line
			(start -0.494 -0.25)
			(end 0.504 -0.25)
			(stroke
				(width 0.15)
				(type solid)
			)
			(layer "F.Fab")
		)
		(fp_line
			(start 0.504 0.248)
			(end -0.494 0.248)
			(stroke
				(width 0.15)
				(type solid)
			)
			(layer "F.Fab")
		)
		(fp_line
			(start -0.494 0.248)
			(end -0.494 -0.25)
			(stroke
				(width 0.15)
				(type solid)
			)
			(layer "F.Fab")
		)
		(pad "1" smd roundrect
			(at -0.48 0 90)
			(size 0.59 0.64)
			(layers "F.Cu" "F.Mask" "F.Paste")
			(roundrect_rratio 0.25)
			(net 1 "GND")
			(pintype "passive")
		)
		(pad "2" smd roundrect
			(at 0.48 0 90)
			(size 0.59 0.64)
			(layers "F.Cu" "F.Mask" "F.Paste")
			(roundrect_rratio 0.25)
			(net 750 "/DC-DC Converters/VDDR_VTT")
			(pintype "passive")
		)
	)
	(footprint "antmicro-footprints:SOT-23-6"
		(layer "F.Cu")
		(at 167.55 187.05)
		(property "Reference" "U36"
			(at -1.15 -2.05 0)
			(layer "F.SilkS")
			(effects
				(font
					(size 0.7 0.7)
					(thickness 0.15)
				)
				(justify left bottom)
			)
		)
		(property "Value" "LM3880"
			(at -1.75 2.75 0)
			(layer "F.Fab")
			(effects
				(font
					(size 0.7 0.7)
					(thickness 0.15)
				)
				(justify left bottom)
			)
		)
		(property "Description" "Power sequencer"
			(at 0 0 0)
			(layer "F.Fab")
			(hide yes)
			(effects
				(font
					(size 1.27 1.27)
					(thickness 0.15)
				)
			)
		)
		(property "Author" "Antmicro"
			(at 0 0 0)
			(layer "F.Fab")
			(hide yes)
			(effects
				(font
					(size 1 1)
					(thickness 0.15)
				)
			)
		)
		(property "License" "Apache-2.0"
			(at 0 0 0)
			(layer "F.Fab")
			(hide yes)
			(effects
				(font
					(size 1 1)
					(thickness 0.15)
				)
			)
		)
		(property "MPN" "LM3880MFX-1AA/NOPB"
			(at 0 0 0)
			(layer "F.Fab")
			(hide yes)
			(effects
				(font
					(size 1 1)
					(thickness 0.15)
				)
			)
		)
		(property "Manufacturer" "Texas Instruments"
			(at 0 0 0)
			(layer "F.Fab")
			(hide yes)
			(effects
				(font
					(size 1 1)
					(thickness 0.15)
				)
			)
		)
		(sheetname "DC-DC Converters")
		(sheetfile "dc-dc.kicad_sch")
		(attr smd)
		(fp_line
			(start -1.45 -0.7)
			(end -1.45 -0.4)
			(stroke
				(width 0.12)
				(type solid)
			)
			(layer "F.SilkS")
		)
		(fp_line
			(start -1.45 0.7)
			(end -1.45 0.4)
			(stroke
				(width 0.12)
				(type solid)
			)
			(layer "F.SilkS")
		)
		(fp_line
			(start -1.3 -0.7)
			(end -1.45 -0.7)
			(stroke
				(width 0.12)
				(type solid)
			)
			(layer "F.SilkS")
		)
		(fp_line
			(start 1.3 -0.7)
			(end 1.45 -0.7)
			(stroke
				(width 0.12)
				(type solid)
			)
			(layer "F.SilkS")
		)
		(fp_line
			(start 1.3 0.7)
			(end 1.45 0.7)
			(stroke
				(width 0.12)
				(type solid)
			)
			(layer "F.SilkS")
		)
		(fp_line
			(start 1.45 -0.7)
			(end 1.45 -0.4)
			(stroke
				(width 0.12)
				(type solid)
			)
			(layer "F.SilkS")
		)
		(fp_line
			(start 1.45 0.7)
			(end 1.45 0.4)
			(stroke
				(width 0.12)
				(type solid)
			)
			(layer "F.SilkS")
		)
		(fp_rect
			(start -1.55 -1.85)
			(end 1.55 1.75)
			(stroke
				(width 0.05)
				(type solid)
			)
			(fill no)
			(layer "F.CrtYd")
		)
		(fp_line
			(start -1.5 -0.7)
			(end 1.5 -0.7)
			(stroke
				(width 0.1)
				(type solid)
			)
			(layer "F.Fab")
		)
		(fp_line
			(start -1.5 0.7)
			(end -1.5 -0.7)
			(stroke
				(width 0.1)
				(type solid)
			)
			(layer "F.Fab")
		)
		(fp_line
			(start 1.5 -0.7)
			(end 1.5 0.7)
			(stroke
				(width 0.1)
				(type solid)
			)
			(layer "F.Fab")
		)
		(fp_line
			(start 1.5 0.7)
			(end -1.5 0.7)
			(stroke
				(width 0.1)
				(type solid)
			)
			(layer "F.Fab")
		)
		(fp_text user "."
			(at -1.4 1.2 180)
			(layer "F.SilkS")
			(effects
				(font
					(size 1 1)
					(thickness 0.15)
				)
			)
		)
		(pad "1" smd roundrect
			(at -0.954 1.1)
			(size 0.55 1)
			(layers "F.Cu" "F.Mask" "F.Paste")
			(roundrect_rratio 0.15)
			(net 37 "+3V3_AON")
			(pinfunction "VCC")
			(pintype "power_in")
		)
		(pad "2" smd roundrect
			(at -0.003 1.1)
			(size 0.55 1)
			(layers "F.Cu" "F.Mask" "F.Paste")
			(roundrect_rratio 0.15)
			(net 1 "GND")
			(pinfunction "GND")
			(pintype "power_in")
		)
		(pad "3" smd roundrect
			(at 0.947 1.1)
			(size 0.55 1)
			(layers "F.Cu" "F.Mask" "F.Paste")
			(roundrect_rratio 0.15)
			(net 14 "/DC-DC Converters/SEQ_EN")
			(pinfunction "EN")
			(pintype "input")
		)
		(pad "4" smd roundrect
			(at 0.947 -1.214)
			(size 0.55 1)
			(layers "F.Cu" "F.Mask" "F.Paste")
			(roundrect_rratio 0.15)
			(net 968 "/DC-DC Converters/EN3")
			(pinfunction "FLAG3")
			(pintype "open_collector")
		)
		(pad "5" smd roundrect
			(at -0.003 -1.214)
			(size 0.55 1)
			(layers "F.Cu" "F.Mask" "F.Paste")
			(roundrect_rratio 0.15)
			(net 967 "/DC-DC Converters/EN2")
			(pinfunction "FLAG2")
			(pintype "open_collector")
		)
		(pad "6" smd roundrect
			(at -0.954 -1.214)
			(size 0.55 1)
			(layers "F.Cu" "F.Mask" "F.Paste")
			(roundrect_rratio 0.15)
			(net 966 "/DC-DC Converters/EN1")
			(pinfunction "FLAG1")
			(pintype "open_collector")
		)
	)
	(footprint "antmicro-footprints:MP_Pad6mm_Drill3mm"
		(layer "F.Cu")
		(at 266.5 73.5)
		(property "Reference" "MH3"
			(at -0.178 4.025 0)
			(layer "F.SilkS")
			(hide yes)
			(effects
				(font
					(size 0.7 0.7)
					(thickness 0.15)
				)
				(justify left bottom)
			)
		)
		(property "Value" "MP_Pad6mm_Drill3mm"
			(at -0.153 -4.153 0)
			(layer "F.Fab")
			(effects
				(font
					(size 0.7 0.7)
					(thickness 0.15)
				)
				(justify left bottom)
			)
		)
		(property "Description" "Mechanical part"
			(at 0 0 0)
			(layer "F.Fab")
			(hide yes)
			(effects
				(font
					(size 1.27 1.27)
					(thickness 0.15)
				)
			)
		)
		(property "Author" "Antmicro"
			(at 0 0 0)
			(layer "F.Fab")
			(hide yes)
			(effects
				(font
					(size 1 1)
					(thickness 0.15)
				)
			)
		)
		(property "License" "Apache-2.0"
			(at 0 0 0)
			(layer "F.Fab")
			(hide yes)
			(effects
				(font
					(size 1 1)
					(thickness 0.15)
				)
			)
		)
		(property "MPN" ""
			(at 0 0 0)
			(layer "F.Fab")
			(hide yes)
			(effects
				(font
					(size 1 1)
					(thickness 0.15)
				)
			)
		)
		(property "Manufacturer" ""
			(at 0 0 0)
			(layer "F.Fab")
			(hide yes)
			(effects
				(font
					(size 1 1)
					(thickness 0.15)
				)
			)
		)
		(property "exclude_from_bom" ""
			(at 0 0 0)
			(layer "F.Fab")
			(hide yes)
			(effects
				(font
					(size 1 1)
					(thickness 0.15)
				)
			)
		)
		(sheetfile "k410t-devboard.kicad_sch")
		(attr exclude_from_pos_files exclude_from_bom)
		(pad "1" thru_hole circle
			(at 0 0)
			(size 6 6)
			(drill 3)
			(layers "*.Cu" "*.Mask")
			(remove_unused_layers no)
			(net 1 "GND")
			(pintype "passive")
		)
	)
	(footprint "antmicro-footprints:TP_SMD_0.75mm"
		(layer "F.Cu")
		(at 175.66 81.1308 180)
		(property "Reference" "TP2"
			(at -0.34 0.3308 270)
			(layer "F.SilkS")
			(effects
				(font
					(size 0.7 0.7)
					(thickness 0.15)
				)
				(justify left bottom)
			)
		)
		(property "Value" "TP_0.75mm_SMD"
			(at 0 1.2 180)
			(layer "F.Fab")
			(effects
				(font
					(size 0.7 0.7)
					(thickness 0.15)
				)
				(justify left bottom)
			)
		)
		(property "Description" "SMT test point"
			(at 0 0 180)
			(layer "F.Fab")
			(hide yes)
			(effects
				(font
					(size 1.27 1.27)
					(thickness 0.15)
				)
			)
		)
		(property "Author" "Antmicro"
			(at 351.32 162.2616 0)
			(layer "F.Fab")
			(hide yes)
			(effects
				(font
					(size 1 1)
					(thickness 0.15)
				)
			)
		)
		(property "License" "Apache-2.0"
			(at 351.32 162.2616 0)
			(layer "F.Fab")
			(hide yes)
			(effects
				(font
					(size 1 1)
					(thickness 0.15)
				)
			)
		)
		(property "MPN" ""
			(at 351.32 162.2616 0)
			(layer "F.Fab")
			(hide yes)
			(effects
				(font
					(size 1 1)
					(thickness 0.15)
				)
			)
		)
		(property "Manufacturer" ""
			(at 351.32 162.2616 0)
			(layer "F.Fab")
			(hide yes)
			(effects
				(font
					(size 1 1)
					(thickness 0.15)
				)
			)
		)
		(sheetname "FMC+ HSPC")
		(sheetfile "fmc-hspc.kicad_sch")
		(attr exclude_from_pos_files)
		(pad "1" smd circle
			(at 0 0 180)
			(size 0.75 0.75)
			(layers "F.Cu" "F.Mask")
			(net 216 "Net-(J18A-VREF_B_M2C)")
			(pinfunction "1")
			(pintype "passive")
		)
	)
	(footprint "antmicro-footprints:R_0402_1005Metric"
		(layer "F.Cu")
		(at 211.9 154.71 -90)
		(descr "Resistor SMD 0402")
		(tags "resistor SMD 0402")
		(property "Reference" "R85"
			(at -0.96 0.35 270)
			(layer "F.SilkS")
			(effects
				(font
					(size 0.7 0.7)
					(thickness 0.15)
				)
				(justify left bottom)
			)
		)
		(property "Value" "R_0R_0402"
			(at 0 1.4 270)
			(layer "F.Fab")
			(effects
				(font
					(size 0.7 0.7)
					(thickness 0.15)
				)
				(justify left bottom)
			)
		)
		(property "Description" "SMD Chip Resistor, Jumper, 0 ohm, 100 mW, 0402 [1005 Metric], Thick Film, General Purpose"
			(at 0 0 270)
			(layer "F.Fab")
			(hide yes)
			(effects
				(font
					(size 1.27 1.27)
					(thickness 0.15)
				)
			)
		)
		(property "Author" "Antmicro"
			(at 57.19 366.61 0)
			(layer "F.Fab")
			(hide yes)
			(effects
				(font
					(size 1 1)
					(thickness 0.15)
				)
			)
		)
		(property "Current" "1A"
			(at 57.19 366.61 0)
			(layer "F.Fab")
			(hide yes)
			(effects
				(font
					(size 1 1)
					(thickness 0.15)
				)
			)
		)
		(property "License" "Apache-2.0"
			(at 57.19 366.61 0)
			(layer "F.Fab")
			(hide yes)
			(effects
				(font
					(size 1 1)
					(thickness 0.15)
				)
			)
		)
		(property "MPN" "ERJ2GE0R00X"
			(at 57.19 366.61 0)
			(layer "F.Fab")
			(hide yes)
			(effects
				(font
					(size 1 1)
					(thickness 0.15)
				)
			)
		)
		(property "Manufacturer" "Panasonic"
			(at 57.19 366.61 0)
			(layer "F.Fab")
			(hide yes)
			(effects
				(font
					(size 1 1)
					(thickness 0.15)
				)
			)
		)
		(property "Tolerance" ""
			(at 57.19 366.61 0)
			(layer "F.Fab")
			(hide yes)
			(effects
				(font
					(size 1 1)
					(thickness 0.15)
				)
			)
		)
		(property "Val" "0R"
			(at 57.19 366.61 0)
			(layer "F.Fab")
			(hide yes)
			(effects
				(font
					(size 1 1)
					(thickness 0.15)
				)
			)
		)
		(sheetname "SPI Flash + SD Card")
		(sheetfile "spi-flash.kicad_sch")
		(attr smd)
		(fp_rect
			(start -0.925 -0.47)
			(end 0.925 0.47)
			(stroke
				(width 0.05)
				(type default)
			)
			(fill no)
			(layer "F.CrtYd")
		)
		(fp_rect
			(start -0.5 -0.25)
			(end 0.5 0.25)
			(stroke
				(width 0.15)
				(type solid)
			)
			(fill no)
			(layer "F.Fab")
		)
		(pad "1" smd roundrect
			(at -0.48 0 270)
			(size 0.59 0.64)
			(layers "F.Cu" "F.Mask" "F.Paste")
			(roundrect_rratio 0.25)
			(net 402 "/FPGA Bank 33 & 34/USR_FLASH_0.DQ3")
			(pintype "passive")
		)
		(pad "2" smd roundrect
			(at 0.48 0 270)
			(size 0.59 0.64)
			(layers "F.Cu" "F.Mask" "F.Paste")
			(roundrect_rratio 0.25)
			(net 905 "/SPI Flash + SD Card/USR_FLASH_0_DQ3")
			(pintype "passive")
		)
	)
	(footprint "antmicro-footprints:R_0402_1005Metric"
		(layer "F.Cu")
		(at 160 184 -90)
		(descr "Resistor SMD 0402")
		(tags "resistor SMD 0402")
		(property "Reference" "R366"
			(at -0.7 -0.4 270)
			(layer "F.SilkS")
			(effects
				(font
					(size 0.7 0.7)
					(thickness 0.15)
				)
				(justify left bottom)
			)
		)
		(property "Value" "R_0R_0402"
			(at 0 1.4 270)
			(layer "F.Fab")
			(effects
				(font
					(size 0.7 0.7)
					(thickness 0.15)
				)
				(justify left bottom)
			)
		)
		(property "Description" "SMD Chip Resistor, Jumper, 0 ohm, 100 mW, 0402 [1005 Metric], Thick Film, General Purpose"
			(at 0 0 270)
			(layer "F.Fab")
			(hide yes)
			(effects
				(font
					(size 1.27 1.27)
					(thickness 0.15)
				)
			)
		)
		(property "Author" "Antmicro"
			(at -24 344 0)
			(layer "F.Fab")
			(hide yes)
			(effects
				(font
					(size 1 1)
					(thickness 0.15)
				)
			)
		)
		(property "Current" "1A"
			(at -24 344 0)
			(layer "F.Fab")
			(hide yes)
			(effects
				(font
					(size 1 1)
					(thickness 0.15)
				)
			)
		)
		(property "DNP" "DNP"
			(at -24 344 0)
			(layer "F.Fab")
			(hide yes)
			(effects
				(font
					(size 1 1)
					(thickness 0.15)
				)
			)
		)
		(property "License" "Apache-2.0"
			(at -24 344 0)
			(layer "F.Fab")
			(hide yes)
			(effects
				(font
					(size 1 1)
					(thickness 0.15)
				)
			)
		)
		(property "MPN" "ERJ2GE0R00X"
			(at -24 344 0)
			(layer "F.Fab")
			(hide yes)
			(effects
				(font
					(size 1 1)
					(thickness 0.15)
				)
			)
		)
		(property "Manufacturer" "Panasonic"
			(at -24 344 0)
			(layer "F.Fab")
			(hide yes)
			(effects
				(font
					(size 1 1)
					(thickness 0.15)
				)
			)
		)
		(property "Tolerance" ""
			(at -24 344 0)
			(layer "F.Fab")
			(hide yes)
			(effects
				(font
					(size 1 1)
					(thickness 0.15)
				)
			)
		)
		(property "Val" "0R"
			(at -24 344 0)
			(layer "F.Fab")
			(hide yes)
			(effects
				(font
					(size 1 1)
					(thickness 0.15)
				)
			)
		)
		(property "dnp" ""
			(at -24 344 0)
			(layer "F.Fab")
			(hide yes)
			(effects
				(font
					(size 1 1)
					(thickness 0.15)
				)
			)
		)
		(property "exclude_from_bom" ""
			(at -24 344 0)
			(layer "F.Fab")
			(hide yes)
			(effects
				(font
					(size 1 1)
					(thickness 0.15)
				)
			)
		)
		(sheetname "FPGA Bank 12 & 13")
		(sheetfile "fpga-bank-12-13.kicad_sch")
		(attr smd exclude_from_bom)
		(fp_rect
			(start -0.925 -0.47)
			(end 0.925 0.47)
			(stroke
				(width 0.05)
				(type default)
			)
			(fill no)
			(layer "F.CrtYd")
		)
		(fp_rect
			(start -0.5 -0.25)
			(end 0.5 0.25)
			(stroke
				(width 0.15)
				(type solid)
			)
			(fill no)
			(layer "F.Fab")
		)
		(pad "1" smd roundrect
			(at -0.48 0 270)
			(size 0.59 0.64)
			(layers "F.Cu" "F.Mask" "F.Paste")
			(roundrect_rratio 0.25)
			(net 572 "/FPGA Bank 12 & 13/~{PB_CTRL_INT}")
			(pintype "passive")
		)
		(pad "2" smd roundrect
			(at 0.48 0 270)
			(size 0.59 0.64)
			(layers "F.Cu" "F.Mask" "F.Paste")
			(roundrect_rratio 0.25)
			(net 577 "/DC-DC Converters/PB_CTRL.~{PB_CTRL_INT}")
			(pintype "passive")
		)
	)
	(footprint "antmicro-footprints:C_0402_1005Metric"
		(layer "F.Cu")
		(at 171.1 176.1625 90)
		(descr "Capacitor SMD 0402")
		(tags "capacitor SMD 0402")
		(property "Reference" "C334"
			(at -3.6375 0.4 90)
			(layer "F.SilkS")
			(effects
				(font
					(size 0.7 0.7)
					(thickness 0.15)
				)
				(justify left bottom)
			)
		)
		(property "Value" "C_1u_0402"
			(at 0 1.4 90)
			(layer "F.Fab")
			(effects
				(font
					(size 0.7 0.7)
					(thickness 0.15)
				)
				(justify left bottom)
			)
		)
		(property "Description" "SMD Multilayer Ceramic Capacitor, 1 µF, 10 V, 0402 [1005 Metric], ± 10%, X6S, C"
			(at 0 0 90)
			(layer "F.Fab")
			(hide yes)
			(effects
				(font
					(size 1.27 1.27)
					(thickness 0.15)
				)
			)
		)
		(property "Author" "Antmicro"
			(at 347.2625 5.0625 0)
			(layer "F.Fab")
			(hide yes)
			(effects
				(font
					(size 1 1)
					(thickness 0.15)
				)
			)
		)
		(property "DNP" "DNP"
			(at 347.2625 5.0625 0)
			(layer "F.Fab")
			(hide yes)
			(effects
				(font
					(size 1 1)
					(thickness 0.15)
				)
			)
		)
		(property "Dielectric" ""
			(at 347.2625 5.0625 0)
			(layer "F.Fab")
			(hide yes)
			(effects
				(font
					(size 1 1)
					(thickness 0.15)
				)
			)
		)
		(property "License" "Apache-2.0"
			(at 347.2625 5.0625 0)
			(layer "F.Fab")
			(hide yes)
			(effects
				(font
					(size 1 1)
					(thickness 0.15)
				)
			)
		)
		(property "MPN" "C1005X6S1A105K050BC"
			(at 347.2625 5.0625 0)
			(layer "F.Fab")
			(hide yes)
			(effects
				(font
					(size 1 1)
					(thickness 0.15)
				)
			)
		)
		(property "Manufacturer" "TDK"
			(at 347.2625 5.0625 0)
			(layer "F.Fab")
			(hide yes)
			(effects
				(font
					(size 1 1)
					(thickness 0.15)
				)
			)
		)
		(property "Val" "1u"
			(at 347.2625 5.0625 0)
			(layer "F.Fab")
			(hide yes)
			(effects
				(font
					(size 1 1)
					(thickness 0.15)
				)
			)
		)
		(property "Voltage" ""
			(at 347.2625 5.0625 0)
			(layer "F.Fab")
			(hide yes)
			(effects
				(font
					(size 1 1)
					(thickness 0.15)
				)
			)
		)
		(property "dnp" ""
			(at 347.2625 5.0625 0)
			(layer "F.Fab")
			(hide yes)
			(effects
				(font
					(size 1 1)
					(thickness 0.15)
				)
			)
		)
		(property "exclude_from_bom" ""
			(at 347.2625 5.0625 0)
			(layer "F.Fab")
			(hide yes)
			(effects
				(font
					(size 1 1)
					(thickness 0.15)
				)
			)
		)
		(sheetname "DC-DC Converters")
		(sheetfile "dc-dc.kicad_sch")
		(attr smd exclude_from_bom)
		(fp_rect
			(start -0.925 -0.47)
			(end 0.925 0.47)
			(stroke
				(width 0.05)
				(type default)
			)
			(fill no)
			(layer "F.CrtYd")
		)
		(fp_line
			(start 0.504 -0.25)
			(end 0.504 0.248)
			(stroke
				(width 0.15)
				(type solid)
			)
			(layer "F.Fab")
		)
		(fp_line
			(start -0.494 -0.25)
			(end 0.504 -0.25)
			(stroke
				(width 0.15)
				(type solid)
			)
			(layer "F.Fab")
		)
		(fp_line
			(start 0.504 0.248)
			(end -0.494 0.248)
			(stroke
				(width 0.15)
				(type solid)
			)
			(layer "F.Fab")
		)
		(fp_line
			(start -0.494 0.248)
			(end -0.494 -0.25)
			(stroke
				(width 0.15)
				(type solid)
			)
			(layer "F.Fab")
		)
		(pad "1" smd roundrect
			(at -0.48 0 90)
			(size 0.59 0.64)
			(layers "F.Cu" "F.Mask" "F.Paste")
			(roundrect_rratio 0.25)
			(net 1 "GND")
			(pintype "passive")
		)
		(pad "2" smd roundrect
			(at 0.48 0 90)
			(size 0.59 0.64)
			(layers "F.Cu" "F.Mask" "F.Paste")
			(roundrect_rratio 0.25)
			(net 740 "/DC-DC Converters/1V35_local")
			(pintype "passive")
		)
	)
	(footprint "antmicro-footprints:C_0402_1005Metric"
		(layer "F.Cu")
		(at 192.6 165.649 90)
		(descr "Capacitor SMD 0402")
		(tags "capacitor SMD 0402")
		(property "Reference" "C364"
			(at -1.401 -0.5 90)
			(layer "F.SilkS")
			(effects
				(font
					(size 0.7 0.7)
					(thickness 0.15)
				)
				(justify left bottom)
			)
		)
		(property "Value" "C_22p_0402"
			(at 0 1.4 90)
			(layer "F.Fab")
			(effects
				(font
					(size 0.7 0.7)
					(thickness 0.15)
				)
				(justify left bottom)
			)
		)
		(property "Description" "SMD Multilayer Ceramic Capacitor, 22 pF, 50 V, 0402 [1005 Metric], ± 5%, C0G / NP0, CC Series"
			(at 0 0 90)
			(layer "F.Fab")
			(hide yes)
			(effects
				(font
					(size 1.27 1.27)
					(thickness 0.15)
				)
			)
		)
		(property "Author" "Antmicro"
			(at 358.249 -26.951 0)
			(layer "F.Fab")
			(hide yes)
			(effects
				(font
					(size 1 1)
					(thickness 0.15)
				)
			)
		)
		(property "Dielectric" ""
			(at 358.249 -26.951 0)
			(layer "F.Fab")
			(hide yes)
			(effects
				(font
					(size 1 1)
					(thickness 0.15)
				)
			)
		)
		(property "License" "Apache-2.0"
			(at 358.249 -26.951 0)
			(layer "F.Fab")
			(hide yes)
			(effects
				(font
					(size 1 1)
					(thickness 0.15)
				)
			)
		)
		(property "MPN" "CC0402JRNPO9BN220"
			(at 358.249 -26.951 0)
			(layer "F.Fab")
			(hide yes)
			(effects
				(font
					(size 1 1)
					(thickness 0.15)
				)
			)
		)
		(property "Manufacturer" "YAGEO"
			(at 358.249 -26.951 0)
			(layer "F.Fab")
			(hide yes)
			(effects
				(font
					(size 1 1)
					(thickness 0.15)
				)
			)
		)
		(property "Val" "22p"
			(at 358.249 -26.951 0)
			(layer "F.Fab")
			(hide yes)
			(effects
				(font
					(size 1 1)
					(thickness 0.15)
				)
			)
		)
		(property "Voltage" ""
			(at 358.249 -26.951 0)
			(layer "F.Fab")
			(hide yes)
			(effects
				(font
					(size 1 1)
					(thickness 0.15)
				)
			)
		)
		(sheetname "DC-DC Converters")
		(sheetfile "dc-dc.kicad_sch")
		(attr smd)
		(fp_rect
			(start -0.925 -0.47)
			(end 0.925 0.47)
			(stroke
				(width 0.05)
				(type default)
			)
			(fill no)
			(layer "F.CrtYd")
		)
		(fp_line
			(start 0.504 -0.25)
			(end 0.504 0.248)
			(stroke
				(width 0.15)
				(type solid)
			)
			(layer "F.Fab")
		)
		(fp_line
			(start -0.494 -0.25)
			(end 0.504 -0.25)
			(stroke
				(width 0.15)
				(type solid)
			)
			(layer "F.Fab")
		)
		(fp_line
			(start 0.504 0.248)
			(end -0.494 0.248)
			(stroke
				(width 0.15)
				(type solid)
			)
			(layer "F.Fab")
		)
		(fp_line
			(start -0.494 0.248)
			(end -0.494 -0.25)
			(stroke
				(width 0.15)
				(type solid)
			)
			(layer "F.Fab")
		)
		(pad "1" smd roundrect
			(at -0.48 0 90)
			(size 0.59 0.64)
			(layers "F.Cu" "F.Mask" "F.Paste")
			(roundrect_rratio 0.25)
			(net 1230 "Net-(C364-Pad1)")
			(pintype "passive")
		)
		(pad "2" smd roundrect
			(at 0.48 0 90)
			(size 0.59 0.64)
			(layers "F.Cu" "F.Mask" "F.Paste")
			(roundrect_rratio 0.25)
			(net 751 "/DC-DC Converters/1V0_REG")
			(pintype "passive")
		)
	)
	(footprint "antmicro-footprints:C_0402_1005Metric"
		(layer "F.Cu")
		(at 173.077501 131.000001 90)
		(descr "Capacitor SMD 0402")
		(tags "capacitor SMD 0402")
		(property "Reference" "C309"
			(at -3.699999 0.369999 90)
			(layer "F.SilkS")
			(effects
				(font
					(size 0.7 0.7)
					(thickness 0.15)
				)
				(justify left bottom)
			)
		)
		(property "Value" "C_100n_0402"
			(at 0 1.4 90)
			(layer "F.Fab")
			(effects
				(font
					(size 0.7 0.7)
					(thickness 0.15)
				)
				(justify left bottom)
			)
		)
		(property "Description" "SMD Multilayer Ceramic Capacitor, 0.1 µF, 50 V, 0402 [1005 Metric], ± 10%, X5R, GRM Series"
			(at 0 0 90)
			(layer "F.Fab")
			(hide yes)
			(effects
				(font
					(size 1.27 1.27)
					(thickness 0.15)
				)
			)
		)
		(property "Author" "Antmicro"
			(at 304.077502 -42.0775 0)
			(layer "F.Fab")
			(hide yes)
			(effects
				(font
					(size 1 1)
					(thickness 0.15)
				)
			)
		)
		(property "Dielectric" "X5R"
			(at 304.077502 -42.0775 0)
			(layer "F.Fab")
			(hide yes)
			(effects
				(font
					(size 1 1)
					(thickness 0.15)
				)
			)
		)
		(property "License" "Apache-2.0"
			(at 304.077502 -42.0775 0)
			(layer "F.Fab")
			(hide yes)
			(effects
				(font
					(size 1 1)
					(thickness 0.15)
				)
			)
		)
		(property "MPN" "GRM155R61H104KE14D"
			(at 304.077502 -42.0775 0)
			(layer "F.Fab")
			(hide yes)
			(effects
				(font
					(size 1 1)
					(thickness 0.15)
				)
			)
		)
		(property "Manufacturer" "Murata"
			(at 304.077502 -42.0775 0)
			(layer "F.Fab")
			(hide yes)
			(effects
				(font
					(size 1 1)
					(thickness 0.15)
				)
			)
		)
		(property "Val" "100n"
			(at 304.077502 -42.0775 0)
			(layer "F.Fab")
			(hide yes)
			(effects
				(font
					(size 1 1)
					(thickness 0.15)
				)
			)
		)
		(property "Voltage" "50V"
			(at 304.077502 -42.0775 0)
			(layer "F.Fab")
			(hide yes)
			(effects
				(font
					(size 1 1)
					(thickness 0.15)
				)
			)
		)
		(sheetname "FMC+ HSPC")
		(sheetfile "fmc-hspc.kicad_sch")
		(attr smd)
		(fp_rect
			(start -0.925 -0.47)
			(end 0.925 0.47)
			(stroke
				(width 0.05)
				(type default)
			)
			(fill no)
			(layer "F.CrtYd")
		)
		(fp_line
			(start 0.504 -0.25)
			(end 0.504 0.248)
			(stroke
				(width 0.15)
				(type solid)
			)
			(layer "F.Fab")
		)
		(fp_line
			(start -0.494 -0.25)
			(end 0.504 -0.25)
			(stroke
				(width 0.15)
				(type solid)
			)
			(layer "F.Fab")
		)
		(fp_line
			(start 0.504 0.248)
			(end -0.494 0.248)
			(stroke
				(width 0.15)
				(type solid)
			)
			(layer "F.Fab")
		)
		(fp_line
			(start -0.494 0.248)
			(end -0.494 -0.25)
			(stroke
				(width 0.15)
				(type solid)
			)
			(layer "F.Fab")
		)
		(pad "1" smd roundrect
			(at -0.48 0 90)
			(size 0.59 0.64)
			(layers "F.Cu" "F.Mask" "F.Paste")
			(roundrect_rratio 0.25)
			(net 101 "/FMC+ HSPC/GTX115.TX2_N")
			(pintype "passive")
		)
		(pad "2" smd roundrect
			(at 0.48 0 90)
			(size 0.59 0.64)
			(layers "F.Cu" "F.Mask" "F.Paste")
			(roundrect_rratio 0.25)
			(net 98 "/FMC+ HSPC/GTX_TX5_C_N")
			(pintype "passive")
		)
	)
	(footprint "antmicro-footprints:R_0402_1005Metric"
		(layer "F.Cu")
		(at 205.103752 98.9615 90)
		(descr "Resistor SMD 0402")
		(tags "resistor SMD 0402")
		(property "Reference" "R248"
			(at -9.0385 6.596248 90)
			(layer "F.SilkS")
			(effects
				(font
					(size 0.7 0.7)
					(thickness 0.15)
				)
				(justify left bottom)
			)
		)
		(property "Value" "R_12k_0402"
			(at 0 1.4 90)
			(layer "F.Fab")
			(effects
				(font
					(size 0.7 0.7)
					(thickness 0.15)
				)
				(justify left bottom)
			)
		)
		(property "Description" "SMD Chip Resistor, 12 kohm, ± 1%, 62.5 mW, 0402 [1005 Metric], Thick Film, General Purpose"
			(at 0 0 90)
			(layer "F.Fab")
			(hide yes)
			(effects
				(font
					(size 1.27 1.27)
					(thickness 0.15)
				)
			)
		)
		(property "Author" "Antmicro"
			(at 304.065252 -106.142252 0)
			(layer "F.Fab")
			(hide yes)
			(effects
				(font
					(size 1 1)
					(thickness 0.15)
				)
			)
		)
		(property "License" "Apache-2.0"
			(at 304.065252 -106.142252 0)
			(layer "F.Fab")
			(hide yes)
			(effects
				(font
					(size 1 1)
					(thickness 0.15)
				)
			)
		)
		(property "MPN" "CR0402-FX-1202GLF"
			(at 304.065252 -106.142252 0)
			(layer "F.Fab")
			(hide yes)
			(effects
				(font
					(size 1 1)
					(thickness 0.15)
				)
			)
		)
		(property "Manufacturer" "Bourns"
			(at 304.065252 -106.142252 0)
			(layer "F.Fab")
			(hide yes)
			(effects
				(font
					(size 1 1)
					(thickness 0.15)
				)
			)
		)
		(property "Tolerance" "1%"
			(at 304.065252 -106.142252 0)
			(layer "F.Fab")
			(hide yes)
			(effects
				(font
					(size 1 1)
					(thickness 0.15)
				)
			)
		)
		(property "Val" "12k"
			(at 304.065252 -106.142252 0)
			(layer "F.Fab")
			(hide yes)
			(effects
				(font
					(size 1 1)
					(thickness 0.15)
				)
			)
		)
		(sheetname "HDMI + Ethernet")
		(sheetfile "hdmi-ethernet.kicad_sch")
		(attr smd)
		(fp_rect
			(start -0.925 -0.47)
			(end 0.925 0.47)
			(stroke
				(width 0.05)
				(type default)
			)
			(fill no)
			(layer "F.CrtYd")
		)
		(fp_rect
			(start -0.5 -0.25)
			(end 0.5 0.25)
			(stroke
				(width 0.15)
				(type solid)
			)
			(fill no)
			(layer "F.Fab")
		)
		(pad "1" smd roundrect
			(at -0.48 0 90)
			(size 0.59 0.64)
			(layers "F.Cu" "F.Mask" "F.Paste")
			(roundrect_rratio 0.25)
			(net 1 "GND")
			(pintype "passive")
		)
		(pad "2" smd roundrect
			(at 0.48 0 90)
			(size 0.59 0.64)
			(layers "F.Cu" "F.Mask" "F.Paste")
			(roundrect_rratio 0.25)
			(net 953 "/HDMI + Ethernet/GBE_ISET")
			(pintype "passive")
		)
	)
	(footprint "antmicro-footprints:R_0402_1005Metric"
		(layer "F.Cu")
		(at 231.580275 161.75712 -90)
		(descr "Resistor SMD 0402")
		(tags "resistor SMD 0402")
		(property "Reference" "R18"
			(at 0.74288 -0.369725 90)
			(layer "F.SilkS")
			(effects
				(font
					(size 0.7 0.7)
					(thickness 0.15)
				)
				(justify right bottom)
			)
		)
		(property "Value" "R_0R_0402"
			(at 0 1.4 90)
			(layer "F.Fab")
			(effects
				(font
					(size 0.7 0.7)
					(thickness 0.15)
				)
				(justify right bottom)
			)
		)
		(property "Description" "SMD Chip Resistor, Jumper, 0 ohm, 100 mW, 0402 [1005 Metric], Thick Film, General Purpose"
			(at 0 0 270)
			(layer "F.Fab")
			(hide yes)
			(effects
				(font
					(size 1.27 1.27)
					(thickness 0.15)
				)
			)
		)
		(property "Author" "Antmicro"
			(at 69.823155 393.337395 0)
			(layer "F.Fab")
			(hide yes)
			(effects
				(font
					(size 1 1)
					(thickness 0.15)
				)
			)
		)
		(property "Current" "1A"
			(at 69.823155 393.337395 0)
			(layer "F.Fab")
			(hide yes)
			(effects
				(font
					(size 1 1)
					(thickness 0.15)
				)
			)
		)
		(property "License" "Apache-2.0"
			(at 69.823155 393.337395 0)
			(layer "F.Fab")
			(hide yes)
			(effects
				(font
					(size 1 1)
					(thickness 0.15)
				)
			)
		)
		(property "MPN" "ERJ2GE0R00X"
			(at 69.823155 393.337395 0)
			(layer "F.Fab")
			(hide yes)
			(effects
				(font
					(size 1 1)
					(thickness 0.15)
				)
			)
		)
		(property "Manufacturer" "Panasonic"
			(at 69.823155 393.337395 0)
			(layer "F.Fab")
			(hide yes)
			(effects
				(font
					(size 1 1)
					(thickness 0.15)
				)
			)
		)
		(property "Tolerance" ""
			(at 69.823155 393.337395 0)
			(layer "F.Fab")
			(hide yes)
			(effects
				(font
					(size 1 1)
					(thickness 0.15)
				)
			)
		)
		(property "Val" "0R"
			(at 69.823155 393.337395 0)
			(layer "F.Fab")
			(hide yes)
			(effects
				(font
					(size 1 1)
					(thickness 0.15)
				)
			)
		)
		(sheetname "Power supply")
		(sheetfile "power-supply.kicad_sch")
		(attr smd)
		(fp_rect
			(start -0.925 -0.47)
			(end 0.925 0.47)
			(stroke
				(width 0.05)
				(type default)
			)
			(fill no)
			(layer "F.CrtYd")
		)
		(fp_rect
			(start -0.5 -0.25)
			(end 0.5 0.25)
			(stroke
				(width 0.15)
				(type solid)
			)
			(fill no)
			(layer "F.Fab")
		)
		(pad "1" smd roundrect
			(at -0.48 0 270)
			(size 0.59 0.64)
			(layers "F.Cu" "F.Mask" "F.Paste")
			(roundrect_rratio 0.25)
			(net 1349 "/SUP_MCU.PD_RST")
			(pintype "passive")
		)
		(pad "2" smd roundrect
			(at 0.48 0 270)
			(size 0.59 0.64)
			(layers "F.Cu" "F.Mask" "F.Paste")
			(roundrect_rratio 0.25)
			(net 983 "/Power supply/PD_CTRL.RESET")
			(pintype "passive")
		)
	)
	(footprint "antmicro-footprints:R_0402_1005Metric"
		(layer "F.Cu")
		(at 242.599 117.404 -90)
		(descr "Resistor SMD 0402")
		(tags "resistor SMD 0402")
		(property "Reference" "R351"
			(at 1.396 1.649 90)
			(unlocked yes)
			(layer "F.SilkS")
			(effects
				(font
					(size 0.7 0.7)
					(thickness 0.15)
				)
				(justify left bottom)
			)
		)
		(property "Value" "R_2k2_0402"
			(at 0 1.4 270)
			(layer "F.Fab")
			(effects
				(font
					(size 0.7 0.7)
					(thickness 0.15)
				)
				(justify left bottom)
			)
		)
		(property "Description" "SMD Chip Resistor, 2.2 kohm, ± 1%, 62.5 mW, 0402 [1005 Metric], Thick Film, General Purpose"
			(at 0 0 270)
			(layer "F.Fab")
			(hide yes)
			(effects
				(font
					(size 1.27 1.27)
					(thickness 0.15)
				)
			)
		)
		(property "Author" "Antmicro"
			(at 125.195 360.003 0)
			(layer "F.Fab")
			(hide yes)
			(effects
				(font
					(size 1 1)
					(thickness 0.15)
				)
			)
		)
		(property "License" "Apache-2.0"
			(at 125.195 360.003 0)
			(layer "F.Fab")
			(hide yes)
			(effects
				(font
					(size 1 1)
					(thickness 0.15)
				)
			)
		)
		(property "MPN" "CR0402-FX-2201GLF"
			(at 125.195 360.003 0)
			(layer "F.Fab")
			(hide yes)
			(effects
				(font
					(size 1 1)
					(thickness 0.15)
				)
			)
		)
		(property "Manufacturer" "Bourns"
			(at 125.195 360.003 0)
			(layer "F.Fab")
			(hide yes)
			(effects
				(font
					(size 1 1)
					(thickness 0.15)
				)
			)
		)
		(property "Tolerance" "1%"
			(at 125.195 360.003 0)
			(layer "F.Fab")
			(hide yes)
			(effects
				(font
					(size 1 1)
					(thickness 0.15)
				)
			)
		)
		(property "Val" "2k2"
			(at 125.195 360.003 0)
			(layer "F.Fab")
			(hide yes)
			(effects
				(font
					(size 1 1)
					(thickness 0.15)
				)
			)
		)
		(sheetname "USB PHY")
		(sheetfile "usb-phy.kicad_sch")
		(attr smd)
		(fp_rect
			(start -0.925 -0.47)
			(end 0.925 0.47)
			(stroke
				(width 0.05)
				(type default)
			)
			(fill no)
			(layer "F.CrtYd")
		)
		(fp_rect
			(start -0.5 -0.25)
			(end 0.5 0.25)
			(stroke
				(width 0.15)
				(type solid)
			)
			(fill no)
			(layer "F.Fab")
		)
		(pad "1" smd roundrect
			(at -0.48 0 270)
			(size 0.59 0.64)
			(layers "F.Cu" "F.Mask" "F.Paste")
			(roundrect_rratio 0.25)
			(net 389 "Net-(U43-ISET)")
			(pintype "passive")
		)
		(pad "2" smd roundrect
			(at 0.48 0 270)
			(size 0.59 0.64)
			(layers "F.Cu" "F.Mask" "F.Paste")
			(roundrect_rratio 0.25)
			(net 1 "GND")
			(pintype "passive")
		)
	)
	(footprint "antmicro-footprints:NetTie-2_SMD_Pad0.127mm"
		(layer "F.Cu")
		(at 189.1 146.349999)
		(descr "Net tie, 2 pin, 0.127mm  SMD pads")
		(tags "net tie")
		(property "Reference" "NT28"
			(at -0.128 -1.345 0)
			(layer "F.SilkS")
			(hide yes)
			(effects
				(font
					(size 0.7 0.7)
					(thickness 0.15)
				)
				(justify left bottom)
			)
		)
		(property "Value" "Net-Tie_2"
			(at 0 1.199 0)
			(layer "F.Fab")
			(effects
				(font
					(size 0.7 0.7)
					(thickness 0.15)
				)
				(justify left bottom)
			)
		)
		(property "Description" "Net tie, 2 pins"
			(at 0 0 0)
			(layer "F.Fab")
			(hide yes)
			(effects
				(font
					(size 1.27 1.27)
					(thickness 0.15)
				)
			)
		)
		(property "Author" "Antmicro"
			(at 0 0 0)
			(layer "F.Fab")
			(hide yes)
			(effects
				(font
					(size 1 1)
					(thickness 0.15)
				)
			)
		)
		(property "License" "Apache-2.0"
			(at 0 0 0)
			(layer "F.Fab")
			(hide yes)
			(effects
				(font
					(size 1 1)
					(thickness 0.15)
				)
			)
		)
		(property "MPN" ""
			(at 0 0 0)
			(layer "F.Fab")
			(hide yes)
			(effects
				(font
					(size 1 1)
					(thickness 0.15)
				)
			)
		)
		(property "Manufacturer" ""
			(at 0 0 0)
			(layer "F.Fab")
			(hide yes)
			(effects
				(font
					(size 1 1)
					(thickness 0.15)
				)
			)
		)
		(sheetname "DC-DC Converters")
		(sheetfile "dc-dc.kicad_sch")
		(attr exclude_from_pos_files)
		(net_tie_pad_groups "1, 2")
		(fp_poly
			(pts
				(xy -0.0635 -0.0635) (xy 0.0625 -0.0635) (xy 0.0625 0.0635) (xy -0.0635 0.0635)
			)
			(stroke
				(width 0)
				(type solid)
			)
			(fill yes)
			(layer "F.Cu")
		)
		(pad "1" smd roundrect
			(at -0.127 0 180)
			(size 0.127 0.127)
			(layers "F.Cu")
			(roundrect_rratio 0.5)
			(chamfer_ratio 0)
			(chamfer top_left bottom_left)
			(net 1216 "/DC-DC Converters/SENSE_1V35_P")
			(pinfunction "1")
			(pintype "passive")
		)
		(pad "2" smd roundrect
			(at 0.126 0)
			(size 0.127 0.127)
			(layers "F.Cu")
			(roundrect_rratio 0.5)
			(chamfer_ratio 0)
			(chamfer top_left bottom_left)
			(net 25 "+1V35")
			(pinfunction "2")
			(pintype "passive")
		)
	)
	(footprint "antmicro-footprints:Resonator_SMD_Abracon_ABM8G_3.2x2.5mm"
		(layer "F.Cu")
		(at 231.4 139.3)
		(property "Reference" "Y5"
			(at 2.85 0.7 270)
			(layer "F.SilkS")
			(effects
				(font
					(size 0.7 0.7)
					(thickness 0.15)
				)
				(justify left bottom)
			)
		)
		(property "Value" "Resonator_12MHz_ABM8G"
			(at -1.75 2.548 0)
			(layer "F.Fab")
			(effects
				(font
					(size 0.7 0.7)
					(thickness 0.15)
				)
				(justify left bottom)
			)
		)
		(property "Description" "Crystal, 12 MHz, SMT, 3.2mm x 2.5mm, 30 ppm, 18 pF, 20 ppm, ABM8G"
			(at 0 0 0)
			(layer "F.Fab")
			(hide yes)
			(effects
				(font
					(size 1.27 1.27)
					(thickness 0.15)
				)
			)
		)
		(property "Author" "Antmicro"
			(at 0 0 0)
			(layer "F.Fab")
			(hide yes)
			(effects
				(font
					(size 1 1)
					(thickness 0.15)
				)
			)
		)
		(property "License" "Apache-2.0"
			(at 0 0 0)
			(layer "F.Fab")
			(hide yes)
			(effects
				(font
					(size 1 1)
					(thickness 0.15)
				)
			)
		)
		(property "MPN" "ABM8G-12.000MHZ-18-D2Y-T"
			(at 0 0 0)
			(layer "F.Fab")
			(hide yes)
			(effects
				(font
					(size 1 1)
					(thickness 0.15)
				)
			)
		)
		(property "Manufacturer" "Abracon"
			(at 0 0 0)
			(layer "F.Fab")
			(hide yes)
			(effects
				(font
					(size 1 1)
					(thickness 0.15)
				)
			)
		)
		(property "Val" "12 MHz"
			(at 0 0 0)
			(layer "F.Fab")
			(hide yes)
			(effects
				(font
					(size 1 1)
					(thickness 0.15)
				)
			)
		)
		(sheetname "Clocks")
		(sheetfile "clocks.kicad_sch")
		(attr smd)
		(fp_line
			(start -1.6 0.3)
			(end -1.6 -0.2)
			(stroke
				(width 0.15)
				(type solid)
			)
			(layer "F.SilkS")
		)
		(fp_line
			(start -0.35 -1.25)
			(end 0.45 -1.25)
			(stroke
				(width 0.15)
				(type solid)
			)
			(layer "F.SilkS")
		)
		(fp_line
			(start -0.35 1.25)
			(end 0.45 1.25)
			(stroke
				(width 0.15)
				(type solid)
			)
			(layer "F.SilkS")
		)
		(fp_line
			(start 1.6 0.3)
			(end 1.6 -0.2)
			(stroke
				(width 0.15)
				(type solid)
			)
			(layer "F.SilkS")
		)
		(fp_circle
			(center -1.75 1.5)
			(end -1.7 1.5)
			(stroke
				(width 0.15)
				(type solid)
			)
			(fill no)
			(layer "F.SilkS")
		)
		(fp_rect
			(start -1.907 -1.55)
			(end 2.006 1.649)
			(stroke
				(width 0.05)
				(type solid)
			)
			(fill no)
			(layer "F.CrtYd")
		)
		(pad "1" smd roundrect
			(at -1.101 0.949)
			(size 1.3 1.1)
			(layers "F.Cu" "F.Mask" "F.Paste")
			(roundrect_rratio 0)
			(chamfer_ratio 0.2)
			(chamfer bottom_left)
			(net 752 "/Clocks/PLL_XI")
			(pintype "passive")
		)
		(pad "2" smd rect
			(at 1.199 0.949)
			(size 1.3 1.1)
			(layers "F.Cu" "F.Mask" "F.Paste")
			(net 1 "GND")
			(pinfunction "SH")
			(pintype "passive")
		)
		(pad "3" smd rect
			(at 1.199 -0.85)
			(size 1.3 1.1)
			(layers "F.Cu" "F.Mask" "F.Paste")
			(net 753 "/Clocks/PLL_XO")
			(pintype "passive")
		)
		(pad "4" smd rect
			(at -1.101 -0.85)
			(size 1.3 1.1)
			(layers "F.Cu" "F.Mask" "F.Paste")
			(net 1 "GND")
			(pinfunction "SH")
			(pintype "passive")
		)
	)
	(footprint "antmicro-footprints:FB_0805_2012Metric"
		(layer "F.Cu")
		(at 232.9 179)
		(descr "FERRITE BEAD 0805")
		(tags "FERRITE BEAD 0805")
		(property "Reference" "FB1"
			(at -1 1.9 0)
			(layer "F.SilkS")
			(effects
				(font
					(size 0.7 0.7)
					(thickness 0.15)
				)
				(justify left bottom)
			)
		)
		(property "Value" "FB_220Z_2A_Murata-BLM21PG_0805"
			(at 0 1.8 0)
			(layer "F.Fab")
			(effects
				(font
					(size 0.7 0.7)
					(thickness 0.15)
				)
				(justify left bottom)
			)
		)
		(property "Description" "Ferrite Bead, 0805 [2012 Metric], 220 ohm, 2 A, BLM21, 0.045 ohm, ± 25%, DC power line"
			(at 0 0 0)
			(layer "F.Fab")
			(hide yes)
			(effects
				(font
					(size 1.27 1.27)
					(thickness 0.15)
				)
			)
		)
		(property "Author" "Antmicro"
			(at 0 0 0)
			(layer "F.Fab")
			(hide yes)
			(effects
				(font
					(size 1 1)
					(thickness 0.15)
				)
			)
		)
		(property "Current" ""
			(at 0 0 0)
			(layer "F.Fab")
			(hide yes)
			(effects
				(font
					(size 1 1)
					(thickness 0.15)
				)
			)
		)
		(property "License" "Apache-2.0"
			(at 0 0 0)
			(layer "F.Fab")
			(hide yes)
			(effects
				(font
					(size 1 1)
					(thickness 0.15)
				)
			)
		)
		(property "MPN" "BLM21PG221SN1D"
			(at 0 0 0)
			(layer "F.Fab")
			(hide yes)
			(effects
				(font
					(size 1 1)
					(thickness 0.15)
				)
			)
		)
		(property "Manufacturer" "Murata"
			(at 0 0 0)
			(layer "F.Fab")
			(hide yes)
			(effects
				(font
					(size 1 1)
					(thickness 0.15)
				)
			)
		)
		(property "Val" "220Z/2A"
			(at 0 0 0)
			(layer "F.Fab")
			(hide yes)
			(effects
				(font
					(size 1 1)
					(thickness 0.15)
				)
			)
		)
		(sheetname "Power supply")
		(sheetfile "power-supply.kicad_sch")
		(attr smd)
		(fp_line
			(start -0.319 0.698)
			(end 0.281 0.698)
			(stroke
				(width 0.15)
				(type solid)
			)
			(layer "F.SilkS")
		)
		(fp_line
			(start -0.299 -0.698)
			(end 0.299 -0.698)
			(stroke
				(width 0.15)
				(type solid)
			)
			(layer "F.SilkS")
		)
		(fp_rect
			(start 1.95 -0.9)
			(end -1.95 0.9)
			(stroke
				(width 0.05)
				(type default)
			)
			(fill no)
			(layer "F.CrtYd")
		)
		(fp_line
			(start -0.948 -0.681)
			(end 0.948 -0.681)
			(stroke
				(width 0.15)
				(type solid)
			)
			(layer "F.Fab")
		)
		(fp_line
			(start -0.948 -0.676)
			(end -0.948 0.676)
			(stroke
				(width 0.15)
				(type solid)
			)
			(layer "F.Fab")
		)
		(fp_line
			(start -0.948 0.681)
			(end 0.948 0.681)
			(stroke
				(width 0.15)
				(type solid)
			)
			(layer "F.Fab")
		)
		(fp_line
			(start 0.948 -0.676)
			(end 0.948 0.676)
			(stroke
				(width 0.15)
				(type solid)
			)
			(layer "F.Fab")
		)
		(pad "1" smd roundrect
			(at -1.1 0)
			(size 1.2 1.3)
			(layers "F.Cu" "F.Mask" "F.Paste")
			(roundrect_rratio 0.25)
			(net 757 "Net-(D4-Pad2)")
			(pintype "passive")
		)
		(pad "2" smd roundrect
			(at 1.1 0)
			(size 1.2 1.3)
			(layers "F.Cu" "F.Mask" "F.Paste")
			(roundrect_rratio 0.25)
			(net 698 "/Power supply/VDD")
			(pintype "passive")
		)
	)
	(footprint "antmicro-footprints:TP_SMD_0.75mm"
		(layer "F.Cu")
		(at 181.7 170.1492)
		(property "Reference" "TP8"
			(at 0.4 0.3508 0)
			(layer "F.SilkS")
			(effects
				(font
					(size 0.7 0.7)
					(thickness 0.15)
				)
				(justify left bottom)
			)
		)
		(property "Value" "TP_0.75mm_SMD"
			(at 0 1.2 0)
			(layer "F.Fab")
			(effects
				(font
					(size 0.7 0.7)
					(thickness 0.15)
				)
				(justify left bottom)
			)
		)
		(property "Description" "SMT test point"
			(at 0 0 0)
			(layer "F.Fab")
			(hide yes)
			(effects
				(font
					(size 1.27 1.27)
					(thickness 0.15)
				)
			)
		)
		(property "Author" "Antmicro"
			(at 0 0 0)
			(layer "F.Fab")
			(hide yes)
			(effects
				(font
					(size 1 1)
					(thickness 0.15)
				)
			)
		)
		(property "License" "Apache-2.0"
			(at 0 0 0)
			(layer "F.Fab")
			(hide yes)
			(effects
				(font
					(size 1 1)
					(thickness 0.15)
				)
			)
		)
		(property "MPN" ""
			(at 0 0 0)
			(layer "F.Fab")
			(hide yes)
			(effects
				(font
					(size 1 1)
					(thickness 0.15)
				)
			)
		)
		(property "Manufacturer" ""
			(at 0 0 0)
			(layer "F.Fab")
			(hide yes)
			(effects
				(font
					(size 1 1)
					(thickness 0.15)
				)
			)
		)
		(sheetname "DC-DC Converters")
		(sheetfile "dc-dc.kicad_sch")
		(attr exclude_from_pos_files)
		(pad "1" smd circle
			(at 0 0)
			(size 0.75 0.75)
			(layers "F.Cu" "F.Mask")
			(net 1393 "/I2C.QDCDC2_SCL")
			(pinfunction "1")
			(pintype "passive")
		)
	)
	(footprint "antmicro-footprints:C_0402_1005Metric"
		(layer "F.Cu")
		(at 155.07 139.2)
		(descr "Capacitor SMD 0402")
		(tags "capacitor SMD 0402")
		(property "Reference" "C348"
			(at -0.47 -0.2 45)
			(layer "F.SilkS")
			(effects
				(font
					(size 0.7 0.7)
					(thickness 0.15)
				)
				(justify left bottom)
			)
		)
		(property "Value" "C_1u_0402"
			(at 0 1.4 0)
			(layer "F.Fab")
			(effects
				(font
					(size 0.7 0.7)
					(thickness 0.15)
				)
				(justify left bottom)
			)
		)
		(property "Description" "SMD Multilayer Ceramic Capacitor, 1 µF, 10 V, 0402 [1005 Metric], ± 10%, X6S, C"
			(at 0 0 0)
			(layer "F.Fab")
			(hide yes)
			(effects
				(font
					(size 1.27 1.27)
					(thickness 0.15)
				)
			)
		)
		(property "Author" "Antmicro"
			(at 0 0 0)
			(layer "F.Fab")
			(hide yes)
			(effects
				(font
					(size 1 1)
					(thickness 0.15)
				)
			)
		)
		(property "Dielectric" ""
			(at 0 0 0)
			(layer "F.Fab")
			(hide yes)
			(effects
				(font
					(size 1 1)
					(thickness 0.15)
				)
			)
		)
		(property "License" "Apache-2.0"
			(at 0 0 0)
			(layer "F.Fab")
			(hide yes)
			(effects
				(font
					(size 1 1)
					(thickness 0.15)
				)
			)
		)
		(property "MPN" "C1005X6S1A105K050BC"
			(at 0 0 0)
			(layer "F.Fab")
			(hide yes)
			(effects
				(font
					(size 1 1)
					(thickness 0.15)
				)
			)
		)
		(property "Manufacturer" "TDK"
			(at 0 0 0)
			(layer "F.Fab")
			(hide yes)
			(effects
				(font
					(size 1 1)
					(thickness 0.15)
				)
			)
		)
		(property "Val" "1u"
			(at 0 0 0)
			(layer "F.Fab")
			(hide yes)
			(effects
				(font
					(size 1 1)
					(thickness 0.15)
				)
			)
		)
		(property "Voltage" ""
			(at 0 0 0)
			(layer "F.Fab")
			(hide yes)
			(effects
				(font
					(size 1 1)
					(thickness 0.15)
				)
			)
		)
		(sheetname "DC-DC Converters")
		(sheetfile "dc-dc.kicad_sch")
		(attr smd)
		(fp_rect
			(start -0.925 -0.47)
			(end 0.925 0.47)
			(stroke
				(width 0.05)
				(type default)
			)
			(fill no)
			(layer "F.CrtYd")
		)
		(fp_line
			(start -0.494 -0.25)
			(end 0.504 -0.25)
			(stroke
				(width 0.15)
				(type solid)
			)
			(layer "F.Fab")
		)
		(fp_line
			(start -0.494 0.248)
			(end -0.494 -0.25)
			(stroke
				(width 0.15)
				(type solid)
			)
			(layer "F.Fab")
		)
		(fp_line
			(start 0.504 -0.25)
			(end 0.504 0.248)
			(stroke
				(width 0.15)
				(type solid)
			)
			(layer "F.Fab")
		)
		(fp_line
			(start 0.504 0.248)
			(end -0.494 0.248)
			(stroke
				(width 0.15)
				(type solid)
			)
			(layer "F.Fab")
		)
		(pad "1" smd roundrect
			(at -0.48 0)
			(size 0.59 0.64)
			(layers "F.Cu" "F.Mask" "F.Paste")
			(roundrect_rratio 0.25)
			(net 1 "GND")
			(pintype "passive")
		)
		(pad "2" smd roundrect
			(at 0.48 0)
			(size 0.59 0.64)
			(layers "F.Cu" "F.Mask" "F.Paste")
			(roundrect_rratio 0.25)
			(net 743 "/DC-DC Converters/1V7")
			(pintype "passive")
		)
	)
	(footprint "antmicro-footprints:R_0402_1005Metric"
		(layer "F.Cu")
		(at 199.931 110.819)
		(descr "Resistor SMD 0402")
		(tags "resistor SMD 0402")
		(property "Reference" "R156"
			(at 0.869 0.381 0)
			(layer "F.SilkS")
			(effects
				(font
					(size 0.7 0.7)
					(thickness 0.15)
				)
				(justify left bottom)
			)
		)
		(property "Value" "R_10k_0402"
			(at 0 1.4 0)
			(layer "F.Fab")
			(effects
				(font
					(size 0.7 0.7)
					(thickness 0.15)
				)
				(justify left bottom)
			)
		)
		(property "Description" "SMD Chip Resistor, 10 kohm, ± 1%, 62.5 mW, 0402 [1005 Metric], Thick Film, General Purpose"
			(at 0 0 0)
			(layer "F.Fab")
			(hide yes)
			(effects
				(font
					(size 1.27 1.27)
					(thickness 0.15)
				)
			)
		)
		(property "Author" "Antmicro"
			(at 0 0 0)
			(layer "F.Fab")
			(hide yes)
			(effects
				(font
					(size 1 1)
					(thickness 0.15)
				)
			)
		)
		(property "License" "Apache-2.0"
			(at 0 0 0)
			(layer "F.Fab")
			(hide yes)
			(effects
				(font
					(size 1 1)
					(thickness 0.15)
				)
			)
		)
		(property "MPN" "CR0402-FX-1002GLF"
			(at 0 0 0)
			(layer "F.Fab")
			(hide yes)
			(effects
				(font
					(size 1 1)
					(thickness 0.15)
				)
			)
		)
		(property "Manufacturer" "Bourns"
			(at 0 0 0)
			(layer "F.Fab")
			(hide yes)
			(effects
				(font
					(size 1 1)
					(thickness 0.15)
				)
			)
		)
		(property "Tolerance" "1%"
			(at 0 0 0)
			(layer "F.Fab")
			(hide yes)
			(effects
				(font
					(size 1 1)
					(thickness 0.15)
				)
			)
		)
		(property "Val" "10k"
			(at 0 0 0)
			(layer "F.Fab")
			(hide yes)
			(effects
				(font
					(size 1 1)
					(thickness 0.15)
				)
			)
		)
		(sheetname "USB PHY")
		(sheetfile "usb-phy.kicad_sch")
		(attr smd)
		(fp_rect
			(start -0.925 -0.47)
			(end 0.925 0.47)
			(stroke
				(width 0.05)
				(type default)
			)
			(fill no)
			(layer "F.CrtYd")
		)
		(fp_rect
			(start -0.5 -0.25)
			(end 0.5 0.25)
			(stroke
				(width 0.15)
				(type solid)
			)
			(fill no)
			(layer "F.Fab")
		)
		(pad "1" smd roundrect
			(at -0.48 0)
			(size 0.59 0.64)
			(layers "F.Cu" "F.Mask" "F.Paste")
			(roundrect_rratio 0.25)
			(net 495 "/FPGA Bank 12 & 13/USB_HOST.INT")
			(pintype "passive")
		)
		(pad "2" smd roundrect
			(at 0.48 0)
			(size 0.59 0.64)
			(layers "F.Cu" "F.Mask" "F.Paste")
			(roundrect_rratio 0.25)
			(net 24 "+3V3")
			(pintype "passive")
		)
	)
	(footprint "antmicro-footprints:C_0402_1005Metric"
		(layer "F.Cu")
		(at 254.899 101 180)
		(descr "Capacitor SMD 0402")
		(tags "capacitor SMD 0402")
		(property "Reference" "C219"
			(at -1.451 -2.4 0)
			(layer "F.SilkS")
			(effects
				(font
					(size 0.7 0.7)
					(thickness 0.15)
				)
				(justify right bottom)
			)
		)
		(property "Value" "C_10u_0402"
			(at 0 1.4 0)
			(layer "F.Fab")
			(effects
				(font
					(size 0.7 0.7)
					(thickness 0.15)
				)
				(justify right bottom)
			)
		)
		(property "Description" "SMD Multilayer Ceramic Capacitor, 10 µF, 6.3 V, 0402 [1005 Metric], ± 20%, X5R, CC Series"
			(at 0 0 180)
			(layer "F.Fab")
			(hide yes)
			(effects
				(font
					(size 1.27 1.27)
					(thickness 0.15)
				)
			)
		)
		(property "Author" "Antmicro"
			(at 509.798 202 0)
			(layer "F.Fab")
			(hide yes)
			(effects
				(font
					(size 1 1)
					(thickness 0.15)
				)
			)
		)
		(property "Dielectric" ""
			(at 509.798 202 0)
			(layer "F.Fab")
			(hide yes)
			(effects
				(font
					(size 1 1)
					(thickness 0.15)
				)
			)
		)
		(property "License" "Apache-2.0"
			(at 509.798 202 0)
			(layer "F.Fab")
			(hide yes)
			(effects
				(font
					(size 1 1)
					(thickness 0.15)
				)
			)
		)
		(property "MPN" "CC0402MRX5R5BB106"
			(at 509.798 202 0)
			(layer "F.Fab")
			(hide yes)
			(effects
				(font
					(size 1 1)
					(thickness 0.15)
				)
			)
		)
		(property "Manufacturer" "YAGEO"
			(at 509.798 202 0)
			(layer "F.Fab")
			(hide yes)
			(effects
				(font
					(size 1 1)
					(thickness 0.15)
				)
			)
		)
		(property "Val" "10u"
			(at 509.798 202 0)
			(layer "F.Fab")
			(hide yes)
			(effects
				(font
					(size 1 1)
					(thickness 0.15)
				)
			)
		)
		(property "Voltage" ""
			(at 509.798 202 0)
			(layer "F.Fab")
			(hide yes)
			(effects
				(font
					(size 1 1)
					(thickness 0.15)
				)
			)
		)
		(sheetname "USB PHY")
		(sheetfile "usb-phy.kicad_sch")
		(attr smd)
		(fp_rect
			(start -0.925 -0.47)
			(end 0.925 0.47)
			(stroke
				(width 0.05)
				(type default)
			)
			(fill no)
			(layer "F.CrtYd")
		)
		(fp_line
			(start 0.504 0.248)
			(end -0.494 0.248)
			(stroke
				(width 0.15)
				(type solid)
			)
			(layer "F.Fab")
		)
		(fp_line
			(start 0.504 -0.25)
			(end 0.504 0.248)
			(stroke
				(width 0.15)
				(type solid)
			)
			(layer "F.Fab")
		)
		(fp_line
			(start -0.494 0.248)
			(end -0.494 -0.25)
			(stroke
				(width 0.15)
				(type solid)
			)
			(layer "F.Fab")
		)
		(fp_line
			(start -0.494 -0.25)
			(end 0.504 -0.25)
			(stroke
				(width 0.15)
				(type solid)
			)
			(layer "F.Fab")
		)
		(pad "1" smd roundrect
			(at -0.48 0 180)
			(size 0.59 0.64)
			(layers "F.Cu" "F.Mask" "F.Paste")
			(roundrect_rratio 0.25)
			(net 1 "GND")
			(pintype "passive")
		)
		(pad "2" smd roundrect
			(at 0.48 0 180)
			(size 0.59 0.64)
			(layers "F.Cu" "F.Mask" "F.Paste")
			(roundrect_rratio 0.25)
			(net 705 "/USB PHY/USB_HOST_VBUS")
			(pintype "passive")
		)
	)
	(footprint "antmicro-footprints:C_0402_1005Metric"
		(layer "F.Cu")
		(at 192.125 184.248999 -90)
		(descr "Capacitor SMD 0402")
		(tags "capacitor SMD 0402")
		(property "Reference" "C203"
			(at -1.298999 -1.275 90)
			(layer "F.SilkS")
			(effects
				(font
					(size 0.7 0.7)
					(thickness 0.15)
				)
				(justify right bottom)
			)
		)
		(property "Value" "C_100n_0402"
			(at 0 1.4 90)
			(layer "F.Fab")
			(effects
				(font
					(size 0.7 0.7)
					(thickness 0.15)
				)
				(justify right bottom)
			)
		)
		(property "Description" "SMD Multilayer Ceramic Capacitor, 0.1 µF, 50 V, 0402 [1005 Metric], ± 10%, X5R, GRM Series"
			(at 0 0 270)
			(layer "F.Fab")
			(hide yes)
			(effects
				(font
					(size 1.27 1.27)
					(thickness 0.15)
				)
			)
		)
		(property "Author" "Antmicro"
			(at 7.876001 376.373999 0)
			(layer "F.Fab")
			(hide yes)
			(effects
				(font
					(size 1 1)
					(thickness 0.15)
				)
			)
		)
		(property "Dielectric" "X5R"
			(at 7.876001 376.373999 0)
			(layer "F.Fab")
			(hide yes)
			(effects
				(font
					(size 1 1)
					(thickness 0.15)
				)
			)
		)
		(property "License" "Apache-2.0"
			(at 7.876001 376.373999 0)
			(layer "F.Fab")
			(hide yes)
			(effects
				(font
					(size 1 1)
					(thickness 0.15)
				)
			)
		)
		(property "MPN" "GRM155R61H104KE14D"
			(at 7.876001 376.373999 0)
			(layer "F.Fab")
			(hide yes)
			(effects
				(font
					(size 1 1)
					(thickness 0.15)
				)
			)
		)
		(property "Manufacturer" "Murata"
			(at 7.876001 376.373999 0)
			(layer "F.Fab")
			(hide yes)
			(effects
				(font
					(size 1 1)
					(thickness 0.15)
				)
			)
		)
		(property "Val" "100n"
			(at 7.876001 376.373999 0)
			(layer "F.Fab")
			(hide yes)
			(effects
				(font
					(size 1 1)
					(thickness 0.15)
				)
			)
		)
		(property "Voltage" "50V"
			(at 7.876001 376.373999 0)
			(layer "F.Fab")
			(hide yes)
			(effects
				(font
					(size 1 1)
					(thickness 0.15)
				)
			)
		)
		(sheetname "Power supply")
		(sheetfile "power-supply.kicad_sch")
		(attr smd)
		(fp_rect
			(start -0.925 -0.47)
			(end 0.925 0.47)
			(stroke
				(width 0.05)
				(type default)
			)
			(fill no)
			(layer "F.CrtYd")
		)
		(fp_line
			(start -0.494 0.248)
			(end -0.494 -0.25)
			(stroke
				(width 0.15)
				(type solid)
			)
			(layer "F.Fab")
		)
		(fp_line
			(start 0.504 0.248)
			(end -0.494 0.248)
			(stroke
				(width 0.15)
				(type solid)
			)
			(layer "F.Fab")
		)
		(fp_line
			(start -0.494 -0.25)
			(end 0.504 -0.25)
			(stroke
				(width 0.15)
				(type solid)
			)
			(layer "F.Fab")
		)
		(fp_line
			(start 0.504 -0.25)
			(end 0.504 0.248)
			(stroke
				(width 0.15)
				(type solid)
			)
			(layer "F.Fab")
		)
		(pad "1" smd roundrect
			(at -0.48 0 270)
			(size 0.59 0.64)
			(layers "F.Cu" "F.Mask" "F.Paste")
			(roundrect_rratio 0.25)
			(net 1 "GND")
			(pintype "passive")
		)
		(pad "2" smd roundrect
			(at 0.48 0 270)
			(size 0.59 0.64)
			(layers "F.Cu" "F.Mask" "F.Paste")
			(roundrect_rratio 0.25)
			(net 4 "/Power supply/DC_IN")
			(pintype "passive")
		)
	)
	(footprint "antmicro-footprints:R_0402_1005Metric"
		(layer "F.Cu")
		(at 236.35 145.45 180)
		(descr "Resistor SMD 0402")
		(tags "resistor SMD 0402")
		(property "Reference" "R183"
			(at 1.05 -4.45 180)
			(layer "F.SilkS")
			(effects
				(font
					(size 0.7 0.7)
					(thickness 0.15)
				)
				(justify left bottom)
			)
		)
		(property "Value" "R_33R_0402"
			(at 0 1.4 180)
			(layer "F.Fab")
			(effects
				(font
					(size 0.7 0.7)
					(thickness 0.15)
				)
				(justify left bottom)
			)
		)
		(property "Description" "SMD Chip Resistor, 33 ohm, ± 1%, 62.5 mW, 0402 [1005 Metric], Thick Film, General Purpose"
			(at 0 0 180)
			(layer "F.Fab")
			(hide yes)
			(effects
				(font
					(size 1.27 1.27)
					(thickness 0.15)
				)
			)
		)
		(property "Author" "Antmicro"
			(at 472.7 290.9 0)
			(layer "F.Fab")
			(hide yes)
			(effects
				(font
					(size 1 1)
					(thickness 0.15)
				)
			)
		)
		(property "License" "Apache-2.0"
			(at 472.7 290.9 0)
			(layer "F.Fab")
			(hide yes)
			(effects
				(font
					(size 1 1)
					(thickness 0.15)
				)
			)
		)
		(property "MPN" "CR0402-FX-33R0GLF"
			(at 472.7 290.9 0)
			(layer "F.Fab")
			(hide yes)
			(effects
				(font
					(size 1 1)
					(thickness 0.15)
				)
			)
		)
		(property "Manufacturer" "Bourns"
			(at 472.7 290.9 0)
			(layer "F.Fab")
			(hide yes)
			(effects
				(font
					(size 1 1)
					(thickness 0.15)
				)
			)
		)
		(property "Tolerance" "1%"
			(at 472.7 290.9 0)
			(layer "F.Fab")
			(hide yes)
			(effects
				(font
					(size 1 1)
					(thickness 0.15)
				)
			)
		)
		(property "Val" "33R"
			(at 472.7 290.9 0)
			(layer "F.Fab")
			(hide yes)
			(effects
				(font
					(size 1 1)
					(thickness 0.15)
				)
			)
		)
		(sheetname "USB PHY")
		(sheetfile "usb-phy.kicad_sch")
		(attr smd)
		(fp_rect
			(start -0.925 -0.47)
			(end 0.925 0.47)
			(stroke
				(width 0.05)
				(type default)
			)
			(fill no)
			(layer "F.CrtYd")
		)
		(fp_rect
			(start -0.5 -0.25)
			(end 0.5 0.25)
			(stroke
				(width 0.15)
				(type solid)
			)
			(fill no)
			(layer "F.Fab")
		)
		(pad "1" smd roundrect
			(at -0.48 0 180)
			(size 0.59 0.64)
			(layers "F.Cu" "F.Mask" "F.Paste")
			(roundrect_rratio 0.25)
			(net 375 "Net-(U23-B2Y)")
			(pintype "passive")
		)
		(pad "2" smd roundrect
			(at 0.48 0 180)
			(size 0.59 0.64)
			(layers "F.Cu" "F.Mask" "F.Paste")
			(roundrect_rratio 0.25)
			(net 1295 "/USB_SPI.MOSI")
			(pintype "passive")
		)
	)
	(footprint "antmicro-footprints:C_0402_1005Metric"
		(layer "F.Cu")
		(at 153.1 139.2 180)
		(descr "Capacitor SMD 0402")
		(tags "capacitor SMD 0402")
		(property "Reference" "C353"
			(at -1.85 2.2 225)
			(layer "F.SilkS")
			(effects
				(font
					(size 0.7 0.7)
					(thickness 0.15)
				)
				(justify right bottom)
			)
		)
		(property "Value" "C_10u_0402"
			(at 0 1.4 0)
			(layer "F.Fab")
			(effects
				(font
					(size 0.7 0.7)
					(thickness 0.15)
				)
				(justify right bottom)
			)
		)
		(property "Description" "SMD Multilayer Ceramic Capacitor, 10 µF, 6.3 V, 0402 [1005 Metric], ± 20%, X5R, CC Series"
			(at 0 0 180)
			(layer "F.Fab")
			(hide yes)
			(effects
				(font
					(size 1.27 1.27)
					(thickness 0.15)
				)
			)
		)
		(property "Author" "Antmicro"
			(at 306.2 278.4 0)
			(layer "F.Fab")
			(hide yes)
			(effects
				(font
					(size 1 1)
					(thickness 0.15)
				)
			)
		)
		(property "Dielectric" ""
			(at 306.2 278.4 0)
			(layer "F.Fab")
			(hide yes)
			(effects
				(font
					(size 1 1)
					(thickness 0.15)
				)
			)
		)
		(property "License" "Apache-2.0"
			(at 306.2 278.4 0)
			(layer "F.Fab")
			(hide yes)
			(effects
				(font
					(size 1 1)
					(thickness 0.15)
				)
			)
		)
		(property "MPN" "CC0402MRX5R5BB106"
			(at 306.2 278.4 0)
			(layer "F.Fab")
			(hide yes)
			(effects
				(font
					(size 1 1)
					(thickness 0.15)
				)
			)
		)
		(property "Manufacturer" "YAGEO"
			(at 306.2 278.4 0)
			(layer "F.Fab")
			(hide yes)
			(effects
				(font
					(size 1 1)
					(thickness 0.15)
				)
			)
		)
		(property "Val" "10u"
			(at 306.2 278.4 0)
			(layer "F.Fab")
			(hide yes)
			(effects
				(font
					(size 1 1)
					(thickness 0.15)
				)
			)
		)
		(property "Voltage" ""
			(at 306.2 278.4 0)
			(layer "F.Fab")
			(hide yes)
			(effects
				(font
					(size 1 1)
					(thickness 0.15)
				)
			)
		)
		(sheetname "DC-DC Converters")
		(sheetfile "dc-dc.kicad_sch")
		(attr smd)
		(fp_rect
			(start -0.925 -0.47)
			(end 0.925 0.47)
			(stroke
				(width 0.05)
				(type default)
			)
			(fill no)
			(layer "F.CrtYd")
		)
		(fp_line
			(start 0.504 0.248)
			(end -0.494 0.248)
			(stroke
				(width 0.15)
				(type solid)
			)
			(layer "F.Fab")
		)
		(fp_line
			(start 0.504 -0.25)
			(end 0.504 0.248)
			(stroke
				(width 0.15)
				(type solid)
			)
			(layer "F.Fab")
		)
		(fp_line
			(start -0.494 0.248)
			(end -0.494 -0.25)
			(stroke
				(width 0.15)
				(type solid)
			)
			(layer "F.Fab")
		)
		(fp_line
			(start -0.494 -0.25)
			(end 0.504 -0.25)
			(stroke
				(width 0.15)
				(type solid)
			)
			(layer "F.Fab")
		)
		(pad "1" smd roundrect
			(at -0.48 0 180)
			(size 0.59 0.64)
			(layers "F.Cu" "F.Mask" "F.Paste")
			(roundrect_rratio 0.25)
			(net 1 "GND")
			(pintype "passive")
		)
		(pad "2" smd roundrect
			(at 0.48 0 180)
			(size 0.59 0.64)
			(layers "F.Cu" "F.Mask" "F.Paste")
			(roundrect_rratio 0.25)
			(net 748 "/DC-DC Converters/MGTAVTT_OUT")
			(pintype "passive")
		)
	)
	(footprint "antmicro-footprints:NetTie-2_SMD_Pad0.127mm"
		(layer "F.Cu")
		(at 249.7 143.602 -90)
		(descr "Net tie, 2 pin, 0.127mm  SMD pads")
		(tags "net tie")
		(property "Reference" "NT20"
			(at -0.128 -1.345 270)
			(layer "F.SilkS")
			(hide yes)
			(effects
				(font
					(size 0.7 0.7)
					(thickness 0.15)
				)
				(justify left bottom)
			)
		)
		(property "Value" "Net-Tie_2"
			(at 0 1.199 270)
			(layer "F.Fab")
			(effects
				(font
					(size 0.7 0.7)
					(thickness 0.15)
				)
				(justify left bottom)
			)
		)
		(property "Description" "Net tie, 2 pins"
			(at 0 0 270)
			(layer "F.Fab")
			(hide yes)
			(effects
				(font
					(size 1.27 1.27)
					(thickness 0.15)
				)
			)
		)
		(property "Author" "Antmicro"
			(at 106.098 393.302 0)
			(layer "F.Fab")
			(hide yes)
			(effects
				(font
					(size 1 1)
					(thickness 0.15)
				)
			)
		)
		(property "License" "Apache-2.0"
			(at 106.098 393.302 0)
			(layer "F.Fab")
			(hide yes)
			(effects
				(font
					(size 1 1)
					(thickness 0.15)
				)
			)
		)
		(property "MPN" ""
			(at 106.098 393.302 0)
			(layer "F.Fab")
			(hide yes)
			(effects
				(font
					(size 1 1)
					(thickness 0.15)
				)
			)
		)
		(property "Manufacturer" ""
			(at 106.098 393.302 0)
			(layer "F.Fab")
			(hide yes)
			(effects
				(font
					(size 1 1)
					(thickness 0.15)
				)
			)
		)
		(sheetname "FPGA Bank 14 & 15")
		(sheetfile "fpga-bank-14-15.kicad_sch")
		(attr exclude_from_pos_files)
		(net_tie_pad_groups "1, 2")
		(fp_poly
			(pts
				(xy -0.0635 -0.0635) (xy 0.0625 -0.0635) (xy 0.0625 0.0635) (xy -0.0635 0.0635)
			)
			(stroke
				(width 0)
				(type solid)
			)
			(fill yes)
			(layer "F.Cu")
		)
		(pad "1" smd roundrect
			(at -0.127 0 90)
			(size 0.127 0.127)
			(layers "F.Cu")
			(roundrect_rratio 0.5)
			(chamfer_ratio 0)
			(chamfer top_left bottom_left)
			(net 75 "/FPGA Bank 14 & 15/SYSTEM_FLASH.~{CS}")
			(pinfunction "1")
			(pintype "passive")
		)
		(pad "2" smd roundrect
			(at 0.126 0 270)
			(size 0.127 0.127)
			(layers "F.Cu")
			(roundrect_rratio 0.5)
			(chamfer_ratio 0)
			(chamfer top_left bottom_left)
			(net 1334 "/SUP_MCU.CFG_CS")
			(pinfunction "2")
			(pintype "passive")
		)
	)
	(footprint "antmicro-footprints:R_0402_1005Metric"
		(layer "F.Cu")
		(at 246.999 113.904 180)
		(descr "Resistor SMD 0402")
		(tags "resistor SMD 0402")
		(property "Reference" "R348"
			(at 1.449 1.654 0)
			(layer "F.SilkS")
			(effects
				(font
					(size 0.7 0.7)
					(thickness 0.15)
				)
				(justify left bottom)
			)
		)
		(property "Value" "R_10k_0402"
			(at 0 1.4 180)
			(layer "F.Fab")
			(effects
				(font
					(size 0.7 0.7)
					(thickness 0.15)
				)
				(justify left bottom)
			)
		)
		(property "Description" "SMD Chip Resistor, 10 kohm, ± 1%, 62.5 mW, 0402 [1005 Metric], Thick Film, General Purpose"
			(at 0 0 180)
			(layer "F.Fab")
			(hide yes)
			(effects
				(font
					(size 1.27 1.27)
					(thickness 0.15)
				)
			)
		)
		(property "Author" "Antmicro"
			(at 493.998 227.808 0)
			(layer "F.Fab")
			(hide yes)
			(effects
				(font
					(size 1 1)
					(thickness 0.15)
				)
			)
		)
		(property "License" "Apache-2.0"
			(at 493.998 227.808 0)
			(layer "F.Fab")
			(hide yes)
			(effects
				(font
					(size 1 1)
					(thickness 0.15)
				)
			)
		)
		(property "MPN" "CR0402-FX-1002GLF"
			(at 493.998 227.808 0)
			(layer "F.Fab")
			(hide yes)
			(effects
				(font
					(size 1 1)
					(thickness 0.15)
				)
			)
		)
		(property "Manufacturer" "Bourns"
			(at 493.998 227.808 0)
			(layer "F.Fab")
			(hide yes)
			(effects
				(font
					(size 1 1)
					(thickness 0.15)
				)
			)
		)
		(property "Tolerance" "1%"
			(at 493.998 227.808 0)
			(layer "F.Fab")
			(hide yes)
			(effects
				(font
					(size 1 1)
					(thickness 0.15)
				)
			)
		)
		(property "Val" "10k"
			(at 493.998 227.808 0)
			(layer "F.Fab")
			(hide yes)
			(effects
				(font
					(size 1 1)
					(thickness 0.15)
				)
			)
		)
		(sheetname "USB PHY")
		(sheetfile "usb-phy.kicad_sch")
		(attr smd)
		(fp_rect
			(start -0.925 -0.47)
			(end 0.925 0.47)
			(stroke
				(width 0.05)
				(type default)
			)
			(fill no)
			(layer "F.CrtYd")
		)
		(fp_rect
			(start -0.5 -0.25)
			(end 0.5 0.25)
			(stroke
				(width 0.15)
				(type solid)
			)
			(fill no)
			(layer "F.Fab")
		)
		(pad "1" smd roundrect
			(at -0.48 0 180)
			(size 0.59 0.64)
			(layers "F.Cu" "F.Mask" "F.Paste")
			(roundrect_rratio 0.25)
			(net 386 "Net-(U43-FLG)")
			(pintype "passive")
		)
		(pad "2" smd roundrect
			(at 0.48 0 180)
			(size 0.59 0.64)
			(layers "F.Cu" "F.Mask" "F.Paste")
			(roundrect_rratio 0.25)
			(net 703 "+5V")
			(pintype "passive")
		)
	)
	(footprint "antmicro-footprints:DFN3538"
		(layer "F.Cu")
		(at 244.7 174.5 180)
		(property "Reference" "D7"
			(at 0.7 -3.3 0)
			(unlocked yes)
			(layer "F.SilkS")
			(effects
				(font
					(size 0.7 0.7)
					(thickness 0.15)
				)
				(justify left bottom)
			)
		)
		(property "Value" "CD-MMBL110S"
			(at 0 3.5 180)
			(unlocked yes)
			(layer "F.Fab")
			(effects
				(font
					(size 0.7 0.7)
					(thickness 0.15)
				)
				(justify left bottom)
			)
		)
		(property "Description" "TVS diode"
			(at 0 0 180)
			(layer "F.Fab")
			(hide yes)
			(effects
				(font
					(size 1.27 1.27)
					(thickness 0.15)
				)
			)
		)
		(property "Author" "Antmicro"
			(at 489.4 349 0)
			(layer "F.Fab")
			(hide yes)
			(effects
				(font
					(size 1 1)
					(thickness 0.15)
				)
			)
		)
		(property "DNP" "DNP"
			(at 489.4 349 0)
			(layer "F.Fab")
			(hide yes)
			(effects
				(font
					(size 1 1)
					(thickness 0.15)
				)
			)
		)
		(property "License" "Apache-2.0"
			(at 489.4 349 0)
			(layer "F.Fab")
			(hide yes)
			(effects
				(font
					(size 1 1)
					(thickness 0.15)
				)
			)
		)
		(property "MPN" "CD-MMBL110S"
			(at 489.4 349 0)
			(layer "F.Fab")
			(hide yes)
			(effects
				(font
					(size 1 1)
					(thickness 0.15)
				)
			)
		)
		(property "Manufacturer" "Bourns"
			(at 489.4 349 0)
			(layer "F.Fab")
			(hide yes)
			(effects
				(font
					(size 1 1)
					(thickness 0.15)
				)
			)
		)
		(property "dnp" ""
			(at 489.4 349 0)
			(layer "F.Fab")
			(hide yes)
			(effects
				(font
					(size 1 1)
					(thickness 0.15)
				)
			)
		)
		(property "exclude_from_bom" ""
			(at 489.4 349 0)
			(layer "F.Fab")
			(hide yes)
			(effects
				(font
					(size 1 1)
					(thickness 0.15)
				)
			)
		)
		(sheetname "Power supply")
		(sheetfile "power-supply.kicad_sch")
		(attr smd exclude_from_bom)
		(fp_line
			(start 1.8 -2)
			(end 1.8 2.05)
			(stroke
				(width 0.15)
				(type solid)
			)
			(layer "F.SilkS")
		)
		(fp_line
			(start 1.6 2.05)
			(end 1.8 2.05)
			(stroke
				(width 0.15)
				(type solid)
			)
			(layer "F.SilkS")
		)
		(fp_line
			(start 1.6 -2)
			(end 1.8 -2)
			(stroke
				(width 0.15)
				(type solid)
			)
			(layer "F.SilkS")
		)
		(fp_line
			(start 0.9 -2.301)
			(end 0.598 -2.301)
			(stroke
				(width 0.15)
				(type solid)
			)
			(layer "F.SilkS")
		)
		(fp_line
			(start 0.748 -2.452)
			(end 0.748 -2.15)
			(stroke
				(width 0.15)
				(type solid)
			)
			(layer "F.SilkS")
		)
		(fp_line
			(start -0.902 -2.25)
			(end -0.6 -2.25)
			(stroke
				(width 0.15)
				(type solid)
			)
			(layer "F.SilkS")
		)
		(fp_line
			(start -0.95 2.05)
			(end 0.95 2.05)
			(stroke
				(width 0.15)
				(type solid)
			)
			(layer "F.SilkS")
		)
		(fp_line
			(start -0.95 -2)
			(end 0.95 -2)
			(stroke
				(width 0.15)
				(type solid)
			)
			(layer "F.SilkS")
		)
		(fp_line
			(start -1.8 2.05)
			(end -1.6 2.05)
			(stroke
				(width 0.15)
				(type solid)
			)
			(layer "F.SilkS")
		)
		(fp_line
			(start -1.8 -1.5)
			(end -1.8 2.05)
			(stroke
				(width 0.15)
				(type solid)
			)
			(layer "F.SilkS")
		)
		(fp_rect
			(start -2.1 -2.6)
			(end 2.1 2.6)
			(stroke
				(width 0.05)
				(type solid)
			)
			(fill no)
			(layer "F.CrtYd")
		)
		(fp_line
			(start -1.051 -2)
			(end -1.801 -1.25)
			(stroke
				(width 0.15)
				(type solid)
			)
			(layer "F.Fab")
		)
		(fp_rect
			(start 1.8 2.048)
			(end -1.8 -2)
			(stroke
				(width 0.15)
				(type solid)
			)
			(fill no)
			(layer "F.Fab")
		)
		(fp_text user "~"
			(at -0.31 2.59 180)
			(unlocked yes)
			(layer "F.SilkS")
			(effects
				(font
					(size 0.7 0.7)
					(thickness 0.15)
				)
				(justify left bottom)
			)
		)
		(pad "1" smd roundrect
			(at -1.27 -1.85 270)
			(size 1.4 0.48)
			(layers "F.Cu" "F.Mask" "F.Paste")
			(roundrect_rratio 0.25)
			(net 762 "Net-(D6-Pad1)")
			(pinfunction "1")
			(pintype "output")
		)
		(pad "2" smd roundrect
			(at 1.27 -1.85 270)
			(size 1.4 0.48)
			(layers "F.Cu" "F.Mask" "F.Paste")
			(roundrect_rratio 0.25)
			(net 763 "Net-(D6-Pad2)")
			(pinfunction "2")
			(pintype "output")
		)
		(pad "3" smd roundrect
			(at -1.27 1.85 270)
			(size 1.4 0.48)
			(layers "F.Cu" "F.Mask" "F.Paste")
			(roundrect_rratio 0.25)
			(net 766 "/HDMI + Ethernet/POE_ETH.VC3")
			(pinfunction "3")
			(pintype "input")
		)
		(pad "4" smd roundrect
			(at 1.27 1.85 270)
			(size 1.4 0.48)
			(layers "F.Cu" "F.Mask" "F.Paste")
			(roundrect_rratio 0.25)
			(net 767 "/HDMI + Ethernet/POE_ETH.VC4")
			(pinfunction "4")
			(pintype "input")
		)
	)
	(footprint "antmicro-footprints:LED_0603_1608Metric_G"
		(layer "F.Cu")
		(at 261.5 95.8)
		(descr "LED SMD 0603 Green")
		(tags "LED SMD 0603 Green")
		(property "Reference" "D23"
			(at -1 1.55 0)
			(layer "F.SilkS")
			(effects
				(font
					(size 0.7 0.7)
					(thickness 0.15)
				)
				(justify left bottom)
			)
		)
		(property "Value" "LED_G_0603_KP-1608CGCK"
			(at 0 1.6 0)
			(layer "F.Fab")
			(effects
				(font
					(size 0.7 0.7)
					(thickness 0.15)
				)
				(justify left bottom)
			)
		)
		(property "Description" "LED, Green, SMD, 0603, 20 mA, 2.1 V, 570 nm"
			(at 0 0 0)
			(layer "F.Fab")
			(hide yes)
			(effects
				(font
					(size 1.27 1.27)
					(thickness 0.15)
				)
			)
		)
		(property "Author" "Antmicro"
			(at 0 0 0)
			(layer "F.Fab")
			(hide yes)
			(effects
				(font
					(size 1 1)
					(thickness 0.15)
				)
			)
		)
		(property "Color" "Green"
			(at 0 0 0)
			(layer "F.Fab")
			(hide yes)
			(effects
				(font
					(size 1 1)
					(thickness 0.15)
				)
			)
		)
		(property "License" "Apache-2.0"
			(at 0 0 0)
			(layer "F.Fab")
			(hide yes)
			(effects
				(font
					(size 1 1)
					(thickness 0.15)
				)
			)
		)
		(property "MPN" "KP-1608CGCK"
			(at 0 0 0)
			(layer "F.Fab")
			(hide yes)
			(effects
				(font
					(size 1 1)
					(thickness 0.15)
				)
			)
		)
		(property "Manufacturer" "Kingbright"
			(at 0 0 0)
			(layer "F.Fab")
			(hide yes)
			(effects
				(font
					(size 1 1)
					(thickness 0.15)
				)
			)
		)
		(sheetname "User GPIO + LED + button + DIP switch")
		(sheetfile "user-gpio.kicad_sch")
		(attr smd)
		(fp_line
			(start -1.18 -0.319)
			(end -1.18 0.321)
			(stroke
				(width 0.15)
				(type solid)
			)
			(layer "F.SilkS")
		)
		(fp_line
			(start -0.094672 0.001008)
			(end -0.24 0.001008)
			(stroke
				(width 0.1)
				(type solid)
			)
			(layer "F.SilkS")
		)
		(fp_line
			(start -0.094672 0.001008)
			(end 0.105328 -0.198992)
			(stroke
				(width 0.1)
				(type solid)
			)
			(layer "F.SilkS")
		)
		(fp_line
			(start -0.094672 0.201008)
			(end -0.094672 -0.198992)
			(stroke
				(width 0.1)
				(type solid)
			)
			(layer "F.SilkS")
		)
		(fp_line
			(start 0.105328 0.001008)
			(end 0.24 0.001)
			(stroke
				(width 0.1)
				(type solid)
			)
			(layer "F.SilkS")
		)
		(fp_line
			(start 0.105328 0.201008)
			(end -0.094672 0.001008)
			(stroke
				(width 0.1)
				(type solid)
			)
			(layer "F.SilkS")
		)
		(fp_line
			(start 0.105328 0.201008)
			(end 0.105328 -0.198992)
			(stroke
				(width 0.1)
				(type solid)
			)
			(layer "F.SilkS")
		)
		(fp_line
			(start 0.22 -0.35)
			(end -0.22 -0.35)
			(stroke
				(width 0.15)
				(type solid)
			)
			(layer "F.SilkS")
		)
		(fp_line
			(start 0.22 0.35)
			(end -0.22 0.35)
			(stroke
				(width 0.15)
				(type solid)
			)
			(layer "F.SilkS")
		)
		(fp_rect
			(start 1.25 0.65)
			(end -1.25 -0.65)
			(stroke
				(width 0.05)
				(type solid)
			)
			(fill no)
			(layer "F.CrtYd")
		)
		(fp_line
			(start -0.199 -0.202)
			(end -0.199 0.1)
			(stroke
				(width 0.15)
				(type solid)
			)
			(layer "F.Fab")
		)
		(fp_line
			(start -0.199 0)
			(end -0.597 0)
			(stroke
				(width 0.15)
				(type solid)
			)
			(layer "F.Fab")
		)
		(fp_line
			(start -0.199 0.2)
			(end -0.199 0.1)
			(stroke
				(width 0.15)
				(type solid)
			)
			(layer "F.Fab")
		)
		(fp_line
			(start -0.101 0)
			(end 0.201 0.2)
			(stroke
				(width 0.15)
				(type solid)
			)
			(layer "F.Fab")
		)
		(fp_line
			(start 0.201 -0.202)
			(end -0.101 0)
			(stroke
				(width 0.15)
				(type solid)
			)
			(layer "F.Fab")
		)
		(fp_line
			(start 0.201 0)
			(end 0.201 -0.202)
			(stroke
				(width 0.15)
				(type solid)
			)
			(layer "F.Fab")
		)
		(fp_line
			(start 0.201 0.2)
			(end 0.201 0)
			(stroke
				(width 0.15)
				(type solid)
			)
			(layer "F.Fab")
		)
		(fp_line
			(start 0.599 0)
			(end 0.201 0)
			(stroke
				(width 0.15)
				(type solid)
			)
			(layer "F.Fab")
		)
		(fp_rect
			(start 0.848 0.4)
			(end -0.85 -0.402)
			(stroke
				(width 0.15)
				(type solid)
			)
			(fill no)
			(layer "F.Fab")
		)
		(pad "1" smd roundrect
			(at -0.7 0 180)
			(size 0.8 1)
			(layers "F.Cu" "F.Mask" "F.Paste")
			(roundrect_rratio 0.2)
			(net 768 "Net-(D23-C)")
			(pinfunction "C")
			(pintype "passive")
		)
		(pad "2" smd roundrect
			(at 0.7 0 180)
			(size 0.8 1)
			(layers "F.Cu" "F.Mask" "F.Paste")
			(roundrect_rratio 0.2)
			(net 785 "Net-(D23-A)")
			(pinfunction "A")
			(pintype "passive")
		)
	)
	(footprint "antmicro-footprints:C_0402_1005Metric"
		(layer "F.Cu")
		(at 253.545 140.135 90)
		(descr "Capacitor SMD 0402")
		(tags "capacitor SMD 0402")
		(property "Reference" "C238"
			(at -1.515 1.255 90)
			(layer "F.SilkS")
			(effects
				(font
					(size 0.7 0.7)
					(thickness 0.15)
				)
				(justify left bottom)
			)
		)
		(property "Value" "C_100n_0402"
			(at 0 1.169 90)
			(layer "F.Fab")
			(effects
				(font
					(size 0.7 0.7)
					(thickness 0.15)
				)
				(justify left bottom)
			)
		)
		(property "Description" "SMD Multilayer Ceramic Capacitor, 0.1 µF, 50 V, 0402 [1005 Metric], ± 10%, X5R, GRM Series"
			(at 0 0 90)
			(layer "F.Fab")
			(hide yes)
			(effects
				(font
					(size 1.27 1.27)
					(thickness 0.15)
				)
			)
		)
		(property "Author" "Antmicro"
			(at 393.68 -113.41 0)
			(layer "F.Fab")
			(hide yes)
			(effects
				(font
					(size 1 1)
					(thickness 0.15)
				)
			)
		)
		(property "Dielectric" "X5R"
			(at 393.68 -113.41 0)
			(layer "F.Fab")
			(hide yes)
			(effects
				(font
					(size 1 1)
					(thickness 0.15)
				)
			)
		)
		(property "License" "Apache-2.0"
			(at 393.68 -113.41 0)
			(layer "F.Fab")
			(hide yes)
			(effects
				(font
					(size 1 1)
					(thickness 0.15)
				)
			)
		)
		(property "MPN" "GRM155R61H104KE14D"
			(at 393.68 -113.41 0)
			(layer "F.Fab")
			(hide yes)
			(effects
				(font
					(size 1 1)
					(thickness 0.15)
				)
			)
		)
		(property "Manufacturer" "Murata"
			(at 393.68 -113.41 0)
			(layer "F.Fab")
			(hide yes)
			(effects
				(font
					(size 1 1)
					(thickness 0.15)
				)
			)
		)
		(property "Val" "100n"
			(at 393.68 -113.41 0)
			(layer "F.Fab")
			(hide yes)
			(effects
				(font
					(size 1 1)
					(thickness 0.15)
				)
			)
		)
		(property "Voltage" "50V"
			(at 393.68 -113.41 0)
			(layer "F.Fab")
			(hide yes)
			(effects
				(font
					(size 1 1)
					(thickness 0.15)
				)
			)
		)
		(sheetname "USB PHY")
		(sheetfile "usb-phy.kicad_sch")
		(attr smd)
		(fp_rect
			(start -0.925 -0.47)
			(end 0.925 0.47)
			(stroke
				(width 0.05)
				(type default)
			)
			(fill no)
			(layer "F.CrtYd")
		)
		(fp_line
			(start 0.504 -0.25)
			(end 0.504 0.248)
			(stroke
				(width 0.15)
				(type solid)
			)
			(layer "F.Fab")
		)
		(fp_line
			(start -0.494 -0.25)
			(end 0.504 -0.25)
			(stroke
				(width 0.15)
				(type solid)
			)
			(layer "F.Fab")
		)
		(fp_line
			(start 0.504 0.248)
			(end -0.494 0.248)
			(stroke
				(width 0.15)
				(type solid)
			)
			(layer "F.Fab")
		)
		(fp_line
			(start -0.494 0.248)
			(end -0.494 -0.25)
			(stroke
				(width 0.15)
				(type solid)
			)
			(layer "F.Fab")
		)
		(pad "1" smd roundrect
			(at -0.48 0 90)
			(size 0.59 0.64)
			(layers "F.Cu" "F.Mask" "F.Paste")
			(roundrect_rratio 0.25)
			(net 1 "GND")
			(pintype "passive")
		)
		(pad "2" smd roundrect
			(at 0.48 0 90)
			(size 0.59 0.64)
			(layers "F.Cu" "F.Mask" "F.Paste")
			(roundrect_rratio 0.25)
			(net 712 "/USB PHY/FTDI_VCORE")
			(pintype "passive")
		)
	)
	(footprint "antmicro-footprints:DFN3538"
		(layer "F.Cu")
		(at 233 174.5 180)
		(property "Reference" "D5"
			(at 0.7 -3.3 0)
			(unlocked yes)
			(layer "F.SilkS")
			(effects
				(font
					(size 0.7 0.7)
					(thickness 0.15)
				)
				(justify left bottom)
			)
		)
		(property "Value" "CD-MMBL110S"
			(at 0 3.5 180)
			(unlocked yes)
			(layer "F.Fab")
			(effects
				(font
					(size 0.7 0.7)
					(thickness 0.15)
				)
				(justify left bottom)
			)
		)
		(property "Description" "TVS diode"
			(at 0 0 180)
			(layer "F.Fab")
			(hide yes)
			(effects
				(font
					(size 1.27 1.27)
					(thickness 0.15)
				)
			)
		)
		(property "Author" "Antmicro"
			(at 466 349 0)
			(layer "F.Fab")
			(hide yes)
			(effects
				(font
					(size 1 1)
					(thickness 0.15)
				)
			)
		)
		(property "License" "Apache-2.0"
			(at 466 349 0)
			(layer "F.Fab")
			(hide yes)
			(effects
				(font
					(size 1 1)
					(thickness 0.15)
				)
			)
		)
		(property "MPN" "CD-MMBL110S"
			(at 466 349 0)
			(layer "F.Fab")
			(hide yes)
			(effects
				(font
					(size 1 1)
					(thickness 0.15)
				)
			)
		)
		(property "Manufacturer" "Bourns"
			(at 466 349 0)
			(layer "F.Fab")
			(hide yes)
			(effects
				(font
					(size 1 1)
					(thickness 0.15)
				)
			)
		)
		(sheetname "Power supply")
		(sheetfile "power-supply.kicad_sch")
		(attr smd)
		(fp_line
			(start 1.8 -2)
			(end 1.8 2.05)
			(stroke
				(width 0.15)
				(type solid)
			)
			(layer "F.SilkS")
		)
		(fp_line
			(start 1.6 2.05)
			(end 1.8 2.05)
			(stroke
				(width 0.15)
				(type solid)
			)
			(layer "F.SilkS")
		)
		(fp_line
			(start 1.6 -2)
			(end 1.8 -2)
			(stroke
				(width 0.15)
				(type solid)
			)
			(layer "F.SilkS")
		)
		(fp_line
			(start 0.9 -2.301)
			(end 0.598 -2.301)
			(stroke
				(width 0.15)
				(type solid)
			)
			(layer "F.SilkS")
		)
		(fp_line
			(start 0.748 -2.452)
			(end 0.748 -2.15)
			(stroke
				(width 0.15)
				(type solid)
			)
			(layer "F.SilkS")
		)
		(fp_line
			(start -0.902 -2.25)
			(end -0.6 -2.25)
			(stroke
				(width 0.15)
				(type solid)
			)
			(layer "F.SilkS")
		)
		(fp_line
			(start -0.95 2.05)
			(end 0.95 2.05)
			(stroke
				(width 0.15)
				(type solid)
			)
			(layer "F.SilkS")
		)
		(fp_line
			(start -0.95 -2)
			(end 0.95 -2)
			(stroke
				(width 0.15)
				(type solid)
			)
			(layer "F.SilkS")
		)
		(fp_line
			(start -1.8 2.05)
			(end -1.6 2.05)
			(stroke
				(width 0.15)
				(type solid)
			)
			(layer "F.SilkS")
		)
		(fp_line
			(start -1.8 -1.5)
			(end -1.8 2.05)
			(stroke
				(width 0.15)
				(type solid)
			)
			(layer "F.SilkS")
		)
		(fp_rect
			(start -2.1 -2.6)
			(end 2.1 2.6)
			(stroke
				(width 0.05)
				(type solid)
			)
			(fill no)
			(layer "F.CrtYd")
		)
		(fp_line
			(start -1.051 -2)
			(end -1.801 -1.25)
			(stroke
				(width 0.15)
				(type solid)
			)
			(layer "F.Fab")
		)
		(fp_rect
			(start 1.8 2.048)
			(end -1.8 -2)
			(stroke
				(width 0.15)
				(type solid)
			)
			(fill no)
			(layer "F.Fab")
		)
		(fp_text user "~"
			(at -0.31 2.59 180)
			(unlocked yes)
			(layer "F.SilkS")
			(effects
				(font
					(size 0.7 0.7)
					(thickness 0.15)
				)
				(justify left bottom)
			)
		)
		(pad "1" smd roundrect
			(at -1.27 -1.85 270)
			(size 1.4 0.48)
			(layers "F.Cu" "F.Mask" "F.Paste")
			(roundrect_rratio 0.25)
			(net 756 "Net-(D4-Pad1)")
			(pinfunction "1")
			(pintype "output")
		)
		(pad "2" smd roundrect
			(at 1.27 -1.85 270)
			(size 1.4 0.48)
			(layers "F.Cu" "F.Mask" "F.Paste")
			(roundrect_rratio 0.25)
			(net 757 "Net-(D4-Pad2)")
			(pinfunction "2")
			(pintype "output")
		)
		(pad "3" smd roundrect
			(at -1.27 1.85 270)
			(size 1.4 0.48)
			(layers "F.Cu" "F.Mask" "F.Paste")
			(roundrect_rratio 0.25)
			(net 760 "/HDMI + Ethernet/POE_GBE.VC3")
			(pinfunction "3")
			(pintype "input")
		)
		(pad "4" smd roundrect
			(at 1.27 1.85 270)
			(size 1.4 0.48)
			(layers "F.Cu" "F.Mask" "F.Paste")
			(roundrect_rratio 0.25)
			(net 761 "/HDMI + Ethernet/POE_GBE.VC4")
			(pinfunction "4")
			(pintype "input")
		)
	)
	(footprint "antmicro-footprints:LED_0603_1608Metric_G"
		(layer "F.Cu")
		(at 266.6 137.8 180)
		(descr "LED SMD 0603 Green")
		(tags "LED SMD 0603 Green")
		(property "Reference" "D27"
			(at -3.4 0.75 0)
			(layer "F.SilkS")
			(effects
				(font
					(size 0.7 0.7)
					(thickness 0.15)
				)
				(justify right bottom)
			)
		)
		(property "Value" "LED_G_0603_KP-1608CGCK"
			(at 0 1.6 0)
			(layer "F.Fab")
			(effects
				(font
					(size 0.7 0.7)
					(thickness 0.15)
				)
				(justify right bottom)
			)
		)
		(property "Description" "LED, Green, SMD, 0603, 20 mA, 2.1 V, 570 nm"
			(at 0 0 180)
			(layer "F.Fab")
			(hide yes)
			(effects
				(font
					(size 1.27 1.27)
					(thickness 0.15)
				)
			)
		)
		(property "Author" "Antmicro"
			(at 533.2 275.6 0)
			(layer "F.Fab")
			(hide yes)
			(effects
				(font
					(size 1 1)
					(thickness 0.15)
				)
			)
		)
		(property "Color" "Green"
			(at 533.2 275.6 0)
			(layer "F.Fab")
			(hide yes)
			(effects
				(font
					(size 1 1)
					(thickness 0.15)
				)
			)
		)
		(property "License" "Apache-2.0"
			(at 533.2 275.6 0)
			(layer "F.Fab")
			(hide yes)
			(effects
				(font
					(size 1 1)
					(thickness 0.15)
				)
			)
		)
		(property "MPN" "KP-1608CGCK"
			(at 533.2 275.6 0)
			(layer "F.Fab")
			(hide yes)
			(effects
				(font
					(size 1 1)
					(thickness 0.15)
				)
			)
		)
		(property "Manufacturer" "Kingbright"
			(at 533.2 275.6 0)
			(layer "F.Fab")
			(hide yes)
			(effects
				(font
					(size 1 1)
					(thickness 0.15)
				)
			)
		)
		(sheetname "USB PHY")
		(sheetfile "usb-phy.kicad_sch")
		(attr smd)
		(fp_line
			(start 0.22 0.35)
			(end -0.22 0.35)
			(stroke
				(width 0.15)
				(type solid)
			)
			(layer "F.SilkS")
		)
		(fp_line
			(start 0.22 -0.35)
			(end -0.22 -0.35)
			(stroke
				(width 0.15)
				(type solid)
			)
			(layer "F.SilkS")
		)
		(fp_line
			(start 0.105328 0.201008)
			(end 0.105328 -0.198992)
			(stroke
				(width 0.1)
				(type solid)
			)
			(layer "F.SilkS")
		)
		(fp_line
			(start 0.105328 0.201008)
			(end -0.094672 0.001008)
			(stroke
				(width 0.1)
				(type solid)
			)
			(layer "F.SilkS")
		)
		(fp_line
			(start 0.105328 0.001008)
			(end 0.24 0.001)
			(stroke
				(width 0.1)
				(type solid)
			)
			(layer "F.SilkS")
		)
		(fp_line
			(start -0.094672 0.201008)
			(end -0.094672 -0.198992)
			(stroke
				(width 0.1)
				(type solid)
			)
			(layer "F.SilkS")
		)
		(fp_line
			(start -0.094672 0.001008)
			(end 0.105328 -0.198992)
			(stroke
				(width 0.1)
				(type solid)
			)
			(layer "F.SilkS")
		)
		(fp_line
			(start -0.094672 0.001008)
			(end -0.24 0.001008)
			(stroke
				(width 0.1)
				(type solid)
			)
			(layer "F.SilkS")
		)
		(fp_line
			(start -1.18 -0.319)
			(end -1.18 0.321)
			(stroke
				(width 0.15)
				(type solid)
			)
			(layer "F.SilkS")
		)
		(fp_rect
			(start 1.25 0.65)
			(end -1.25 -0.65)
			(stroke
				(width 0.05)
				(type solid)
			)
			(fill no)
			(layer "F.CrtYd")
		)
		(fp_line
			(start 0.599 0)
			(end 0.201 0)
			(stroke
				(width 0.15)
				(type solid)
			)
			(layer "F.Fab")
		)
		(fp_line
			(start 0.201 0.2)
			(end 0.201 0)
			(stroke
				(width 0.15)
				(type solid)
			)
			(layer "F.Fab")
		)
		(fp_line
			(start 0.201 0)
			(end 0.201 -0.202)
			(stroke
				(width 0.15)
				(type solid)
			)
			(layer "F.Fab")
		)
		(fp_line
			(start 0.201 -0.202)
			(end -0.101 0)
			(stroke
				(width 0.15)
				(type solid)
			)
			(layer "F.Fab")
		)
		(fp_line
			(start -0.101 0)
			(end 0.201 0.2)
			(stroke
				(width 0.15)
				(type solid)
			)
			(layer "F.Fab")
		)
		(fp_line
			(start -0.199 0.2)
			(end -0.199 0.1)
			(stroke
				(width 0.15)
				(type solid)
			)
			(layer "F.Fab")
		)
		(fp_line
			(start -0.199 0)
			(end -0.597 0)
			(stroke
				(width 0.15)
				(type solid)
			)
			(layer "F.Fab")
		)
		(fp_line
			(start -0.199 -0.202)
			(end -0.199 0.1)
			(stroke
				(width 0.15)
				(type solid)
			)
			(layer "F.Fab")
		)
		(fp_rect
			(start 0.848 0.4)
			(end -0.85 -0.402)
			(stroke
				(width 0.15)
				(type solid)
			)
			(fill no)
			(layer "F.Fab")
		)
		(pad "1" smd roundrect
			(at -0.7 0)
			(size 0.8 1)
			(layers "F.Cu" "F.Mask" "F.Paste")
			(roundrect_rratio 0.2)
			(net 1 "GND")
			(pinfunction "C")
			(pintype "passive")
		)
		(pad "2" smd roundrect
			(at 0.7 0)
			(size 0.8 1)
			(layers "F.Cu" "F.Mask" "F.Paste")
			(roundrect_rratio 0.2)
			(net 791 "Net-(D27-A)")
			(pinfunction "A")
			(pintype "passive")
		)
	)
	(footprint "antmicro-footprints:C_0402_1005Metric"
		(layer "F.Cu")
		(at 151.975 156.225)
		(descr "Capacitor SMD 0402")
		(tags "capacitor SMD 0402")
		(property "Reference" "C349"
			(at -1.625 1.225 0)
			(layer "F.SilkS")
			(effects
				(font
					(size 0.7 0.7)
					(thickness 0.15)
				)
				(justify left bottom)
			)
		)
		(property "Value" "C_10u_0402"
			(at 0 1.4 0)
			(layer "F.Fab")
			(effects
				(font
					(size 0.7 0.7)
					(thickness 0.15)
				)
				(justify left bottom)
			)
		)
		(property "Description" "SMD Multilayer Ceramic Capacitor, 10 µF, 6.3 V, 0402 [1005 Metric], ± 20%, X5R, CC Series"
			(at 0 0 0)
			(layer "F.Fab")
			(hide yes)
			(effects
				(font
					(size 1.27 1.27)
					(thickness 0.15)
				)
			)
		)
		(property "Author" "Antmicro"
			(at 0 0 0)
			(layer "F.Fab")
			(hide yes)
			(effects
				(font
					(size 1 1)
					(thickness 0.15)
				)
			)
		)
		(property "Dielectric" ""
			(at 0 0 0)
			(layer "F.Fab")
			(hide yes)
			(effects
				(font
					(size 1 1)
					(thickness 0.15)
				)
			)
		)
		(property "License" "Apache-2.0"
			(at 0 0 0)
			(layer "F.Fab")
			(hide yes)
			(effects
				(font
					(size 1 1)
					(thickness 0.15)
				)
			)
		)
		(property "MPN" "CC0402MRX5R5BB106"
			(at 0 0 0)
			(layer "F.Fab")
			(hide yes)
			(effects
				(font
					(size 1 1)
					(thickness 0.15)
				)
			)
		)
		(property "Manufacturer" "YAGEO"
			(at 0 0 0)
			(layer "F.Fab")
			(hide yes)
			(effects
				(font
					(size 1 1)
					(thickness 0.15)
				)
			)
		)
		(property "Val" "10u"
			(at 0 0 0)
			(layer "F.Fab")
			(hide yes)
			(effects
				(font
					(size 1 1)
					(thickness 0.15)
				)
			)
		)
		(property "Voltage" ""
			(at 0 0 0)
			(layer "F.Fab")
			(hide yes)
			(effects
				(font
					(size 1 1)
					(thickness 0.15)
				)
			)
		)
		(sheetname "DC-DC Converters")
		(sheetfile "dc-dc.kicad_sch")
		(attr smd)
		(fp_rect
			(start -0.925 -0.47)
			(end 0.925 0.47)
			(stroke
				(width 0.05)
				(type default)
			)
			(fill no)
			(layer "F.CrtYd")
		)
		(fp_line
			(start -0.494 -0.25)
			(end 0.504 -0.25)
			(stroke
				(width 0.15)
				(type solid)
			)
			(layer "F.Fab")
		)
		(fp_line
			(start -0.494 0.248)
			(end -0.494 -0.25)
			(stroke
				(width 0.15)
				(type solid)
			)
			(layer "F.Fab")
		)
		(fp_line
			(start 0.504 -0.25)
			(end 0.504 0.248)
			(stroke
				(width 0.15)
				(type solid)
			)
			(layer "F.Fab")
		)
		(fp_line
			(start 0.504 0.248)
			(end -0.494 0.248)
			(stroke
				(width 0.15)
				(type solid)
			)
			(layer "F.Fab")
		)
		(pad "1" smd roundrect
			(at -0.48 0)
			(size 0.59 0.64)
			(layers "F.Cu" "F.Mask" "F.Paste")
			(roundrect_rratio 0.25)
			(net 1 "GND")
			(pintype "passive")
		)
		(pad "2" smd roundrect
			(at 0.48 0)
			(size 0.59 0.64)
			(layers "F.Cu" "F.Mask" "F.Paste")
			(roundrect_rratio 0.25)
			(net 24 "+3V3")
			(pintype "passive")
		)
	)
	(footprint "antmicro-footprints:R_0402_1005Metric"
		(layer "F.Cu")
		(at 238.8 127.8 90)
		(descr "Resistor SMD 0402")
		(tags "resistor SMD 0402")
		(property "Reference" "R175"
			(at 0.75 0.375 90)
			(layer "F.SilkS")
			(effects
				(font
					(size 0.7 0.7)
					(thickness 0.15)
				)
				(justify left bottom)
			)
		)
		(property "Value" "R_47k_0402"
			(at 0 1.4 90)
			(layer "F.Fab")
			(effects
				(font
					(size 0.7 0.7)
					(thickness 0.15)
				)
				(justify left bottom)
			)
		)
		(property "Description" "SMD Chip Resistor, 47 kohm, ± 1%, 62.5 mW, 0402 [1005 Metric], Thick Film, General Purpose"
			(at 0 0 90)
			(layer "F.Fab")
			(hide yes)
			(effects
				(font
					(size 1.27 1.27)
					(thickness 0.15)
				)
			)
		)
		(property "Author" "Antmicro"
			(at 366.6 -111 0)
			(layer "F.Fab")
			(hide yes)
			(effects
				(font
					(size 1 1)
					(thickness 0.15)
				)
			)
		)
		(property "License" "Apache-2.0"
			(at 366.6 -111 0)
			(layer "F.Fab")
			(hide yes)
			(effects
				(font
					(size 1 1)
					(thickness 0.15)
				)
			)
		)
		(property "MPN" "CR0402-FX-4702GLF"
			(at 366.6 -111 0)
			(layer "F.Fab")
			(hide yes)
			(effects
				(font
					(size 1 1)
					(thickness 0.15)
				)
			)
		)
		(property "Manufacturer" "Bourns"
			(at 366.6 -111 0)
			(layer "F.Fab")
			(hide yes)
			(effects
				(font
					(size 1 1)
					(thickness 0.15)
				)
			)
		)
		(property "Tolerance" "1%"
			(at 366.6 -111 0)
			(layer "F.Fab")
			(hide yes)
			(effects
				(font
					(size 1 1)
					(thickness 0.15)
				)
			)
		)
		(property "Val" "47k"
			(at 366.6 -111 0)
			(layer "F.Fab")
			(hide yes)
			(effects
				(font
					(size 1 1)
					(thickness 0.15)
				)
			)
		)
		(sheetname "USB PHY")
		(sheetfile "usb-phy.kicad_sch")
		(attr smd)
		(fp_rect
			(start -0.925 -0.47)
			(end 0.925 0.47)
			(stroke
				(width 0.05)
				(type default)
			)
			(fill no)
			(layer "F.CrtYd")
		)
		(fp_rect
			(start -0.5 -0.25)
			(end 0.5 0.25)
			(stroke
				(width 0.15)
				(type solid)
			)
			(fill no)
			(layer "F.Fab")
		)
		(pad "1" smd roundrect
			(at -0.48 0 90)
			(size 0.59 0.64)
			(layers "F.Cu" "F.Mask" "F.Paste")
			(roundrect_rratio 0.25)
			(net 799 "FTDI_DIS")
			(pintype "passive")
		)
		(pad "2" smd roundrect
			(at 0.48 0 90)
			(size 0.59 0.64)
			(layers "F.Cu" "F.Mask" "F.Paste")
			(roundrect_rratio 0.25)
			(net 24 "+3V3")
			(pintype "passive")
		)
	)
	(footprint "antmicro-footprints:C_0402_1005Metric"
		(layer "F.Cu")
		(at 256.345 133.735 180)
		(descr "Capacitor SMD 0402")
		(tags "capacitor SMD 0402")
		(property "Reference" "C229"
			(at -2.205 3.835 0)
			(layer "F.SilkS")
			(effects
				(font
					(size 0.7 0.7)
					(thickness 0.15)
				)
				(justify right bottom)
			)
		)
		(property "Value" "C_10u_0402"
			(at 0 1.4 0)
			(layer "F.Fab")
			(effects
				(font
					(size 0.7 0.7)
					(thickness 0.15)
				)
				(justify right bottom)
			)
		)
		(property "Description" "SMD Multilayer Ceramic Capacitor, 10 µF, 6.3 V, 0402 [1005 Metric], ± 20%, X5R, CC Series"
			(at 0 0 180)
			(layer "F.Fab")
			(hide yes)
			(effects
				(font
					(size 1.27 1.27)
					(thickness 0.15)
				)
			)
		)
		(property "Author" "Antmicro"
			(at 512.69 267.47 0)
			(layer "F.Fab")
			(hide yes)
			(effects
				(font
					(size 1 1)
					(thickness 0.15)
				)
			)
		)
		(property "Dielectric" ""
			(at 512.69 267.47 0)
			(layer "F.Fab")
			(hide yes)
			(effects
				(font
					(size 1 1)
					(thickness 0.15)
				)
			)
		)
		(property "License" "Apache-2.0"
			(at 512.69 267.47 0)
			(layer "F.Fab")
			(hide yes)
			(effects
				(font
					(size 1 1)
					(thickness 0.15)
				)
			)
		)
		(property "MPN" "CC0402MRX5R5BB106"
			(at 512.69 267.47 0)
			(layer "F.Fab")
			(hide yes)
			(effects
				(font
					(size 1 1)
					(thickness 0.15)
				)
			)
		)
		(property "Manufacturer" "YAGEO"
			(at 512.69 267.47 0)
			(layer "F.Fab")
			(hide yes)
			(effects
				(font
					(size 1 1)
					(thickness 0.15)
				)
			)
		)
		(property "Val" "10u"
			(at 512.69 267.47 0)
			(layer "F.Fab")
			(hide yes)
			(effects
				(font
					(size 1 1)
					(thickness 0.15)
				)
			)
		)
		(property "Voltage" ""
			(at 512.69 267.47 0)
			(layer "F.Fab")
			(hide yes)
			(effects
				(font
					(size 1 1)
					(thickness 0.15)
				)
			)
		)
		(sheetname "USB PHY")
		(sheetfile "usb-phy.kicad_sch")
		(attr smd)
		(fp_rect
			(start -0.925 -0.47)
			(end 0.925 0.47)
			(stroke
				(width 0.05)
				(type default)
			)
			(fill no)
			(layer "F.CrtYd")
		)
		(fp_line
			(start 0.504 0.248)
			(end -0.494 0.248)
			(stroke
				(width 0.15)
				(type solid)
			)
			(layer "F.Fab")
		)
		(fp_line
			(start 0.504 -0.25)
			(end 0.504 0.248)
			(stroke
				(width 0.15)
				(type solid)
			)
			(layer "F.Fab")
		)
		(fp_line
			(start -0.494 0.248)
			(end -0.494 -0.25)
			(stroke
				(width 0.15)
				(type solid)
			)
			(layer "F.Fab")
		)
		(fp_line
			(start -0.494 -0.25)
			(end 0.504 -0.25)
			(stroke
				(width 0.15)
				(type solid)
			)
			(layer "F.Fab")
		)
		(pad "1" smd roundrect
			(at -0.48 0 180)
			(size 0.59 0.64)
			(layers "F.Cu" "F.Mask" "F.Paste")
			(roundrect_rratio 0.25)
			(net 1 "GND")
			(pintype "passive")
		)
		(pad "2" smd roundrect
			(at 0.48 0 180)
			(size 0.59 0.64)
			(layers "F.Cu" "F.Mask" "F.Paste")
			(roundrect_rratio 0.25)
			(net 711 "/USB PHY/FTDI_VPLL")
			(pintype "passive")
		)
	)
	(footprint "antmicro-footprints:R_0402_1005Metric"
		(layer "F.Cu")
		(at 264.7 139.5 90)
		(descr "Resistor SMD 0402")
		(tags "resistor SMD 0402")
		(property "Reference" "R150"
			(at 33.25 -29.85 180)
			(layer "F.SilkS")
			(effects
				(font
					(size 0.7 0.7)
					(thickness 0.15)
				)
				(justify left bottom)
			)
		)
		(property "Value" "R_330R_0402"
			(at 0 1.4 90)
			(layer "F.Fab")
			(effects
				(font
					(size 0.7 0.7)
					(thickness 0.15)
				)
				(justify left bottom)
			)
		)
		(property "Description" "SMD Chip Resistor, 330 ohm, ± 1%, 62.5 mW, 0402 [1005 Metric], Thick Film, General Purpose"
			(at 0 0 90)
			(layer "F.Fab")
			(hide yes)
			(effects
				(font
					(size 1.27 1.27)
					(thickness 0.15)
				)
			)
		)
		(property "Author" "Antmicro"
			(at 404.2 -125.2 0)
			(layer "F.Fab")
			(hide yes)
			(effects
				(font
					(size 1 1)
					(thickness 0.15)
				)
			)
		)
		(property "License" "Apache-2.0"
			(at 404.2 -125.2 0)
			(layer "F.Fab")
			(hide yes)
			(effects
				(font
					(size 1 1)
					(thickness 0.15)
				)
			)
		)
		(property "MPN" "CR0402-FX-3300GLF"
			(at 404.2 -125.2 0)
			(layer "F.Fab")
			(hide yes)
			(effects
				(font
					(size 1 1)
					(thickness 0.15)
				)
			)
		)
		(property "Manufacturer" "Bourns"
			(at 404.2 -125.2 0)
			(layer "F.Fab")
			(hide yes)
			(effects
				(font
					(size 1 1)
					(thickness 0.15)
				)
			)
		)
		(property "Tolerance" "1%"
			(at 404.2 -125.2 0)
			(layer "F.Fab")
			(hide yes)
			(effects
				(font
					(size 1 1)
					(thickness 0.15)
				)
			)
		)
		(property "Val" "330R"
			(at 404.2 -125.2 0)
			(layer "F.Fab")
			(hide yes)
			(effects
				(font
					(size 1 1)
					(thickness 0.15)
				)
			)
		)
		(sheetname "USB PHY")
		(sheetfile "usb-phy.kicad_sch")
		(attr smd)
		(fp_rect
			(start -0.925 -0.47)
			(end 0.925 0.47)
			(stroke
				(width 0.05)
				(type default)
			)
			(fill no)
			(layer "F.CrtYd")
		)
		(fp_rect
			(start -0.5 -0.25)
			(end 0.5 0.25)
			(stroke
				(width 0.15)
				(type solid)
			)
			(fill no)
			(layer "F.Fab")
		)
		(pad "1" smd roundrect
			(at -0.48 0 90)
			(size 0.59 0.64)
			(layers "F.Cu" "F.Mask" "F.Paste")
			(roundrect_rratio 0.25)
			(net 790 "Net-(D26-A)")
			(pintype "passive")
		)
		(pad "2" smd roundrect
			(at 0.48 0 90)
			(size 0.59 0.64)
			(layers "F.Cu" "F.Mask" "F.Paste")
			(roundrect_rratio 0.25)
			(net 912 "/USB PHY/LED_TX0")
			(pintype "passive")
		)
	)
	(footprint "antmicro-footprints:C_0402_1005Metric"
		(layer "F.Cu")
		(at 193.7 169.249 -90)
		(descr "Capacitor SMD 0402")
		(tags "capacitor SMD 0402")
		(property "Reference" "C204"
			(at 0.801 -0.4 270)
			(layer "F.SilkS")
			(effects
				(font
					(size 0.7 0.7)
					(thickness 0.15)
				)
				(justify right bottom)
			)
		)
		(property "Value" "C_100n_0402"
			(at 0 1.4 90)
			(layer "F.Fab")
			(effects
				(font
					(size 0.7 0.7)
					(thickness 0.15)
				)
				(justify right bottom)
			)
		)
		(property "Description" "SMD Multilayer Ceramic Capacitor, 0.1 µF, 50 V, 0402 [1005 Metric], ± 10%, X5R, GRM Series"
			(at 0 0 270)
			(layer "F.Fab")
			(hide yes)
			(effects
				(font
					(size 1.27 1.27)
					(thickness 0.15)
				)
			)
		)
		(property "Author" "Antmicro"
			(at 24.451 362.949 0)
			(layer "F.Fab")
			(hide yes)
			(effects
				(font
					(size 1 1)
					(thickness 0.15)
				)
			)
		)
		(property "Dielectric" "X5R"
			(at 24.451 362.949 0)
			(layer "F.Fab")
			(hide yes)
			(effects
				(font
					(size 1 1)
					(thickness 0.15)
				)
			)
		)
		(property "License" "Apache-2.0"
			(at 24.451 362.949 0)
			(layer "F.Fab")
			(hide yes)
			(effects
				(font
					(size 1 1)
					(thickness 0.15)
				)
			)
		)
		(property "MPN" "GRM155R61H104KE14D"
			(at 24.451 362.949 0)
			(layer "F.Fab")
			(hide yes)
			(effects
				(font
					(size 1 1)
					(thickness 0.15)
				)
			)
		)
		(property "Manufacturer" "Murata"
			(at 24.451 362.949 0)
			(layer "F.Fab")
			(hide yes)
			(effects
				(font
					(size 1 1)
					(thickness 0.15)
				)
			)
		)
		(property "Val" "100n"
			(at 24.451 362.949 0)
			(layer "F.Fab")
			(hide yes)
			(effects
				(font
					(size 1 1)
					(thickness 0.15)
				)
			)
		)
		(property "Voltage" "50V"
			(at 24.451 362.949 0)
			(layer "F.Fab")
			(hide yes)
			(effects
				(font
					(size 1 1)
					(thickness 0.15)
				)
			)
		)
		(sheetname "Power supply")
		(sheetfile "power-supply.kicad_sch")
		(attr smd)
		(fp_rect
			(start -0.925 -0.47)
			(end 0.925 0.47)
			(stroke
				(width 0.05)
				(type default)
			)
			(fill no)
			(layer "F.CrtYd")
		)
		(fp_line
			(start -0.494 0.248)
			(end -0.494 -0.25)
			(stroke
				(width 0.15)
				(type solid)
			)
			(layer "F.Fab")
		)
		(fp_line
			(start 0.504 0.248)
			(end -0.494 0.248)
			(stroke
				(width 0.15)
				(type solid)
			)
			(layer "F.Fab")
		)
		(fp_line
			(start -0.494 -0.25)
			(end 0.504 -0.25)
			(stroke
				(width 0.15)
				(type solid)
			)
			(layer "F.Fab")
		)
		(fp_line
			(start 0.504 -0.25)
			(end 0.504 0.248)
			(stroke
				(width 0.15)
				(type solid)
			)
			(layer "F.Fab")
		)
		(pad "1" smd roundrect
			(at -0.48 0 270)
			(size 0.59 0.64)
			(layers "F.Cu" "F.Mask" "F.Paste")
			(roundrect_rratio 0.25)
			(net 1 "GND")
			(pintype "passive")
		)
		(pad "2" smd roundrect
			(at 0.48 0 270)
			(size 0.59 0.64)
			(layers "F.Cu" "F.Mask" "F.Paste")
			(roundrect_rratio 0.25)
			(net 700 "/Power supply/USB_PD_VBUS")
			(pintype "passive")
		)
	)
	(footprint "antmicro-footprints:R_0402_1005Metric"
		(layer "F.Cu")
		(at 154.3125 169.2 90)
		(descr "Resistor SMD 0402")
		(tags "resistor SMD 0402")
		(property "Reference" "R296"
			(at 0.1 -0.4625 90)
			(layer "F.SilkS")
			(effects
				(font
					(size 0.7 0.7)
					(thickness 0.15)
				)
				(justify left bottom)
			)
		)
		(property "Value" "R_0R_0402"
			(at 0 1.4 90)
			(layer "F.Fab")
			(effects
				(font
					(size 0.7 0.7)
					(thickness 0.15)
				)
				(justify left bottom)
			)
		)
		(property "Description" "SMD Chip Resistor, Jumper, 0 ohm, 100 mW, 0402 [1005 Metric], Thick Film, General Purpose"
			(at 0 0 90)
			(layer "F.Fab")
			(hide yes)
			(effects
				(font
					(size 1.27 1.27)
					(thickness 0.15)
				)
			)
		)
		(property "Author" "Antmicro"
			(at 323.5125 14.8875 0)
			(layer "F.Fab")
			(hide yes)
			(effects
				(font
					(size 1 1)
					(thickness 0.15)
				)
			)
		)
		(property "Current" "1A"
			(at 323.5125 14.8875 0)
			(layer "F.Fab")
			(hide yes)
			(effects
				(font
					(size 1 1)
					(thickness 0.15)
				)
			)
		)
		(property "License" "Apache-2.0"
			(at 323.5125 14.8875 0)
			(layer "F.Fab")
			(hide yes)
			(effects
				(font
					(size 1 1)
					(thickness 0.15)
				)
			)
		)
		(property "MPN" "ERJ2GE0R00X"
			(at 323.5125 14.8875 0)
			(layer "F.Fab")
			(hide yes)
			(effects
				(font
					(size 1 1)
					(thickness 0.15)
				)
			)
		)
		(property "Manufacturer" "Panasonic"
			(at 323.5125 14.8875 0)
			(layer "F.Fab")
			(hide yes)
			(effects
				(font
					(size 1 1)
					(thickness 0.15)
				)
			)
		)
		(property "Tolerance" ""
			(at 323.5125 14.8875 0)
			(layer "F.Fab")
			(hide yes)
			(effects
				(font
					(size 1 1)
					(thickness 0.15)
				)
			)
		)
		(property "Val" "0R"
			(at 323.5125 14.8875 0)
			(layer "F.Fab")
			(hide yes)
			(effects
				(font
					(size 1 1)
					(thickness 0.15)
				)
			)
		)
		(sheetname "DC-DC Converters")
		(sheetfile "dc-dc.kicad_sch")
		(attr smd)
		(fp_rect
			(start -0.925 -0.47)
			(end 0.925 0.47)
			(stroke
				(width 0.05)
				(type default)
			)
			(fill no)
			(layer "F.CrtYd")
		)
		(fp_rect
			(start -0.5 -0.25)
			(end 0.5 0.25)
			(stroke
				(width 0.15)
				(type solid)
			)
			(fill no)
			(layer "F.Fab")
		)
		(pad "1" smd roundrect
			(at -0.48 0 90)
			(size 0.59 0.64)
			(layers "F.Cu" "F.Mask" "F.Paste")
			(roundrect_rratio 0.25)
			(net 959 "/DC-DC Converters/FB1")
			(pintype "passive")
		)
		(pad "2" smd roundrect
			(at 0.48 0 90)
			(size 0.59 0.64)
			(layers "F.Cu" "F.Mask" "F.Paste")
			(roundrect_rratio 0.25)
			(net 733 "/DC-DC Converters/MGTAVCC_local")
			(pintype "passive")
		)
	)
	(footprint "antmicro-footprints:BGA-900_31x31mm_Layout30x30_P1x1mm_FFG900"
		(locked yes)
		(layer "F.Cu")
		(at 200 130)
		(property "Reference" "U1"
			(at -15.74 -15.78 0)
			(layer "F.SilkS")
			(effects
				(font
					(size 0.7 0.7)
					(thickness 0.15)
				)
				(justify left bottom)
			)
		)
		(property "Value" "XC7K410T-2FFG900I"
			(at -4.436 17.635 0)
			(layer "F.Fab")
			(effects
				(font
					(size 0.7 0.7)
					(thickness 0.15)
				)
				(justify left bottom)
			)
		)
		(property "Description" "FPGA, Kintex-7, MMCM, PLL, 350 I/O's, 710 MHz, 406720 Cells, 970 mV to 1.03 V, FCBGA-900"
			(at 0 0 0)
			(layer "F.Fab")
			(hide yes)
			(effects
				(font
					(size 1.27 1.27)
					(thickness 0.15)
				)
			)
		)
		(property "Author" "Antmicro"
			(at 0 0 0)
			(layer "F.Fab")
			(hide yes)
			(effects
				(font
					(size 1 1)
					(thickness 0.15)
				)
			)
		)
		(property "License" "Apache-2.0"
			(at 0 0 0)
			(layer "F.Fab")
			(hide yes)
			(effects
				(font
					(size 1 1)
					(thickness 0.15)
				)
			)
		)
		(property "MPN" "XC7K410T-2FFG900I"
			(at 0 0 0)
			(layer "F.Fab")
			(hide yes)
			(effects
				(font
					(size 1 1)
					(thickness 0.15)
				)
			)
		)
		(property "Manufacturer" "AMD-Xilinx"
			(at 0 0 0)
			(layer "F.Fab")
			(hide yes)
			(effects
				(font
					(size 1 1)
					(thickness 0.15)
				)
			)
		)
		(sheetname "FPGA supply")
		(sheetfile "fpga-supply.kicad_sch")
		(attr smd)
		(fp_line
			(start -15.5 15.499)
			(end -15.5 -15.5)
			(stroke
				(width 0.15)
				(type solid)
			)
			(layer "F.SilkS")
		)
		(fp_line
			(start 15.499 -15.5)
			(end -15.5 -15.5)
			(stroke
				(width 0.15)
				(type solid)
			)
			(layer "F.SilkS")
		)
		(fp_line
			(start 15.499 -15.5)
			(end 15.499 15.499)
			(stroke
				(width 0.15)
				(type solid)
			)
			(layer "F.SilkS")
		)
		(fp_line
			(start 15.499 15.499)
			(end -15.5 15.499)
			(stroke
				(width 0.15)
				(type solid)
			)
			(layer "F.SilkS")
		)
		(fp_circle
			(center -15.8 -15.8)
			(end -15.751 -15.8)
			(stroke
				(width 0.15)
				(type solid)
			)
			(fill no)
			(layer "F.SilkS")
		)
		(fp_rect
			(start -16.5 -16.5)
			(end 16.499 16.499)
			(stroke
				(width 0.05)
				(type solid)
			)
			(fill no)
			(layer "F.CrtYd")
		)
		(fp_line
			(start -15.5 -15.301)
			(end -15.301 -15.5)
			(stroke
				(width 0.15)
				(type solid)
			)
			(layer "F.Fab")
		)
		(fp_line
			(start -15.5 15.499)
			(end -15.5 -15.5)
			(stroke
				(width 0.15)
				(type solid)
			)
			(layer "F.Fab")
		)
		(fp_line
			(start 15.499 -15.5)
			(end -15.5 -15.5)
			(stroke
				(width 0.15)
				(type solid)
			)
			(layer "F.Fab")
		)
		(fp_line
			(start 15.499 15.499)
			(end -15.5 15.499)
			(stroke
				(width 0.15)
				(type solid)
			)
			(layer "F.Fab")
		)
		(fp_line
			(start 15.499 15.499)
			(end 15.499 -15.5)
			(stroke
				(width 0.15)
				(type solid)
			)
			(layer "F.Fab")
		)
		(pad "A1" smd circle
			(at -14.5 -14.5)
			(size 0.5 0.5)
			(property pad_prop_bga)
			(layers "F.Cu" "F.Mask" "F.Paste")
			(net 1 "GND")
			(pinfunction "GND")
			(pintype "bidirectional")
			(solder_mask_margin 0.02)
		)
		(pad "A2" smd circle
			(at -13.5 -14.5)
			(size 0.5 0.5)
			(property pad_prop_bga)
			(layers "F.Cu" "F.Mask" "F.Paste")
			(net 1 "GND")
			(pinfunction "GND")
			(pintype "passive")
			(solder_mask_margin 0.02)
		)
		(pad "A3" smd circle
			(at -12.5 -14.5)
			(size 0.5 0.5)
			(property pad_prop_bga)
			(layers "F.Cu" "F.Mask" "F.Paste")
			(net 573 "unconnected-(U1G-MGTXTXN3_118-PadA3)")
			(pinfunction "MGTXTXN3_118")
			(pintype "bidirectional+no_connect")
			(die_length 14.432)
			(solder_mask_margin 0.02)
		)
		(pad "A4" smd circle
			(at -11.5 -14.5)
			(size 0.5 0.5)
			(property pad_prop_bga)
			(layers "F.Cu" "F.Mask" "F.Paste")
			(net 574 "unconnected-(U1G-MGTXTXP3_118-PadA4)")
			(pinfunction "MGTXTXP3_118")
			(pintype "bidirectional+no_connect")
			(die_length 14.414)
			(solder_mask_margin 0.02)
		)
		(pad "A5" smd circle
			(at -10.5 -14.5)
			(size 0.5 0.5)
			(property pad_prop_bga)
			(layers "F.Cu" "F.Mask" "F.Paste")
			(net 1 "GND")
			(pinfunction "GND")
			(pintype "passive")
			(solder_mask_margin 0.02)
		)
		(pad "A6" smd circle
			(at -9.5 -14.5)
			(size 0.5 0.5)
			(property pad_prop_bga)
			(layers "F.Cu" "F.Mask" "F.Paste")
			(net 1 "GND")
			(pinfunction "GND")
			(pintype "passive")
			(solder_mask_margin 0.02)
		)
		(pad "A7" smd circle
			(at -8.5 -14.5)
			(size 0.5 0.5)
			(property pad_prop_bga)
			(layers "F.Cu" "F.Mask" "F.Paste")
			(net 575 "unconnected-(U1G-MGTXRXN3_118-PadA7)")
			(pinfunction "MGTXRXN3_118")
			(pintype "bidirectional+no_connect")
			(die_length 11.951)
			(solder_mask_margin 0.02)
		)
		(pad "A8" smd circle
			(at -7.5 -14.5)
			(size 0.5 0.5)
			(property pad_prop_bga)
			(layers "F.Cu" "F.Mask" "F.Paste")
			(net 576 "unconnected-(U1G-MGTXRXP3_118-PadA8)")
			(pinfunction "MGTXRXP3_118")
			(pintype "bidirectional+no_connect")
			(die_length 11.93)
			(solder_mask_margin 0.02)
		)
		(pad "A9" smd circle
			(at -6.5 -14.5)
			(size 0.5 0.5)
			(property pad_prop_bga)
			(layers "F.Cu" "F.Mask" "F.Paste")
			(net 1 "GND")
			(pinfunction "GND")
			(pintype "passive")
			(solder_mask_margin 0.02)
		)
		(pad "A10" smd circle
			(at -5.5 -14.5)
			(size 0.5 0.5)
			(property pad_prop_bga)
			(layers "F.Cu" "F.Mask" "F.Paste")
			(net 257 "/FPGA Config/INIT_B")
			(pinfunction "INIT_B_0")
			(pintype "bidirectional")
			(die_length 30.087)
			(solder_mask_margin 0.02)
		)
		(pad "A11" smd circle
			(at -4.5 -14.5)
			(size 0.5 0.5)
			(property pad_prop_bga)
			(layers "F.Cu" "F.Mask" "F.Paste")
			(net 428 "/FMC+ HSPC/FMC.IO17_P")
			(pinfunction "IO_L17P_T2_18")
			(pintype "bidirectional")
			(die_length 26.57)
			(solder_mask_margin 0.02)
		)
		(pad "A12" smd circle
			(at -3.5 -14.5)
			(size 0.5 0.5)
			(property pad_prop_bga)
			(layers "F.Cu" "F.Mask" "F.Paste")
			(net 426 "/FMC+ HSPC/FMC.IO17_N")
			(pinfunction "IO_L17N_T2_18")
			(pintype "bidirectional")
			(die_length 25.299)
			(solder_mask_margin 0.02)
		)
		(pad "A13" smd circle
			(at -2.5 -14.5)
			(size 0.5 0.5)
			(property pad_prop_bga)
			(layers "F.Cu" "F.Mask" "F.Paste")
			(net 634 "/FMC+ HSPC/FMC.IO22_N")
			(pinfunction "IO_L22N_T3_18")
			(pintype "bidirectional")
			(die_length 25.219)
			(solder_mask_margin 0.02)
		)
		(pad "A14" smd circle
			(at -1.5 -14.5)
			(size 0.5 0.5)
			(property pad_prop_bga)
			(layers "F.Cu" "F.Mask" "F.Paste")
			(net 1 "GND")
			(pinfunction "GND")
			(pintype "passive")
			(solder_mask_margin 0.02)
		)
		(pad "A15" smd circle
			(at -0.5 -14.5)
			(size 0.5 0.5)
			(property pad_prop_bga)
			(layers "F.Cu" "F.Mask" "F.Paste")
			(net 349 "/FMC+ HSPC/FMC.IO24_N")
			(pinfunction "IO_L24N_T3_18")
			(pintype "bidirectional")
			(die_length 24.216)
			(solder_mask_margin 0.02)
		)
		(pad "A16" smd circle
			(at 0.5 -14.5)
			(size 0.5 0.5)
			(property pad_prop_bga)
			(layers "F.Cu" "F.Mask" "F.Paste")
			(net 578 "/FPGA Bank 12 & 13/USB_HOST.CLK")
			(pinfunction "IO_L20P_T3_17")
			(pintype "bidirectional")
			(die_length 26.083)
			(solder_mask_margin 0.02)
		)
		(pad "A17" smd circle
			(at 1.5 -14.5)
			(size 0.5 0.5)
			(property pad_prop_bga)
			(layers "F.Cu" "F.Mask" "F.Paste")
			(net 579 "/FPGA Bank 12 & 13/USB_HOST.MISO")
			(pinfunction "IO_L20N_T3_17")
			(pintype "bidirectional")
			(die_length 25.395)
			(solder_mask_margin 0.02)
		)
		(pad "A18" smd circle
			(at 2.5 -14.5)
			(size 0.5 0.5)
			(property pad_prop_bga)
			(layers "F.Cu" "F.Mask" "F.Paste")
			(net 580 "/FPGA Bank 12 & 13/USB_HOST.GPX")
			(pinfunction "IO_L22N_T3_17")
			(pintype "bidirectional")
			(die_length 25.265)
			(solder_mask_margin 0.02)
		)
		(pad "A19" smd circle
			(at 3.5 -14.5)
			(size 0.5 0.5)
			(property pad_prop_bga)
			(layers "F.Cu" "F.Mask" "F.Paste")
			(net 24 "+3V3")
			(pinfunction "VCCO_17")
			(pintype "bidirectional")
			(solder_mask_margin 0.02)
		)
		(pad "A20" smd circle
			(at 4.5 -14.5)
			(size 0.5 0.5)
			(property pad_prop_bga)
			(layers "F.Cu" "F.Mask" "F.Paste")
			(net 581 "unconnected-(U1C-IO_L21P_T3_DQS_17-PadA20)")
			(pinfunction "IO_L21P_T3_DQS_17")
			(pintype "bidirectional+no_connect")
			(die_length 23.453)
			(solder_mask_margin 0.02)
		)
		(pad "A21" smd circle
			(at 5.5 -14.5)
			(size 0.5 0.5)
			(property pad_prop_bga)
			(layers "F.Cu" "F.Mask" "F.Paste")
			(net 582 "unconnected-(U1C-IO_L21N_T3_DQS_17-PadA21)")
			(pinfunction "IO_L21N_T3_DQS_17")
			(pintype "bidirectional+no_connect")
			(die_length 23.28)
			(solder_mask_margin 0.02)
		)
		(pad "A22" smd circle
			(at 6.5 -14.5)
			(size 0.5 0.5)
			(property pad_prop_bga)
			(layers "F.Cu" "F.Mask" "F.Paste")
			(net 565 "/FPGA Bank 16 & 17/HDMI.CLK_N")
			(pinfunction "IO_L23N_T3_17")
			(pintype "bidirectional")
			(die_length 21.922)
			(solder_mask_margin 0.02)
		)
		(pad "A23" smd circle
			(at 7.5 -14.5)
			(size 0.5 0.5)
			(property pad_prop_bga)
			(layers "F.Cu" "F.Mask" "F.Paste")
			(net 1271 "/USER_IO.B8")
			(pinfunction "IO_L1N_T0_16")
			(pintype "bidirectional")
			(die_length 22.02)
			(solder_mask_margin 0.02)
		)
		(pad "A24" smd circle
			(at 8.5 -14.5)
			(size 0.5 0.5)
			(property pad_prop_bga)
			(layers "F.Cu" "F.Mask" "F.Paste")
			(net 1 "GND")
			(pinfunction "GND")
			(pintype "passive")
			(solder_mask_margin 0.02)
		)
		(pad "A25" smd circle
			(at 9.5 -14.5)
			(size 0.5 0.5)
			(property pad_prop_bga)
			(layers "F.Cu" "F.Mask" "F.Paste")
			(net 1284 "/USER_IO.B24")
			(pinfunction "IO_L10P_T1_16")
			(pintype "bidirectional")
			(die_length 23.09)
			(solder_mask_margin 0.02)
		)
		(pad "A26" smd circle
			(at 10.5 -14.5)
			(size 0.5 0.5)
			(property pad_prop_bga)
			(layers "F.Cu" "F.Mask" "F.Paste")
			(net 1274 "/USER_IO.B11")
			(pinfunction "IO_L10N_T1_16")
			(pintype "bidirectional")
			(die_length 24.986)
			(solder_mask_margin 0.02)
		)
		(pad "A27" smd circle
			(at 11.5 -14.5)
			(size 0.5 0.5)
			(property pad_prop_bga)
			(layers "F.Cu" "F.Mask" "F.Paste")
			(net 1273 "/USER_IO.B10")
			(pinfunction "IO_L7N_T1_16")
			(pintype "bidirectional")
			(die_length 22.513)
			(solder_mask_margin 0.02)
		)
		(pad "A28" smd circle
			(at 12.5 -14.5)
			(size 0.5 0.5)
			(property pad_prop_bga)
			(layers "F.Cu" "F.Mask" "F.Paste")
			(net 1272 "/USER_IO.B9")
			(pinfunction "IO_L9N_T1_DQS_16")
			(pintype "bidirectional")
			(die_length 23.234)
			(solder_mask_margin 0.02)
		)
		(pad "A29" smd circle
			(at 13.5 -14.5)
			(size 0.5 0.5)
			(property pad_prop_bga)
			(layers "F.Cu" "F.Mask" "F.Paste")
			(net 3 "VCC_USR_B")
			(pinfunction "VCCO_16")
			(pintype "bidirectional")
			(solder_mask_margin 0.02)
		)
		(pad "A30" smd circle
			(at 14.5 -14.5)
			(size 0.5 0.5)
			(property pad_prop_bga)
			(layers "F.Cu" "F.Mask" "F.Paste")
			(net 1267 "/USER_IO.B3")
			(pinfunction "IO_L17N_T2_16")
			(pintype "bidirectional")
			(die_length 24.871)
			(solder_mask_margin 0.02)
		)
		(pad "AA1" smd circle
			(at -14.5 5.5)
			(size 0.5 0.5)
			(property pad_prop_bga)
			(layers "F.Cu" "F.Mask" "F.Paste")
			(net 1 "GND")
			(pinfunction "GND")
			(pintype "passive")
			(solder_mask_margin 0.02)
		)
		(pad "AA2" smd circle
			(at -13.5 5.5)
			(size 0.5 0.5)
			(property pad_prop_bga)
			(layers "F.Cu" "F.Mask" "F.Paste")
			(net 1 "GND")
			(pinfunction "GND")
			(pintype "passive")
			(solder_mask_margin 0.02)
		)
		(pad "AA3" smd circle
			(at -12.5 5.5)
			(size 0.5 0.5)
			(property pad_prop_bga)
			(layers "F.Cu" "F.Mask" "F.Paste")
			(net 483 "/FMC+ HSPC/GTX115.RX0_N")
			(pinfunction "MGTXRXN0_115")
			(pintype "bidirectional")
			(die_length 17.779)
			(solder_mask_margin 0.02)
		)
		(pad "AA4" smd circle
			(at -11.5 5.5)
			(size 0.5 0.5)
			(property pad_prop_bga)
			(layers "F.Cu" "F.Mask" "F.Paste")
			(net 486 "/FMC+ HSPC/GTX115.RX0_P")
			(pinfunction "MGTXRXP0_115")
			(pintype "bidirectional")
			(die_length 17.802)
			(solder_mask_margin 0.02)
		)
		(pad "AA5" smd circle
			(at -10.5 5.5)
			(size 0.5 0.5)
			(property pad_prop_bga)
			(layers "F.Cu" "F.Mask" "F.Paste")
			(net 1 "GND")
			(pinfunction "GND")
			(pintype "passive")
			(solder_mask_margin 0.02)
		)
		(pad "AA6" smd circle
			(at -9.5 5.5)
			(size 0.5 0.5)
			(property pad_prop_bga)
			(layers "F.Cu" "F.Mask" "F.Paste")
			(net 1 "GND")
			(pinfunction "GND")
			(pintype "passive")
			(solder_mask_margin 0.02)
		)
		(pad "AA7" smd circle
			(at -8.5 5.5)
			(size 0.5 0.5)
			(property pad_prop_bga)
			(layers "F.Cu" "F.Mask" "F.Paste")
			(net 1 "GND")
			(pinfunction "GND")
			(pintype "passive")
			(solder_mask_margin 0.02)
		)
		(pad "AA8" smd circle
			(at -7.5 5.5)
			(size 0.5 0.5)
			(property pad_prop_bga)
			(layers "F.Cu" "F.Mask" "F.Paste")
			(net 1309 "/USER_IO.DIP_SW2")
			(pinfunction "IO_L2P_T0_33")
			(pintype "bidirectional")
			(die_length 14.905)
			(solder_mask_margin 0.02)
		)
		(pad "AA9" smd circle
			(at -6.5 5.5)
			(size 0.5 0.5)
			(property pad_prop_bga)
			(layers "F.Cu" "F.Mask" "F.Paste")
			(net 26 "+1V8")
			(pinfunction "VCCO_33")
			(pintype "bidirectional")
			(solder_mask_margin 0.02)
		)
		(pad "AA10" smd circle
			(at -5.5 5.5 90)
			(size 0.5 0.5)
			(property pad_prop_bga)
			(layers "F.Cu" "F.Mask" "F.Paste")
			(net 13 "/USER_IO.BUTTON1")
			(pinfunction "IO_L5N_T0_33")
			(pintype "bidirectional")
			(die_length 8.194)
			(solder_mask_margin 0.02)
		)
		(pad "AA11" smd circle
			(at -4.5 5.5)
			(size 0.5 0.5)
			(property pad_prop_bga)
			(layers "F.Cu" "F.Mask" "F.Paste")
			(net 1228 "/USER_IO.BUTTON0")
			(pinfunction "IO_L5P_T0_33")
			(pintype "bidirectional")
			(die_length 8.33)
			(solder_mask_margin 0.02)
		)
		(pad "AA12" smd circle
			(at -3.5 5.5)
			(size 0.5 0.5)
			(property pad_prop_bga)
			(layers "F.Cu" "F.Mask" "F.Paste")
			(net 1318 "/USER_IO.DIP_SW7")
			(pinfunction "IO_L1P_T0_33")
			(pintype "bidirectional")
			(die_length 8.782)
			(solder_mask_margin 0.02)
		)
		(pad "AA13" smd circle
			(at -2.5 5.5)
			(size 0.5 0.5)
			(property pad_prop_bga)
			(layers "F.Cu" "F.Mask" "F.Paste")
			(net 1324 "/USER_IO.DIP_SW4")
			(pinfunction "IO_L6P_T0_33")
			(pintype "bidirectional")
			(die_length 10.996)
			(solder_mask_margin 0.02)
		)
		(pad "AA14" smd circle
			(at -1.5 5.5)
			(size 0.5 0.5)
			(property pad_prop_bga)
			(layers "F.Cu" "F.Mask" "F.Paste")
			(net 1 "GND")
			(pinfunction "GND")
			(pintype "passive")
			(solder_mask_margin 0.02)
		)
		(pad "AA15" smd circle
			(at -0.5 5.5)
			(size 0.5 0.5)
			(property pad_prop_bga)
			(layers "F.Cu" "F.Mask" "F.Paste")
			(net 584 "/FPGA Bank 12 & 13/USB_USER.VP")
			(pinfunction "IO_L20P_T3_32")
			(pintype "bidirectional")
			(die_length 12.195)
			(solder_mask_margin 0.02)
		)
		(pad "AA16" smd circle
			(at 0.5 5.5)
			(size 0.5 0.5)
			(property pad_prop_bga)
			(layers "F.Cu" "F.Mask" "F.Paste")
			(net 511 "/FPGA Bank 18 & 32/ETH_RMII.TXEN")
			(pinfunction "IO_L23N_T3_32")
			(pintype "bidirectional")
			(die_length 14.54)
			(solder_mask_margin 0.02)
		)
		(pad "AA17" smd circle
			(at 1.5 5.5)
			(size 0.5 0.5)
			(property pad_prop_bga)
			(layers "F.Cu" "F.Mask" "F.Paste")
			(net 585 "unconnected-(U1D-IO_L23P_T3_32-PadAA17)")
			(pinfunction "IO_L23P_T3_32")
			(pintype "bidirectional+no_connect")
			(die_length 16.445)
			(solder_mask_margin 0.02)
		)
		(pad "AA18" smd circle
			(at 2.5 5.5)
			(size 0.5 0.5)
			(property pad_prop_bga)
			(layers "F.Cu" "F.Mask" "F.Paste")
			(net 502 "/FPGA Bank 18 & 32/ETH_RMII.MDIO")
			(pinfunction "IO_L16P_T2_32")
			(pintype "bidirectional")
			(die_length 23.589)
			(solder_mask_margin 0.02)
		)
		(pad "AA19" smd circle
			(at 3.5 5.5)
			(size 0.5 0.5)
			(property pad_prop_bga)
			(layers "F.Cu" "F.Mask" "F.Paste")
			(net 26 "+1V8")
			(pinfunction "VCCO_32")
			(pintype "bidirectional")
			(solder_mask_margin 0.02)
		)
		(pad "AA20" smd circle
			(at 4.5 5.5)
			(size 0.5 0.5)
			(property pad_prop_bga)
			(layers "F.Cu" "F.Mask" "F.Paste")
			(net 1363 "/SUP_MCU.A17")
			(pinfunction "IO_L6P_T0_12")
			(pintype "bidirectional")
			(die_length 6.201)
			(solder_mask_margin 0.02)
		)
		(pad "AA21" smd circle
			(at 5.5 5.5)
			(size 0.5 0.5)
			(property pad_prop_bga)
			(layers "F.Cu" "F.Mask" "F.Paste")
			(net 1372 "/SUP_MCU.D0")
			(pinfunction "IO_L2N_T0_12")
			(pintype "bidirectional")
			(die_length 9.235)
			(solder_mask_margin 0.02)
		)
		(pad "AA22" smd circle
			(at 6.5 5.5)
			(size 0.5 0.5)
			(property pad_prop_bga)
			(layers "F.Cu" "F.Mask" "F.Paste")
			(net 1382 "/SUP_MCU.D1")
			(pinfunction "IO_L4P_T0_12")
			(pintype "bidirectional")
			(die_length 8.789)
			(solder_mask_margin 0.02)
		)
		(pad "AA23" smd circle
			(at 7.5 5.5)
			(size 0.5 0.5)
			(property pad_prop_bga)
			(layers "F.Cu" "F.Mask" "F.Paste")
			(net 1381 "/SUP_MCU.D4")
			(pinfunction "IO_L4N_T0_12")
			(pintype "bidirectional")
			(die_length 8.88)
			(solder_mask_margin 0.02)
		)
		(pad "AA24" smd circle
			(at 8.5 5.5)
			(size 0.5 0.5)
			(property pad_prop_bga)
			(layers "F.Cu" "F.Mask" "F.Paste")
			(net 1 "GND")
			(pinfunction "GND")
			(pintype "passive")
			(solder_mask_margin 0.02)
		)
		(pad "AA25" smd circle
			(at 9.5 5.5)
			(size 0.5 0.5)
			(property pad_prop_bga)
			(layers "F.Cu" "F.Mask" "F.Paste")
			(net 433 "/FPGA Bank 12 & 13/PMOD_A.IO7")
			(pinfunction "IO_L6P_T0_13")
			(pintype "bidirectional")
			(die_length 12.199)
			(solder_mask_margin 0.02)
		)
		(pad "AA26" smd circle
			(at 10.5 5.5)
			(size 0.5 0.5)
			(property pad_prop_bga)
			(layers "F.Cu" "F.Mask" "F.Paste")
			(net 1302 "/USER_IO.LED_GREEN3")
			(pinfunction "IO_L1N_T0_13")
			(pintype "bidirectional")
			(die_length 12.222)
			(solder_mask_margin 0.02)
		)
		(pad "AA27" smd circle
			(at 11.5 5.5)
			(size 0.5 0.5)
			(property pad_prop_bga)
			(layers "F.Cu" "F.Mask" "F.Paste")
			(net 451 "/FPGA Bank 12 & 13/PMOD_B.IO8")
			(pinfunction "IO_L5P_T0_13")
			(pintype "bidirectional")
			(die_length 12.889)
			(solder_mask_margin 0.02)
		)
		(pad "AA28" smd circle
			(at 12.5 5.5)
			(size 0.5 0.5)
			(property pad_prop_bga)
			(layers "F.Cu" "F.Mask" "F.Paste")
			(net 1301 "/USER_IO.LED_GREEN2")
			(pinfunction "IO_L3N_T0_DQS_13")
			(pintype "bidirectional")
			(die_length 14.752)
			(solder_mask_margin 0.02)
		)
		(pad "AA29" smd circle
			(at 13.5 5.5)
			(size 0.5 0.5)
			(property pad_prop_bga)
			(layers "F.Cu" "F.Mask" "F.Paste")
			(net 24 "+3V3")
			(pinfunction "VCCO_13")
			(pintype "bidirectional")
			(solder_mask_margin 0.02)
		)
		(pad "AA30" smd circle
			(at 14.5 5.5)
			(size 0.5 0.5)
			(property pad_prop_bga)
			(layers "F.Cu" "F.Mask" "F.Paste")
			(net 1303 "/USER_IO.LED_GREEN4")
			(pinfunction "IO_L8N_T1_13")
			(pintype "bidirectional")
			(die_length 18.273)
			(solder_mask_margin 0.02)
		)
		(pad "AB1" smd circle
			(at -14.5 6.5)
			(size 0.5 0.5)
			(property pad_prop_bga)
			(layers "F.Cu" "F.Mask" "F.Paste")
			(net 298 "/FPGA Config/MODE2")
			(pinfunction "M2_0")
			(pintype "bidirectional")
			(die_length 28.796)
			(solder_mask_margin 0.02)
		)
		(pad "AB2" smd circle
			(at -13.5 6.5)
			(size 0.5 0.5)
			(property pad_prop_bga)
			(layers "F.Cu" "F.Mask" "F.Paste")
			(net 299 "/FPGA Config/MODE1")
			(pinfunction "M1_0")
			(pintype "bidirectional")
			(die_length 27.299)
			(solder_mask_margin 0.02)
		)
		(pad "AB3" smd circle
			(at -12.5 6.5)
			(size 0.5 0.5)
			(property pad_prop_bga)
			(layers "F.Cu" "F.Mask" "F.Paste")
			(net 1 "GND")
			(pinfunction "GND")
			(pintype "passive")
			(solder_mask_margin 0.02)
		)
		(pad "AB4" smd circle
			(at -11.5 6.5)
			(size 0.5 0.5)
			(property pad_prop_bga)
			(layers "F.Cu" "F.Mask" "F.Paste")
			(net 1 "GND")
			(pinfunction "GND")
			(pintype "passive")
			(solder_mask_margin 0.02)
		)
		(pad "AB5" smd circle
			(at -10.5 6.5)
			(size 0.5 0.5)
			(property pad_prop_bga)
			(layers "F.Cu" "F.Mask" "F.Paste")
			(net 300 "/FPGA Config/MODE0")
			(pinfunction "M0_0")
			(pintype "bidirectional")
			(die_length 23.349)
			(solder_mask_margin 0.02)
		)
		(pad "AB6" smd circle
			(at -9.5 6.5)
			(size 0.5 0.5)
			(property pad_prop_bga)
			(layers "F.Cu" "F.Mask" "F.Paste")
			(net 24 "+3V3")
			(pinfunction "VCCO_0")
			(pintype "bidirectional")
			(solder_mask_margin 0.02)
		)
		(pad "AB7" smd circle
			(at -8.5 6.5)
			(size 0.5 0.5)
			(property pad_prop_bga)
			(layers "F.Cu" "F.Mask" "F.Paste")
			(net 568 "/FPGA Bank 33 & 34/DDR_VRP")
			(pinfunction "IO_25_VRP_34")
			(pintype "bidirectional")
			(die_length 13.149)
			(solder_mask_margin 0.02)
		)
		(pad "AB8" smd circle
			(at -7.5 6.5)
			(size 0.5 0.5)
			(property pad_prop_bga)
			(layers "F.Cu" "F.Mask" "F.Paste")
			(net 1310 "/USER_IO.DIP_SW1")
			(pinfunction "IO_L2N_T0_33")
			(pintype "bidirectional")
			(die_length 15.354)
			(solder_mask_margin 0.02)
		)
		(pad "AB9" smd circle
			(at -6.5 6.5)
			(size 0.5 0.5)
			(property pad_prop_bga)
			(layers "F.Cu" "F.Mask" "F.Paste")
			(net 1320 "/USER_IO.DIP_SW6")
			(pinfunction "IO_L3P_T0_DQS_33")
			(pintype "bidirectional")
			(die_length 11.874)
			(solder_mask_margin 0.02)
		)
		(pad "AB10" smd circle
			(at -5.5 6.5)
			(size 0.5 0.5)
			(property pad_prop_bga)
			(layers "F.Cu" "F.Mask" "F.Paste")
			(net 391 "/FPGA Bank 33 & 34/SD_CARD.DAT3")
			(pinfunction "IO_L7P_T1_33")
			(pintype "bidirectional")
			(die_length 11.514)
			(solder_mask_margin 0.02)
		)
		(pad "AB11" smd circle
			(at -4.5 6.5)
			(size 0.5 0.5)
			(property pad_prop_bga)
			(layers "F.Cu" "F.Mask" "F.Paste")
			(net 1 "GND")
			(pinfunction "GND")
			(pintype "passive")
			(solder_mask_margin 0.02)
		)
		(pad "AB12" smd circle
			(at -3.5 6.5)
			(size 0.5 0.5)
			(property pad_prop_bga)
			(layers "F.Cu" "F.Mask" "F.Paste")
			(net 399 "unconnected-(U1E-IO_L1N_T0_33-PadAB12)")
			(pinfunction "IO_L1N_T0_33")
			(pintype "bidirectional+no_connect")
			(die_length 9.344)
			(solder_mask_margin 0.02)
		)
		(pad "AB13" smd circle
			(at -2.5 6.5)
			(size 0.5 0.5)
			(property pad_prop_bga)
			(layers "F.Cu" "F.Mask" "F.Paste")
			(net 1322 "/USER_IO.DIP_SW5")
			(pinfunction "IO_L6N_T0_VREF_33")
			(pintype "bidirectional")
			(die_length 8.095)
			(solder_mask_margin 0.02)
		)
		(pad "AB14" smd circle
			(at -1.5 6.5)
			(size 0.5 0.5)
			(property pad_prop_bga)
			(layers "F.Cu" "F.Mask" "F.Paste")
			(net 586 "unconnected-(U1D-IO_25_VRP_32-PadAB14)")
			(pinfunction "IO_25_VRP_32")
			(pintype "bidirectional+no_connect")
			(die_length 11.456)
			(solder_mask_margin 0.02)
		)
		(pad "AB15" smd circle
			(at -0.5 6.5)
			(size 0.5 0.5)
			(property pad_prop_bga)
			(layers "F.Cu" "F.Mask" "F.Paste")
			(net 587 "/FPGA Bank 12 & 13/USB_USER.RCV")
			(pinfunction "IO_L20N_T3_32")
			(pintype "bidirectional")
			(die_length 11.928)
			(solder_mask_margin 0.02)
		)
		(pad "AB16" smd circle
			(at 0.5 6.5)
			(size 0.5 0.5)
			(property pad_prop_bga)
			(layers "F.Cu" "F.Mask" "F.Paste")
			(net 26 "+1V8")
			(pinfunction "VCCO_32")
			(pintype "passive")
			(solder_mask_margin 0.02)
		)
		(pad "AB17" smd circle
			(at 1.5 6.5)
			(size 0.5 0.5)
			(property pad_prop_bga)
			(layers "F.Cu" "F.Mask" "F.Paste")
			(net 588 "unconnected-(U1D-IO_L18P_T2_32-PadAB17)")
			(pinfunction "IO_L18P_T2_32")
			(pintype "bidirectional+no_connect")
			(die_length 20.845)
			(solder_mask_margin 0.02)
		)
		(pad "AB18" smd circle
			(at 2.5 6.5)
			(size 0.5 0.5)
			(property pad_prop_bga)
			(layers "F.Cu" "F.Mask" "F.Paste")
			(net 589 "/FPGA Bank 18 & 32/ETH_RMII.MDC")
			(pinfunction "IO_L16N_T2_32")
			(pintype "bidirectional")
			(die_length 21.634)
			(solder_mask_margin 0.02)
		)
		(pad "AB19" smd circle
			(at 3.5 6.5)
			(size 0.5 0.5)
			(property pad_prop_bga)
			(layers "F.Cu" "F.Mask" "F.Paste")
			(net 590 "unconnected-(U1D-IO_L17P_T2_32-PadAB19)")
			(pinfunction "IO_L17P_T2_32")
			(pintype "bidirectional+no_connect")
			(die_length 21.895)
			(solder_mask_margin 0.02)
		)
		(pad "AB20" smd circle
			(at 4.5 6.5)
			(size 0.5 0.5)
			(property pad_prop_bga)
			(layers "F.Cu" "F.Mask" "F.Paste")
			(net 1356 "/SUP_MCU.A18")
			(pinfunction "IO_L6N_T0_VREF_12")
			(pintype "bidirectional")
			(die_length 4.931)
			(solder_mask_margin 0.02)
		)
		(pad "AB21" smd circle
			(at 5.5 6.5)
			(size 0.5 0.5)
			(property pad_prop_bga)
			(layers "F.Cu" "F.Mask" "F.Paste")
			(net 1 "GND")
			(pinfunction "GND")
			(pintype "passive")
			(solder_mask_margin 0.02)
		)
		(pad "AB22" smd circle
			(at 6.5 6.5)
			(size 0.5 0.5)
			(property pad_prop_bga)
			(layers "F.Cu" "F.Mask" "F.Paste")
			(net 1370 "/SUP_MCU.A11")
			(pinfunction "IO_L3P_T0_DQS_12")
			(pintype "bidirectional")
			(die_length 7.838)
			(solder_mask_margin 0.02)
		)
		(pad "AB23" smd circle
			(at 7.5 6.5)
			(size 0.5 0.5)
			(property pad_prop_bga)
			(layers "F.Cu" "F.Mask" "F.Paste")
			(net 1373 "/SUP_MCU.D3")
			(pinfunction "IO_L3N_T0_DQS_12")
			(pintype "bidirectional")
			(die_length 8.178)
			(solder_mask_margin 0.02)
		)
		(pad "AB24" smd circle
			(at 8.5 6.5)
			(size 0.5 0.5)
			(property pad_prop_bga)
			(layers "F.Cu" "F.Mask" "F.Paste")
			(net 1388 "/SUP_MCU.WR")
			(pinfunction "IO_L7P_T1_12")
			(pintype "bidirectional")
			(die_length 8.112)
			(solder_mask_margin 0.02)
		)
		(pad "AB25" smd circle
			(at 9.5 6.5)
			(size 0.5 0.5)
			(property pad_prop_bga)
			(layers "F.Cu" "F.Mask" "F.Paste")
			(net 453 "/FPGA Bank 12 & 13/PMOD_B.IO10")
			(pinfunction "IO_L6N_T0_VREF_13")
			(pintype "bidirectional")
			(die_length 11.623)
			(solder_mask_margin 0.02)
		)
		(pad "AB26" smd circle
			(at 10.5 6.5)
			(size 0.5 0.5)
			(property pad_prop_bga)
			(layers "F.Cu" "F.Mask" "F.Paste")
			(net 24 "+3V3")
			(pinfunction "VCCO_13")
			(pintype "passive")
			(solder_mask_margin 0.02)
		)
		(pad "AB27" smd circle
			(at 11.5 6.5)
			(size 0.5 0.5)
			(property pad_prop_bga)
			(layers "F.Cu" "F.Mask" "F.Paste")
			(net 1402 "/PLL.CLK2")
			(pinfunction "IO_L12P_T1_MRCC_13")
			(pintype "bidirectional")
			(die_length 15.547)
			(solder_mask_margin 0.02)
		)
		(pad "AB28" smd circle
			(at 12.5 6.5)
			(size 0.5 0.5)
			(property pad_prop_bga)
			(layers "F.Cu" "F.Mask" "F.Paste")
			(net 1307 "/USER_IO.LED_BLUE")
			(pinfunction "IO_L5N_T0_13")
			(pintype "bidirectional")
			(die_length 14.753)
			(solder_mask_margin 0.02)
		)
		(pad "AB29" smd circle
			(at 13.5 6.5)
			(size 0.5 0.5)
			(property pad_prop_bga)
			(layers "F.Cu" "F.Mask" "F.Paste")
			(net 470 "/FPGA Bank 12 & 13/PMOD_B.IO2")
			(pinfunction "IO_L10P_T1_13")
			(pintype "bidirectional")
			(die_length 17.569)
			(solder_mask_margin 0.02)
		)
		(pad "AB30" smd circle
			(at 14.5 6.5)
			(size 0.5 0.5)
			(property pad_prop_bga)
			(layers "F.Cu" "F.Mask" "F.Paste")
			(net 462 "/FPGA Bank 12 & 13/PMOD_B.IO1")
			(pinfunction "IO_L10N_T1_13")
			(pintype "bidirectional")
			(die_length 19.386)
			(solder_mask_margin 0.02)
		)
		(pad "AC1" smd circle
			(at -14.5 7.5)
			(size 0.5 0.5)
			(property pad_prop_bga)
			(layers "F.Cu" "F.Mask" "F.Paste")
			(net 543 "/DRAM + SRAM/DDR.A12")
			(pinfunction "IO_L2N_T0_34")
			(pintype "bidirectional")
			(die_length 18.921)
			(solder_mask_margin 0.02)
		)
		(pad "AC2" smd circle
			(at -13.5 7.5)
			(size 0.5 0.5)
			(property pad_prop_bga)
			(layers "F.Cu" "F.Mask" "F.Paste")
			(net 544 "/DRAM + SRAM/DDR.A13")
			(pinfunction "IO_L2P_T0_34")
			(pintype "bidirectional")
			(die_length 17.032)
			(solder_mask_margin 0.02)
		)
		(pad "AC3" smd circle
			(at -12.5 7.5)
			(size 0.5 0.5)
			(property pad_prop_bga)
			(layers "F.Cu" "F.Mask" "F.Paste")
			(net 25 "+1V35")
			(pinfunction "VCCO_34")
			(pintype "bidirectional")
			(solder_mask_margin 0.02)
		)
		(pad "AC4" smd circle
			(at -11.5 7.5)
			(size 0.5 0.5)
			(property pad_prop_bga)
			(layers "F.Cu" "F.Mask" "F.Paste")
			(net 541 "/DRAM + SRAM/DDR.A10")
			(pinfunction "IO_L4N_T0_34")
			(pintype "bidirectional")
			(die_length 17.452)
			(solder_mask_margin 0.02)
		)
		(pad "AC5" smd circle
			(at -10.5 7.5)
			(size 0.5 0.5)
			(property pad_prop_bga)
			(layers "F.Cu" "F.Mask" "F.Paste")
			(net 542 "/DRAM + SRAM/DDR.A11")
			(pinfunction "IO_L4P_T0_34")
			(pintype "bidirectional")
			(die_length 16.757)
			(solder_mask_margin 0.02)
		)
		(pad "AC6" smd circle
			(at -9.5 7.5)
			(size 0.5 0.5)
			(property pad_prop_bga)
			(layers "F.Cu" "F.Mask" "F.Paste")
			(net 567 "/FPGA Bank 33 & 34/DDR_VRN")
			(pinfunction "IO_0_VRN_34")
			(pintype "bidirectional")
			(die_length 18.428)
			(solder_mask_margin 0.02)
		)
		(pad "AC7" smd circle
			(at -8.5 7.5)
			(size 0.5 0.5)
			(property pad_prop_bga)
			(layers "F.Cu" "F.Mask" "F.Paste")
			(net 538 "/DRAM + SRAM/DDR.A7")
			(pinfunction "IO_L6P_T0_34")
			(pintype "bidirectional")
			(die_length 17.548)
			(solder_mask_margin 0.02)
		)
		(pad "AC8" smd circle
			(at -7.5 7.5)
			(size 0.5 0.5)
			(property pad_prop_bga)
			(layers "F.Cu" "F.Mask" "F.Paste")
			(net 1 "GND")
			(pinfunction "GND")
			(pintype "passive")
			(solder_mask_margin 0.02)
		)
		(pad "AC9" smd circle
			(at -6.5 7.5)
			(size 0.5 0.5)
			(property pad_prop_bga)
			(layers "F.Cu" "F.Mask" "F.Paste")
			(net 1308 "/USER_IO.DIP_SW3")
			(pinfunction "IO_L3N_T0_DQS_33")
			(pintype "bidirectional")
			(die_length 11.56)
			(solder_mask_margin 0.02)
		)
		(pad "AC10" smd circle
			(at -5.5 7.5)
			(size 0.5 0.5)
			(property pad_prop_bga)
			(layers "F.Cu" "F.Mask" "F.Paste")
			(net 393 "/FPGA Bank 33 & 34/SD_CARD.CMD")
			(pinfunction "IO_L7N_T1_33")
			(pintype "bidirectional")
			(die_length 12.11)
			(solder_mask_margin 0.02)
		)
		(pad "AC11" smd circle
			(at -4.5 7.5)
			(size 0.5 0.5)
			(property pad_prop_bga)
			(layers "F.Cu" "F.Mask" "F.Paste")
			(net 394 "/FPGA Bank 33 & 34/SD_CARD.CLK")
			(pinfunction "IO_L9N_T1_DQS_33")
			(pintype "bidirectional")
			(die_length 14.841)
			(solder_mask_margin 0.02)
		)
		(pad "AC12" smd circle
			(at -3.5 7.5)
			(size 0.5 0.5)
			(property pad_prop_bga)
			(layers "F.Cu" "F.Mask" "F.Paste")
			(net 406 "unconnected-(U1E-IO_L9P_T1_DQS_33-PadAC12)")
			(pinfunction "IO_L9P_T1_DQS_33")
			(pintype "bidirectional+no_connect")
			(die_length 14.948)
			(solder_mask_margin 0.02)
		)
		(pad "AC13" smd circle
			(at -2.5 7.5)
			(size 0.5 0.5)
			(property pad_prop_bga)
			(layers "F.Cu" "F.Mask" "F.Paste")
			(net 26 "+1V8")
			(pinfunction "VCCO_33")
			(pintype "passive")
			(solder_mask_margin 0.02)
		)
		(pad "AC14" smd circle
			(at -1.5 7.5)
			(size 0.5 0.5)
			(property pad_prop_bga)
			(layers "F.Cu" "F.Mask" "F.Paste")
			(net 601 "unconnected-(U1D-IO_L22P_T3_32-PadAC14)")
			(pinfunction "IO_L22P_T3_32")
			(pintype "bidirectional+no_connect")
			(die_length 12.461)
			(solder_mask_margin 0.02)
		)
		(pad "AC15" smd circle
			(at -0.5 7.5)
			(size 0.5 0.5)
			(property pad_prop_bga)
			(layers "F.Cu" "F.Mask" "F.Paste")
			(net 513 "/FPGA Bank 18 & 32/ETH_RMII.TXD0")
			(pinfunction "IO_L21N_T3_DQS_32")
			(pintype "bidirectional")
			(die_length 14.881)
			(solder_mask_margin 0.02)
		)
		(pad "AC16" smd circle
			(at 0.5 7.5)
			(size 0.5 0.5)
			(property pad_prop_bga)
			(layers "F.Cu" "F.Mask" "F.Paste")
			(net 602 "unconnected-(U1D-IO_L21P_T3_DQS_32-PadAC16)")
			(pinfunction "IO_L21P_T3_DQS_32")
			(pintype "bidirectional+no_connect")
			(die_length 15.421)
			(solder_mask_margin 0.02)
		)
		(pad "AC17" smd circle
			(at 1.5 7.5)
			(size 0.5 0.5)
			(property pad_prop_bga)
			(layers "F.Cu" "F.Mask" "F.Paste")
			(net 516 "/FPGA Bank 18 & 32/ETH_RMII.REFCLK")
			(pinfunction "IO_L18N_T2_32")
			(pintype "bidirectional")
			(die_length 20.722)
			(solder_mask_margin 0.02)
		)
		(pad "AC18" smd circle
			(at 2.5 7.5)
			(size 0.5 0.5)
			(property pad_prop_bga)
			(layers "F.Cu" "F.Mask" "F.Paste")
			(net 1 "GND")
			(pinfunction "GND")
			(pintype "passive")
			(solder_mask_margin 0.02)
		)
		(pad "AC19" smd circle
			(at 3.5 7.5)
			(size 0.5 0.5)
			(property pad_prop_bga)
			(layers "F.Cu" "F.Mask" "F.Paste")
			(net 519 "/FPGA Bank 18 & 32/ETH_RMII.RXD0")
			(pinfunction "IO_L17N_T2_32")
			(pintype "bidirectional")
			(die_length 20.941)
			(solder_mask_margin 0.02)
		)
		(pad "AC20" smd circle
			(at 4.5 7.5)
			(size 0.5 0.5)
			(property pad_prop_bga)
			(layers "F.Cu" "F.Mask" "F.Paste")
			(net 1374 "/SUP_MCU.D6")
			(pinfunction "IO_L5P_T0_12")
			(pintype "bidirectional")
			(die_length 6.323)
			(solder_mask_margin 0.02)
		)
		(pad "AC21" smd circle
			(at 5.5 7.5)
			(size 0.5 0.5)
			(property pad_prop_bga)
			(layers "F.Cu" "F.Mask" "F.Paste")
			(net 1380 "/SUP_MCU.D5")
			(pinfunction "IO_L5N_T0_12")
			(pintype "bidirectional")
			(die_length 5.293)
			(solder_mask_margin 0.02)
		)
		(pad "AC22" smd circle
			(at 6.5 7.5)
			(size 0.5 0.5)
			(property pad_prop_bga)
			(layers "F.Cu" "F.Mask" "F.Paste")
			(net 1369 "/SUP_MCU.A10")
			(pinfunction "IO_L8P_T1_12")
			(pintype "bidirectional")
			(die_length 7.349)
			(solder_mask_margin 0.02)
		)
		(pad "AC23" smd circle
			(at 7.5 7.5)
			(size 0.5 0.5)
			(property pad_prop_bga)
			(layers "F.Cu" "F.Mask" "F.Paste")
			(net 24 "+3V3")
			(pinfunction "VCCO_12")
			(pintype "bidirectional")
			(solder_mask_margin 0.02)
		)
		(pad "AC24" smd circle
			(at 8.5 7.5)
			(size 0.5 0.5)
			(property pad_prop_bga)
			(layers "F.Cu" "F.Mask" "F.Paste")
			(net 1378 "/SUP_MCU.A8")
			(pinfunction "IO_L9P_T1_DQS_12")
			(pintype "bidirectional")
			(die_length 8.538)
			(solder_mask_margin 0.02)
		)
		(pad "AC25" smd circle
			(at 9.5 7.5)
			(size 0.5 0.5)
			(property pad_prop_bga)
			(layers "F.Cu" "F.Mask" "F.Paste")
			(net 1391 "/SUP_MCU.A9")
			(pinfunction "IO_L7N_T1_12")
			(pintype "bidirectional")
			(die_length 9.609)
			(solder_mask_margin 0.02)
		)
		(pad "AC26" smd circle
			(at 10.5 7.5)
			(size 0.5 0.5)
			(property pad_prop_bga)
			(layers "F.Cu" "F.Mask" "F.Paste")
			(net 603 "unconnected-(U1A-IO_L19P_T3_13-PadAC26)")
			(pinfunction "IO_L19P_T3_13")
			(pintype "bidirectional+no_connect")
			(die_length 13.896)
			(solder_mask_margin 0.02)
		)
		(pad "AC27" smd circle
			(at 11.5 7.5)
			(size 0.5 0.5)
			(property pad_prop_bga)
			(layers "F.Cu" "F.Mask" "F.Paste")
			(net 604 "unconnected-(U1A-IO_L12N_T1_MRCC_13-PadAC27)")
			(pinfunction "IO_L12N_T1_MRCC_13")
			(pintype "bidirectional+no_connect")
			(die_length 15.768)
			(solder_mask_margin 0.02)
		)
		(pad "AC28" smd circle
			(at 12.5 7.5)
			(size 0.5 0.5)
			(property pad_prop_bga)
			(layers "F.Cu" "F.Mask" "F.Paste")
			(net 1 "GND")
			(pinfunction "GND")
			(pintype "passive")
			(solder_mask_margin 0.02)
		)
		(pad "AC29" smd circle
			(at 13.5 7.5)
			(size 0.5 0.5)
			(property pad_prop_bga)
			(layers "F.Cu" "F.Mask" "F.Paste")
			(net 471 "/FPGA Bank 12 & 13/PMOD_B.IO3")
			(pinfunction "IO_L7P_T1_13")
			(pintype "bidirectional")
			(die_length 15.896)
			(solder_mask_margin 0.02)
		)
		(pad "AC30" smd circle
			(at 14.5 7.5)
			(size 0.5 0.5)
			(property pad_prop_bga)
			(layers "F.Cu" "F.Mask" "F.Paste")
			(net 452 "/FPGA Bank 12 & 13/PMOD_B.IO9")
			(pinfunction "IO_L7N_T1_13")
			(pintype "bidirectional")
			(die_length 17.582)
			(solder_mask_margin 0.02)
		)
		(pad "AD1" smd circle
			(at -14.5 8.5)
			(size 0.5 0.5)
			(property pad_prop_bga)
			(layers "F.Cu" "F.Mask" "F.Paste")
			(net 552 "/DRAM + SRAM/DDR.CK_N")
			(pinfunction "IO_L3N_T0_DQS_34")
			(pintype "bidirectional")
			(die_length 20.294)
			(solder_mask_margin 0.02)
		)
		(pad "AD2" smd circle
			(at -13.5 8.5)
			(size 0.5 0.5)
			(property pad_prop_bga)
			(layers "F.Cu" "F.Mask" "F.Paste")
			(net 551 "/DRAM + SRAM/DDR.CK_P")
			(pinfunction "IO_L3P_T0_DQS_34")
			(pintype "bidirectional")
			(die_length 20.014)
			(solder_mask_margin 0.02)
		)
		(pad "AD3" smd circle
			(at -12.5 8.5)
			(size 0.5 0.5)
			(property pad_prop_bga)
			(layers "F.Cu" "F.Mask" "F.Paste")
			(net 545 "/DRAM + SRAM/DDR.A14")
			(pinfunction "IO_L1N_T0_34")
			(pintype "bidirectional")
			(die_length 19.656)
			(solder_mask_margin 0.02)
		)
		(pad "AD4" smd circle
			(at -11.5 8.5)
			(size 0.5 0.5)
			(property pad_prop_bga)
			(layers "F.Cu" "F.Mask" "F.Paste")
			(net 546 "/DRAM + SRAM/DDR.A15")
			(pinfunction "IO_L1P_T0_34")
			(pintype "bidirectional")
			(die_length 20.951)
			(solder_mask_margin 0.02)
		)
		(pad "AD5" smd circle
			(at -10.5 8.5)
			(size 0.5 0.5)
			(property pad_prop_bga)
			(layers "F.Cu" "F.Mask" "F.Paste")
			(net 1 "GND")
			(pinfunction "GND")
			(pintype "passive")
			(solder_mask_margin 0.02)
		)
		(pad "AD6" smd circle
			(at -9.5 8.5)
			(size 0.5 0.5)
			(property pad_prop_bga)
			(layers "F.Cu" "F.Mask" "F.Paste")
			(net 540 "/DRAM + SRAM/DDR.A9")
			(pinfunction "IO_L5P_T0_34")
			(pintype "bidirectional")
			(die_length 19.148)
			(solder_mask_margin 0.02)
		)
		(pad "AD7" smd circle
			(at -8.5 8.5)
			(size 0.5 0.5)
			(property pad_prop_bga)
			(layers "F.Cu" "F.Mask" "F.Paste")
			(net 11 "+0V675_VREF")
			(pinfunction "IO_L6N_T0_VREF_34")
			(pintype "bidirectional")
			(die_length 15.552)
			(solder_mask_margin 0.02)
		)
		(pad "AD8" smd circle
			(at -7.5 8.5)
			(size 0.5 0.5)
			(property pad_prop_bga)
			(layers "F.Cu" "F.Mask" "F.Paste")
			(net 412 "unconnected-(U1E-IO_L8P_T1_33-PadAD8)")
			(pinfunction "IO_L8P_T1_33")
			(pintype "bidirectional+no_connect")
			(die_length 14.02)
			(solder_mask_margin 0.02)
		)
		(pad "AD9" smd circle
			(at -6.5 8.5)
			(size 0.5 0.5)
			(property pad_prop_bga)
			(layers "F.Cu" "F.Mask" "F.Paste")
			(net 640 "/Clocks/LVDS_XO_200M_ENA")
			(pinfunction "IO_L10P_T1_33")
			(pintype "bidirectional")
			(die_length 15.484)
			(solder_mask_margin 0.02)
		)
		(pad "AD10" smd circle
			(at -5.5 8.5)
			(size 0.5 0.5)
			(property pad_prop_bga)
			(layers "F.Cu" "F.Mask" "F.Paste")
			(net 26 "+1V8")
			(pinfunction "VCCO_33")
			(pintype "passive")
			(solder_mask_margin 0.02)
		)
		(pad "AD11" smd circle
			(at -4.5 8.5)
			(size 0.5 0.5)
			(property pad_prop_bga)
			(layers "F.Cu" "F.Mask" "F.Paste")
			(net 623 "/Clocks/SYS.CLK_N")
			(pinfunction "IO_L12N_T1_MRCC_33")
			(pintype "bidirectional")
			(die_length 17.198)
			(solder_mask_margin 0.02)
		)
		(pad "AD12" smd circle
			(at -3.5 8.5)
			(size 0.5 0.5)
			(property pad_prop_bga)
			(layers "F.Cu" "F.Mask" "F.Paste")
			(net 624 "/Clocks/SYS.CLK_P")
			(pinfunction "IO_L12P_T1_MRCC_33")
			(pintype "bidirectional")
			(die_length 17.066)
			(solder_mask_margin 0.02)
		)
		(pad "AD13" smd circle
			(at -2.5 8.5)
			(size 0.5 0.5)
			(property pad_prop_bga)
			(layers "F.Cu" "F.Mask" "F.Paste")
			(net 415 "unconnected-(U1E-IO_25_VRP_33-PadAD13)")
			(pinfunction "IO_25_VRP_33")
			(pintype "bidirectional+no_connect")
			(die_length 15.655)
			(solder_mask_margin 0.02)
		)
		(pad "AD14" smd circle
			(at -1.5 8.5)
			(size 0.5 0.5)
			(property pad_prop_bga)
			(layers "F.Cu" "F.Mask" "F.Paste")
			(net 515 "/FPGA Bank 18 & 32/ETH_RMII.TXD1")
			(pinfunction "IO_L22N_T3_32")
			(pintype "bidirectional")
			(die_length 12.008)
			(solder_mask_margin 0.02)
		)
		(pad "AD15" smd circle
			(at -0.5 8.5)
			(size 0.5 0.5)
			(property pad_prop_bga)
			(layers "F.Cu" "F.Mask" "F.Paste")
			(net 1 "GND")
			(pinfunction "GND")
			(pintype "passive")
			(solder_mask_margin 0.02)
		)
		(pad "AD16" smd circle
			(at 0.5 8.5)
			(size 0.5 0.5)
			(property pad_prop_bga)
			(layers "F.Cu" "F.Mask" "F.Paste")
			(net 605 "unconnected-(U1D-IO_L14N_T2_SRCC_32-PadAD16)")
			(pinfunction "IO_L14N_T2_SRCC_32")
			(pintype "bidirectional+no_connect")
			(die_length 20.892)
			(solder_mask_margin 0.02)
		)
		(pad "AD17" smd circle
			(at 1.5 8.5)
			(size 0.5 0.5)
			(property pad_prop_bga)
			(layers "F.Cu" "F.Mask" "F.Paste")
			(net 606 "unconnected-(U1D-IO_L14P_T2_SRCC_32-PadAD17)")
			(pinfunction "IO_L14P_T2_SRCC_32")
			(pintype "bidirectional+no_connect")
			(die_length 20.478)
			(solder_mask_margin 0.02)
		)
		(pad "AD18" smd circle
			(at 2.5 8.5)
			(size 0.5 0.5)
			(property pad_prop_bga)
			(layers "F.Cu" "F.Mask" "F.Paste")
			(net 501 "/FPGA Bank 18 & 32/ETH_RMII.~{RESET}")
			(pinfunction "IO_L13P_T2_MRCC_32")
			(pintype "bidirectional")
			(die_length 22.172)
			(solder_mask_margin 0.02)
		)
		(pad "AD19" smd circle
			(at 3.5 8.5)
			(size 0.5 0.5)
			(property pad_prop_bga)
			(layers "F.Cu" "F.Mask" "F.Paste")
			(net 607 "unconnected-(U1D-IO_L10P_T1_32-PadAD19)")
			(pinfunction "IO_L10P_T1_32")
			(pintype "bidirectional+no_connect")
			(die_length 21.412)
			(solder_mask_margin 0.02)
		)
		(pad "AD20" smd circle
			(at 4.5 8.5)
			(size 0.5 0.5)
			(property pad_prop_bga)
			(layers "F.Cu" "F.Mask" "F.Paste")
			(net 24 "+3V3")
			(pinfunction "VCCO_12")
			(pintype "passive")
			(solder_mask_margin 0.02)
		)
		(pad "AD21" smd circle
			(at 5.5 8.5)
			(size 0.5 0.5)
			(property pad_prop_bga)
			(layers "F.Cu" "F.Mask" "F.Paste")
			(net 1392 "/SUP_MCU.ALE")
			(pinfunction "IO_L10P_T1_12")
			(pintype "bidirectional")
			(die_length 9.418)
			(solder_mask_margin 0.02)
		)
		(pad "AD22" smd circle
			(at 6.5 8.5)
			(size 0.5 0.5)
			(property pad_prop_bga)
			(layers "F.Cu" "F.Mask" "F.Paste")
			(net 1328 "/SUP_MCU.TX1")
			(pinfunction "IO_L8N_T1_12")
			(pintype "bidirectional")
			(die_length 8.457)
			(solder_mask_margin 0.02)
		)
		(pad "AD23" smd circle
			(at 7.5 8.5)
			(size 0.5 0.5)
			(property pad_prop_bga)
			(layers "F.Cu" "F.Mask" "F.Paste")
			(net 1365 "/SUP_MCU.CLKO")
			(pinfunction "IO_L12P_T1_MRCC_12")
			(pintype "bidirectional")
			(die_length 9.583)
			(solder_mask_margin 0.02)
		)
		(pad "AD24" smd circle
			(at 8.5 8.5)
			(size 0.5 0.5)
			(property pad_prop_bga)
			(layers "F.Cu" "F.Mask" "F.Paste")
			(net 1351 "/SUP_MCU.A0")
			(pinfunction "IO_L9N_T1_DQS_12")
			(pintype "bidirectional")
			(die_length 9.257)
			(solder_mask_margin 0.02)
		)
		(pad "AD25" smd circle
			(at 9.5 8.5)
			(size 0.5 0.5)
			(property pad_prop_bga)
			(layers "F.Cu" "F.Mask" "F.Paste")
			(net 1 "GND")
			(pinfunction "GND")
			(pintype "passive")
			(solder_mask_margin 0.02)
		)
		(pad "AD26" smd circle
			(at 10.5 8.5)
			(size 0.5 0.5)
			(property pad_prop_bga)
			(layers "F.Cu" "F.Mask" "F.Paste")
			(net 608 "unconnected-(U1A-IO_L19N_T3_VREF_13-PadAD26)")
			(pinfunction "IO_L19N_T3_VREF_13")
			(pintype "bidirectional+no_connect")
			(die_length 16.018)
			(solder_mask_margin 0.02)
		)
		(pad "AD27" smd circle
			(at 11.5 8.5)
			(size 0.5 0.5)
			(property pad_prop_bga)
			(layers "F.Cu" "F.Mask" "F.Paste")
			(net 438 "/FPGA Bank 12 & 13/PMOD_A.IO9")
			(pinfunction "IO_L11P_T1_SRCC_13")
			(pintype "bidirectional")
			(die_length 15.78)
			(solder_mask_margin 0.02)
		)
		(pad "AD28" smd circle
			(at 12.5 8.5)
			(size 0.5 0.5)
			(property pad_prop_bga)
			(layers "F.Cu" "F.Mask" "F.Paste")
			(net 442 "/FPGA Bank 12 & 13/PMOD_B.IO7")
			(pinfunction "IO_L11N_T1_SRCC_13")
			(pintype "bidirectional")
			(die_length 16.608)
			(solder_mask_margin 0.02)
		)
		(pad "AD29" smd circle
			(at 13.5 8.5)
			(size 0.5 0.5)
			(property pad_prop_bga)
			(layers "F.Cu" "F.Mask" "F.Paste")
			(net 570 "/FPGA Bank 12 & 13/USB_USER.VBUS_PEN")
			(pinfunction "IO_L9P_T1_DQS_13")
			(pintype "bidirectional")
			(die_length 18.051)
			(solder_mask_margin 0.02)
		)
		(pad "AD30" smd circle
			(at 14.5 8.5)
			(size 0.5 0.5)
			(property pad_prop_bga)
			(layers "F.Cu" "F.Mask" "F.Paste")
			(net 24 "+3V3")
			(pinfunction "VCCO_13")
			(pintype "passive")
			(solder_mask_margin 0.02)
		)
		(pad "AE1" smd circle
			(at -14.5 9.5)
			(size 0.5 0.5)
			(property pad_prop_bga)
			(layers "F.Cu" "F.Mask" "F.Paste")
			(net 535 "/DRAM + SRAM/DDR.A4")
			(pinfunction "IO_L8P_T1_34")
			(pintype "bidirectional")
			(die_length 19.484)
			(solder_mask_margin 0.02)
		)
		(pad "AE2" smd circle
			(at -13.5 9.5)
			(size 0.5 0.5)
			(property pad_prop_bga)
			(layers "F.Cu" "F.Mask" "F.Paste")
			(net 1 "GND")
			(pinfunction "GND")
			(pintype "passive")
			(solder_mask_margin 0.02)
		)
		(pad "AE3" smd circle
			(at -12.5 9.5)
			(size 0.5 0.5)
			(property pad_prop_bga)
			(layers "F.Cu" "F.Mask" "F.Paste")
			(net 549 "/DRAM + SRAM/DDR.BA2")
			(pinfunction "IO_L10N_T1_34")
			(pintype "bidirectional")
			(die_length 20.774)
			(solder_mask_margin 0.02)
		)
		(pad "AE4" smd circle
			(at -11.5 9.5)
			(size 0.5 0.5)
			(property pad_prop_bga)
			(layers "F.Cu" "F.Mask" "F.Paste")
			(net 531 "/DRAM + SRAM/DDR.A0")
			(pinfunction "IO_L10P_T1_34")
			(pintype "bidirectional")
			(die_length 20.074)
			(solder_mask_margin 0.02)
		)
		(pad "AE5" smd circle
			(at -10.5 9.5)
			(size 0.5 0.5)
			(property pad_prop_bga)
			(layers "F.Cu" "F.Mask" "F.Paste")
			(net 548 "/DRAM + SRAM/DDR.BA1")
			(pinfunction "IO_L11P_T1_SRCC_34")
			(pintype "bidirectional")
			(die_length 21.14)
			(solder_mask_margin 0.02)
		)
		(pad "AE6" smd circle
			(at -9.5 9.5)
			(size 0.5 0.5)
			(property pad_prop_bga)
			(layers "F.Cu" "F.Mask" "F.Paste")
			(net 539 "/DRAM + SRAM/DDR.A8")
			(pinfunction "IO_L5N_T0_34")
			(pintype "bidirectional")
			(die_length 19.788)
			(solder_mask_margin 0.02)
		)
		(pad "AE7" smd circle
			(at -8.5 9.5)
			(size 0.5 0.5)
			(property pad_prop_bga)
			(layers "F.Cu" "F.Mask" "F.Paste")
			(net 25 "+1V35")
			(pinfunction "VCCO_34")
			(pintype "passive")
			(solder_mask_margin 0.02)
		)
		(pad "AE8" smd circle
			(at -7.5 9.5)
			(size 0.5 0.5)
			(property pad_prop_bga)
			(layers "F.Cu" "F.Mask" "F.Paste")
			(net 421 "unconnected-(U1E-IO_L8N_T1_33-PadAE8)")
			(pinfunction "IO_L8N_T1_33")
			(pintype "bidirectional+no_connect")
			(die_length 15.592)
			(solder_mask_margin 0.02)
		)
		(pad "AE9" smd circle
			(at -6.5 9.5)
			(size 0.5 0.5)
			(property pad_prop_bga)
			(layers "F.Cu" "F.Mask" "F.Paste")
			(net 390 "/FPGA Bank 33 & 34/SD_CARD.DAT2")
			(pinfunction "IO_L10N_T1_33")
			(pintype "bidirectional")
			(die_length 16.427)
			(solder_mask_margin 0.02)
		)
		(pad "AE10" smd circle
			(at -5.5 9.5)
			(size 0.5 0.5)
			(property pad_prop_bga)
			(layers "F.Cu" "F.Mask" "F.Paste")
			(net 422 "unconnected-(U1E-IO_L14P_T2_SRCC_33-PadAE10)")
			(pinfunction "IO_L14P_T2_SRCC_33")
			(pintype "bidirectional+no_connect")
			(die_length 15.465)
			(solder_mask_margin 0.02)
		)
		(pad "AE11" smd circle
			(at -4.5 9.5)
			(size 0.5 0.5)
			(property pad_prop_bga)
			(layers "F.Cu" "F.Mask" "F.Paste")
			(net 425 "unconnected-(U1E-IO_L11P_T1_SRCC_33-PadAE11)")
			(pinfunction "IO_L11P_T1_SRCC_33")
			(pintype "bidirectional+no_connect")
			(die_length 18.396)
			(solder_mask_margin 0.02)
		)
		(pad "AE12" smd circle
			(at -3.5 9.5)
			(size 0.5 0.5)
			(property pad_prop_bga)
			(layers "F.Cu" "F.Mask" "F.Paste")
			(net 1 "GND")
			(pinfunction "GND")
			(pintype "passive")
			(solder_mask_margin 0.02)
		)
		(pad "AE13" smd circle
			(at -2.5 9.5)
			(size 0.5 0.5)
			(property pad_prop_bga)
			(layers "F.Cu" "F.Mask" "F.Paste")
			(net 416 "/FPGA Bank 33 & 34/SD_CARD.~{CD}")
			(pinfunction "IO_L19P_T3_33")
			(pintype "bidirectional")
			(die_length 19.974)
			(solder_mask_margin 0.02)
		)
		(pad "AE14" smd circle
			(at -1.5 9.5)
			(size 0.5 0.5)
			(property pad_prop_bga)
			(layers "F.Cu" "F.Mask" "F.Paste")
			(net 609 "unconnected-(U1D-IO_L19N_T3_VREF_32-PadAE14)")
			(pinfunction "IO_L19N_T3_VREF_32")
			(pintype "bidirectional+no_connect")
			(die_length 11.352)
			(solder_mask_margin 0.02)
		)
		(pad "AE15" smd circle
			(at -0.5 9.5)
			(size 0.5 0.5)
			(property pad_prop_bga)
			(layers "F.Cu" "F.Mask" "F.Paste")
			(net 610 "unconnected-(U1D-IO_L19P_T3_32-PadAE15)")
			(pinfunction "IO_L19P_T3_32")
			(pintype "bidirectional+no_connect")
			(die_length 14.144)
			(solder_mask_margin 0.02)
		)
		(pad "AE16" smd circle
			(at 0.5 9.5)
			(size 0.5 0.5)
			(property pad_prop_bga)
			(layers "F.Cu" "F.Mask" "F.Paste")
			(net 611 "unconnected-(U1D-IO_L6P_T0_32-PadAE16)")
			(pinfunction "IO_L6P_T0_32")
			(pintype "bidirectional+no_connect")
			(die_length 19.283)
			(solder_mask_margin 0.02)
		)
		(pad "AE17" smd circle
			(at 1.5 9.5)
			(size 0.5 0.5)
			(property pad_prop_bga)
			(layers "F.Cu" "F.Mask" "F.Paste")
			(net 26 "+1V8")
			(pinfunction "VCCO_32")
			(pintype "passive")
			(solder_mask_margin 0.02)
		)
		(pad "AE18" smd circle
			(at 2.5 9.5)
			(size 0.5 0.5)
			(property pad_prop_bga)
			(layers "F.Cu" "F.Mask" "F.Paste")
			(net 520 "/FPGA Bank 18 & 32/ETH_RMII.RXD1")
			(pinfunction "IO_L13N_T2_MRCC_32")
			(pintype "bidirectional")
			(die_length 22.208)
			(solder_mask_margin 0.02)
		)
		(pad "AE19" smd circle
			(at 3.5 9.5)
			(size 0.5 0.5)
			(property pad_prop_bga)
			(layers "F.Cu" "F.Mask" "F.Paste")
			(net 612 "unconnected-(U1D-IO_L10N_T1_32-PadAE19)")
			(pinfunction "IO_L10N_T1_32")
			(pintype "bidirectional+no_connect")
			(die_length 22.544)
			(solder_mask_margin 0.02)
		)
		(pad "AE20" smd circle
			(at 4.5 9.5)
			(size 0.5 0.5)
			(property pad_prop_bga)
			(layers "F.Cu" "F.Mask" "F.Paste")
			(net 474 "/FPGA Bank 12 & 13/CW_HEADER.RST")
			(pinfunction "IO_25_12")
			(pintype "bidirectional")
			(die_length 6.449)
			(solder_mask_margin 0.02)
		)
		(pad "AE21" smd circle
			(at 5.5 9.5)
			(size 0.5 0.5)
			(property pad_prop_bga)
			(layers "F.Cu" "F.Mask" "F.Paste")
			(net 1375 "/SUP_MCU.D7")
			(pinfunction "IO_L10N_T1_12")
			(pintype "bidirectional")
			(die_length 10.51)
			(solder_mask_margin 0.02)
		)
		(pad "AE22" smd circle
			(at 6.5 9.5)
			(size 0.5 0.5)
			(property pad_prop_bga)
			(layers "F.Cu" "F.Mask" "F.Paste")
			(net 1 "GND")
			(pinfunction "GND")
			(pintype "passive")
			(solder_mask_margin 0.02)
		)
		(pad "AE23" smd circle
			(at 7.5 9.5)
			(size 0.5 0.5)
			(property pad_prop_bga)
			(layers "F.Cu" "F.Mask" "F.Paste")
			(net 1376 "/SUP_MCU.CE")
			(pinfunction "IO_L11P_T1_SRCC_12")
			(pintype "bidirectional")
			(die_length 10.622)
			(solder_mask_margin 0.02)
		)
		(pad "AE24" smd circle
			(at 8.5 9.5)
			(size 0.5 0.5)
			(property pad_prop_bga)
			(layers "F.Cu" "F.Mask" "F.Paste")
			(net 1329 "/SUP_MCU.TX0")
			(pinfunction "IO_L12N_T1_MRCC_12")
			(pintype "bidirectional")
			(die_length 9.679)
			(solder_mask_margin 0.02)
		)
		(pad "AE25" smd circle
			(at 9.5 9.5)
			(size 0.5 0.5)
			(property pad_prop_bga)
			(layers "F.Cu" "F.Mask" "F.Paste")
			(net 1354 "/SUP_MCU.A7")
			(pinfunction "IO_L16P_T2_12")
			(pintype "bidirectional")
			(die_length 16.226)
			(solder_mask_margin 0.02)
		)
		(pad "AE26" smd circle
			(at 10.5 9.5)
			(size 0.5 0.5)
			(property pad_prop_bga)
			(layers "F.Cu" "F.Mask" "F.Paste")
			(net 432 "/FPGA Bank 12 & 13/FAN_PWM_CTRL")
			(pinfunction "IO_25_13")
			(pintype "bidirectional")
			(die_length 12.263)
			(solder_mask_margin 0.02)
		)
		(pad "AE27" smd circle
			(at 11.5 9.5)
			(size 0.5 0.5)
			(property pad_prop_bga)
			(layers "F.Cu" "F.Mask" "F.Paste")
			(net 24 "+3V3")
			(pinfunction "VCCO_13")
			(pintype "passive")
			(solder_mask_margin 0.02)
		)
		(pad "AE28" smd circle
			(at 12.5 9.5)
			(size 0.5 0.5)
			(property pad_prop_bga)
			(layers "F.Cu" "F.Mask" "F.Paste")
			(net 1403 "/PLL.CLK1")
			(pinfunction "IO_L14P_T2_SRCC_13")
			(pintype "bidirectional")
			(die_length 19.231)
			(solder_mask_margin 0.02)
		)
		(pad "AE29" smd circle
			(at 13.5 9.5)
			(size 0.5 0.5)
			(property pad_prop_bga)
			(layers "F.Cu" "F.Mask" "F.Paste")
			(net 613 "unconnected-(U1A-IO_L9N_T1_DQS_13-PadAE29)")
			(pinfunction "IO_L9N_T1_DQS_13")
			(pintype "bidirectional+no_connect")
			(die_length 18.383)
			(solder_mask_margin 0.02)
		)
		(pad "AE30" smd circle
			(at 14.5 9.5)
			(size 0.5 0.5)
			(property pad_prop_bga)
			(layers "F.Cu" "F.Mask" "F.Paste")
			(net 614 "unconnected-(U1A-IO_L16P_T2_13-PadAE30)")
			(pinfunction "IO_L16P_T2_13")
			(pintype "bidirectional+no_connect")
			(die_length 20.537)
			(solder_mask_margin 0.02)
		)
		(pad "AF1" smd circle
			(at -14.5 10.5)
			(size 0.5 0.5)
			(property pad_prop_bga)
			(layers "F.Cu" "F.Mask" "F.Paste")
			(net 534 "/DRAM + SRAM/DDR.A3")
			(pinfunction "IO_L8N_T1_34")
			(pintype "bidirectional")
			(die_length 20.617)
			(solder_mask_margin 0.02)
		)
		(pad "AF2" smd circle
			(at -13.5 10.5)
			(size 0.5 0.5)
			(property pad_prop_bga)
			(layers "F.Cu" "F.Mask" "F.Paste")
			(net 536 "/DRAM + SRAM/DDR.A5")
			(pinfunction "IO_L7N_T1_34")
			(pintype "bidirectional")
			(die_length 21.199)
			(solder_mask_margin 0.02)
		)
		(pad "AF3" smd circle
			(at -12.5 10.5)
			(size 0.5 0.5)
			(property pad_prop_bga)
			(layers "F.Cu" "F.Mask" "F.Paste")
			(net 537 "/DRAM + SRAM/DDR.A6")
			(pinfunction "IO_L7P_T1_34")
			(pintype "bidirectional")
			(die_length 20.914)
			(solder_mask_margin 0.02)
		)
		(pad "AF4" smd circle
			(at -11.5 10.5)
			(size 0.5 0.5)
			(property pad_prop_bga)
			(layers "F.Cu" "F.Mask" "F.Paste")
			(net 25 "+1V35")
			(pinfunction "VCCO_34")
			(pintype "passive")
			(solder_mask_margin 0.02)
		)
		(pad "AF5" smd circle
			(at -10.5 10.5)
			(size 0.5 0.5)
			(property pad_prop_bga)
			(layers "F.Cu" "F.Mask" "F.Paste")
			(net 547 "/DRAM + SRAM/DDR.BA0")
			(pinfunction "IO_L11N_T1_SRCC_34")
			(pintype "bidirectional")
			(die_length 21.528)
			(solder_mask_margin 0.02)
		)
		(pad "AF6" smd circle
			(at -9.5 10.5)
			(size 0.5 0.5)
			(property pad_prop_bga)
			(layers "F.Cu" "F.Mask" "F.Paste")
			(net 559 "/DRAM + SRAM/DDR.~{CAS}")
			(pinfunction "IO_L12P_T1_MRCC_34")
			(pintype "bidirectional")
			(die_length 20.428)
			(solder_mask_margin 0.02)
		)
		(pad "AF7" smd circle
			(at -8.5 10.5)
			(size 0.5 0.5)
			(property pad_prop_bga)
			(layers "F.Cu" "F.Mask" "F.Paste")
			(net 654 "/DRAM + SRAM/DDR.DQ7")
			(pinfunction "IO_L20P_T3_34")
			(pintype "bidirectional")
			(die_length 21.476)
			(solder_mask_margin 0.02)
		)
		(pad "AF8" smd circle
			(at -7.5 10.5)
			(size 0.5 0.5)
			(property pad_prop_bga)
			(layers "F.Cu" "F.Mask" "F.Paste")
			(net 557 "/DRAM + SRAM/DDR.DM")
			(pinfunction "IO_L19P_T3_34")
			(pintype "bidirectional")
			(die_length 18.874)
			(solder_mask_margin 0.02)
		)
		(pad "AF9" smd circle
			(at -6.5 10.5)
			(size 0.5 0.5)
			(property pad_prop_bga)
			(layers "F.Cu" "F.Mask" "F.Paste")
			(net 1 "GND")
			(pinfunction "GND")
			(pintype "passive")
			(solder_mask_margin 0.02)
		)
		(pad "AF10" smd circle
			(at -5.5 10.5)
			(size 0.5 0.5)
			(property pad_prop_bga)
			(layers "F.Cu" "F.Mask" "F.Paste")
			(net 435 "unconnected-(U1E-IO_L14N_T2_SRCC_33-PadAF10)")
			(pinfunction "IO_L14N_T2_SRCC_33")
			(pintype "bidirectional+no_connect")
			(die_length 15.658)
			(solder_mask_margin 0.02)
		)
		(pad "AF11" smd circle
			(at -4.5 10.5)
			(size 0.5 0.5)
			(property pad_prop_bga)
			(layers "F.Cu" "F.Mask" "F.Paste")
			(net 397 "/FPGA Bank 33 & 34/SD_CARD.DAT1")
			(pinfunction "IO_L11N_T1_SRCC_33")
			(pintype "bidirectional")
			(die_length 18.351)
			(solder_mask_margin 0.02)
		)
		(pad "AF12" smd circle
			(at -3.5 10.5)
			(size 0.5 0.5)
			(property pad_prop_bga)
			(layers "F.Cu" "F.Mask" "F.Paste")
			(net 436 "unconnected-(U1E-IO_L23P_T3_33-PadAF12)")
			(pinfunction "IO_L23P_T3_33")
			(pintype "bidirectional+no_connect")
			(die_length 20.111)
			(solder_mask_margin 0.02)
		)
		(pad "AF13" smd circle
			(at -2.5 10.5)
			(size 0.5 0.5)
			(property pad_prop_bga)
			(layers "F.Cu" "F.Mask" "F.Paste")
			(net 407 "/FPGA Bank 33 & 34/USR_FLASH_0.~{CS}")
			(pinfunction "IO_L19N_T3_VREF_33")
			(pintype "bidirectional")
			(die_length 19.268)
			(solder_mask_margin 0.02)
		)
		(pad "AF14" smd circle
			(at -1.5 10.5)
			(size 0.5 0.5)
			(property pad_prop_bga)
			(layers "F.Cu" "F.Mask" "F.Paste")
			(net 26 "+1V8")
			(pinfunction "VCCO_32")
			(pintype "passive")
			(solder_mask_margin 0.02)
		)
		(pad "AF15" smd circle
			(at -0.5 10.5)
			(size 0.5 0.5)
			(property pad_prop_bga)
			(layers "F.Cu" "F.Mask" "F.Paste")
			(net 615 "unconnected-(U1D-IO_L4P_T0_32-PadAF15)")
			(pinfunction "IO_L4P_T0_32")
			(pintype "bidirectional+no_connect")
			(die_length 18.766)
			(solder_mask_margin 0.02)
		)
		(pad "AF16" smd circle
			(at 0.5 10.5)
			(size 0.5 0.5)
			(property pad_prop_bga)
			(layers "F.Cu" "F.Mask" "F.Paste")
			(net 616 "/FPGA Bank 12 & 13/USB_USER.SPD")
			(pinfunction "IO_L6N_T0_VREF_32")
			(pintype "bidirectional")
			(die_length 17.245)
			(solder_mask_margin 0.02)
		)
		(pad "AF17" smd circle
			(at 1.5 10.5)
			(size 0.5 0.5)
			(property pad_prop_bga)
			(layers "F.Cu" "F.Mask" "F.Paste")
			(net 617 "unconnected-(U1D-IO_L12P_T1_MRCC_32-PadAF17)")
			(pinfunction "IO_L12P_T1_MRCC_32")
			(pintype "bidirectional+no_connect")
			(die_length 19.799)
			(solder_mask_margin 0.02)
		)
		(pad "AF18" smd circle
			(at 2.5 10.5)
			(size 0.5 0.5)
			(property pad_prop_bga)
			(layers "F.Cu" "F.Mask" "F.Paste")
			(net 517 "/FPGA Bank 18 & 32/ETH_RMII.RX_DV")
			(pinfunction "IO_L11P_T1_SRCC_32")
			(pintype "bidirectional")
			(die_length 20.405)
			(solder_mask_margin 0.02)
		)
		(pad "AF19" smd circle
			(at 3.5 10.5)
			(size 0.5 0.5)
			(property pad_prop_bga)
			(layers "F.Cu" "F.Mask" "F.Paste")
			(net 1 "GND")
			(pinfunction "GND")
			(pintype "passive")
			(solder_mask_margin 0.02)
		)
		(pad "AF20" smd circle
			(at 4.5 10.5)
			(size 0.5 0.5)
			(property pad_prop_bga)
			(layers "F.Cu" "F.Mask" "F.Paste")
			(net 480 "/FPGA Bank 12 & 13/CW_HEADER.TPDIC")
			(pinfunction "IO_L19P_T3_12")
			(pintype "bidirectional")
			(die_length 9.781)
			(solder_mask_margin 0.02)
		)
		(pad "AF21" smd circle
			(at 5.5 10.5)
			(size 0.5 0.5)
			(property pad_prop_bga)
			(layers "F.Cu" "F.Mask" "F.Paste")
			(net 475 "/FPGA Bank 12 & 13/CW_HEADER.MISO")
			(pinfunction "IO_L19N_T3_VREF_12")
			(pintype "bidirectional")
			(die_length 10.006)
			(solder_mask_margin 0.02)
		)
		(pad "AF22" smd circle
			(at 6.5 10.5)
			(size 0.5 0.5)
			(property pad_prop_bga)
			(layers "F.Cu" "F.Mask" "F.Paste")
			(net 488 "/FPGA Bank 12 & 13/CW_HEADER.HS2")
			(pinfunction "IO_L13P_T2_MRCC_12")
			(pintype "bidirectional")
			(die_length 11.098)
			(solder_mask_margin 0.02)
		)
		(pad "AF23" smd circle
			(at 7.5 10.5)
			(size 0.5 0.5)
			(property pad_prop_bga)
			(layers "F.Cu" "F.Mask" "F.Paste")
			(net 1361 "/SUP_MCU.A4")
			(pinfunction "IO_L11N_T1_SRCC_12")
			(pintype "bidirectional")
			(die_length 10.641)
			(solder_mask_margin 0.02)
		)
		(pad "AF24" smd circle
			(at 8.5 10.5)
			(size 0.5 0.5)
			(property pad_prop_bga)
			(layers "F.Cu" "F.Mask" "F.Paste")
			(net 24 "+3V3")
			(pinfunction "VCCO_12")
			(pintype "passive")
			(solder_mask_margin 0.02)
		)
		(pad "AF25" smd circle
			(at 9.5 10.5)
			(size 0.5 0.5)
			(property pad_prop_bga)
			(layers "F.Cu" "F.Mask" "F.Paste")
			(net 1362 "/SUP_MCU.A6")
			(pinfunction "IO_L16N_T2_12")
			(pintype "bidirectional")
			(die_length 14.464)
			(solder_mask_margin 0.02)
		)
		(pad "AF26" smd circle
			(at 10.5 10.5)
			(size 0.5 0.5)
			(property pad_prop_bga)
			(layers "F.Cu" "F.Mask" "F.Paste")
			(net 571 "/FPGA Bank 12 & 13/~{PB_CTRL_CLR}")
			(pinfunction "IO_L23P_T3_13")
			(pintype "bidirectional")
			(die_length 15.71)
			(solder_mask_margin 0.02)
		)
		(pad "AF27" smd circle
			(at 11.5 10.5)
			(size 0.5 0.5)
			(property pad_prop_bga)
			(layers "F.Cu" "F.Mask" "F.Paste")
			(net 572 "/FPGA Bank 12 & 13/~{PB_CTRL_INT}")
			(pinfunction "IO_L23N_T3_13")
			(pintype "bidirectional")
			(die_length 16.589)
			(solder_mask_margin 0.02)
		)
		(pad "AF28" smd circle
			(at 12.5 10.5)
			(size 0.5 0.5)
			(property pad_prop_bga)
			(layers "F.Cu" "F.Mask" "F.Paste")
			(net 458 "/FPGA Bank 12 & 13/PMOD_A.IO3")
			(pinfunction "IO_L14N_T2_SRCC_13")
			(pintype "bidirectional")
			(die_length 18.857)
			(solder_mask_margin 0.02)
		)
		(pad "AF29" smd circle
			(at 13.5 10.5)
			(size 0.5 0.5)
			(property pad_prop_bga)
			(layers "F.Cu" "F.Mask" "F.Paste")
			(net 1 "GND")
			(pinfunction "GND")
			(pintype "passive")
			(solder_mask_margin 0.02)
		)
		(pad "AF30" smd circle
			(at 14.5 10.5)
			(size 0.5 0.5)
			(property pad_prop_bga)
			(layers "F.Cu" "F.Mask" "F.Paste")
			(net 618 "unconnected-(U1A-IO_L16N_T2_13-PadAF30)")
			(pinfunction "IO_L16N_T2_13")
			(pintype "bidirectional+no_connect")
			(die_length 19.947)
			(solder_mask_margin 0.02)
		)
		(pad "AG1" smd circle
			(at -14.5 11.5)
			(size 0.5 0.5)
			(property pad_prop_bga)
			(layers "F.Cu" "F.Mask" "F.Paste")
			(net 25 "+1V35")
			(pinfunction "VCCO_34")
			(pintype "passive")
			(solder_mask_margin 0.02)
		)
		(pad "AG2" smd circle
			(at -13.5 11.5)
			(size 0.5 0.5)
			(property pad_prop_bga)
			(layers "F.Cu" "F.Mask" "F.Paste")
			(net 558 "/DRAM + SRAM/DDR.~{WE}")
			(pinfunction "IO_L15P_T2_DQS_34")
			(pintype "bidirectional")
			(die_length 22.704)
			(solder_mask_margin 0.02)
		)
		(pad "AG3" smd circle
			(at -12.5 11.5)
			(size 0.5 0.5)
			(property pad_prop_bga)
			(layers "F.Cu" "F.Mask" "F.Paste")
			(net 532 "/DRAM + SRAM/DDR.A1")
			(pinfunction "IO_L9N_T1_DQS_34")
			(pintype "bidirectional")
			(die_length 23.545)
			(solder_mask_margin 0.02)
		)
		(pad "AG4" smd circle
			(at -11.5 11.5)
			(size 0.5 0.5)
			(property pad_prop_bga)
			(layers "F.Cu" "F.Mask" "F.Paste")
			(net 533 "/DRAM + SRAM/DDR.A2")
			(pinfunction "IO_L9P_T1_DQS_34")
			(pintype "bidirectional")
			(die_length 23.769)
			(solder_mask_margin 0.02)
		)
		(pad "AG5" smd circle
			(at -10.5 11.5)
			(size 0.5 0.5)
			(property pad_prop_bga)
			(layers "F.Cu" "F.Mask" "F.Paste")
			(net 560 "/DRAM + SRAM/DDR.~{RAS}")
			(pinfunction "IO_L12N_T1_MRCC_34")
			(pintype "bidirectional")
			(die_length 20.454)
			(solder_mask_margin 0.02)
		)
		(pad "AG6" smd circle
			(at -9.5 11.5)
			(size 0.5 0.5)
			(property pad_prop_bga)
			(layers "F.Cu" "F.Mask" "F.Paste")
			(net 1 "GND")
			(pinfunction "GND")
			(pintype "passive")
			(solder_mask_margin 0.02)
		)
		(pad "AG7" smd circle
			(at -8.5 11.5)
			(size 0.5 0.5)
			(property pad_prop_bga)
			(layers "F.Cu" "F.Mask" "F.Paste")
			(net 655 "/DRAM + SRAM/DDR.DQ4")
			(pinfunction "IO_L20N_T3_34")
			(pintype "bidirectional")
			(die_length 21.497)
			(solder_mask_margin 0.02)
		)
		(pad "AG8" smd circle
			(at -7.5 11.5)
			(size 0.5 0.5)
			(property pad_prop_bga)
			(layers "F.Cu" "F.Mask" "F.Paste")
			(net 11 "+0V675_VREF")
			(pinfunction "IO_L19N_T3_VREF_34")
			(pintype "bidirectional")
			(die_length 15.362)
			(solder_mask_margin 0.02)
		)
		(pad "AG9" smd circle
			(at -6.5 11.5)
			(size 0.5 0.5)
			(property pad_prop_bga)
			(layers "F.Cu" "F.Mask" "F.Paste")
			(net 443 "unconnected-(U1E-IO_L16P_T2_33-PadAG9)")
			(pinfunction "IO_L16P_T2_33")
			(pintype "bidirectional+no_connect")
			(die_length 15.472)
			(solder_mask_margin 0.02)
		)
		(pad "AG10" smd circle
			(at -5.5 11.5)
			(size 0.5 0.5)
			(property pad_prop_bga)
			(layers "F.Cu" "F.Mask" "F.Paste")
			(net 447 "unconnected-(U1E-IO_L13P_T2_MRCC_33-PadAG10)")
			(pinfunction "IO_L13P_T2_MRCC_33")
			(pintype "bidirectional+no_connect")
			(die_length 19.427)
			(solder_mask_margin 0.02)
		)
		(pad "AG11" smd circle
			(at -4.5 11.5)
			(size 0.5 0.5)
			(property pad_prop_bga)
			(layers "F.Cu" "F.Mask" "F.Paste")
			(net 26 "+1V8")
			(pinfunction "VCCO_33")
			(pintype "passive")
			(solder_mask_margin 0.02)
		)
		(pad "AG12" smd circle
			(at -3.5 11.5)
			(size 0.5 0.5)
			(property pad_prop_bga)
			(layers "F.Cu" "F.Mask" "F.Paste")
			(net 448 "unconnected-(U1E-IO_L23N_T3_33-PadAG12)")
			(pinfunction "IO_L23N_T3_33")
			(pintype "bidirectional+no_connect")
			(die_length 20.042)
			(solder_mask_margin 0.02)
		)
		(pad "AG13" smd circle
			(at -2.5 11.5)
			(size 0.5 0.5)
			(property pad_prop_bga)
			(layers "F.Cu" "F.Mask" "F.Paste")
			(net 402 "/FPGA Bank 33 & 34/USR_FLASH_0.DQ3")
			(pinfunction "IO_L24P_T3_33")
			(pintype "bidirectional")
			(die_length 20.152)
			(solder_mask_margin 0.02)
		)
		(pad "AG14" smd circle
			(at -1.5 11.5)
			(size 0.5 0.5)
			(property pad_prop_bga)
			(layers "F.Cu" "F.Mask" "F.Paste")
			(net 498 "/FPGA Bank 12 & 13/USB_USER.~{OE}")
			(pinfunction "IO_L4N_T0_32")
			(pintype "bidirectional")
			(die_length 19.861)
			(solder_mask_margin 0.02)
		)
		(pad "AG15" smd circle
			(at -0.5 11.5)
			(size 0.5 0.5)
			(property pad_prop_bga)
			(layers "F.Cu" "F.Mask" "F.Paste")
			(net 619 "/FPGA Bank 12 & 13/USB_USER.SCON")
			(pinfunction "IO_L2P_T0_32")
			(pintype "bidirectional")
			(die_length 19.43)
			(solder_mask_margin 0.02)
		)
		(pad "AG16" smd circle
			(at 0.5 11.5)
			(size 0.5 0.5)
			(property pad_prop_bga)
			(layers "F.Cu" "F.Mask" "F.Paste")
			(net 1 "GND")
			(pinfunction "GND")
			(pintype "passive")
			(solder_mask_margin 0.02)
		)
		(pad "AG17" smd circle
			(at 1.5 11.5)
			(size 0.5 0.5)
			(property pad_prop_bga)
			(layers "F.Cu" "F.Mask" "F.Paste")
			(net 620 "unconnected-(U1D-IO_L12N_T1_MRCC_32-PadAG17)")
			(pinfunction "IO_L12N_T1_MRCC_32")
			(pintype "bidirectional+no_connect")
			(die_length 19.963)
			(solder_mask_margin 0.02)
		)
		(pad "AG18" smd circle
			(at 2.5 11.5)
			(size 0.5 0.5)
			(property pad_prop_bga)
			(layers "F.Cu" "F.Mask" "F.Paste")
			(net 621 "unconnected-(U1D-IO_L11N_T1_SRCC_32-PadAG18)")
			(pinfunction "IO_L11N_T1_SRCC_32")
			(pintype "bidirectional+no_connect")
			(die_length 20.178)
			(solder_mask_margin 0.02)
		)
		(pad "AG19" smd circle
			(at 3.5 11.5)
			(size 0.5 0.5)
			(property pad_prop_bga)
			(layers "F.Cu" "F.Mask" "F.Paste")
			(net 626 "unconnected-(U1D-IO_L8P_T1_32-PadAG19)")
			(pinfunction "IO_L8P_T1_32")
			(pintype "bidirectional+no_connect")
			(die_length 22.281)
			(solder_mask_margin 0.02)
		)
		(pad "AG20" smd circle
			(at 4.5 11.5)
			(size 0.5 0.5)
			(property pad_prop_bga)
			(layers "F.Cu" "F.Mask" "F.Paste")
			(net 485 "/FPGA Bank 12 & 13/CW_HEADER.TPDID")
			(pinfunction "IO_L22P_T3_12")
			(pintype "bidirectional")
			(die_length 10.048)
			(solder_mask_margin 0.02)
		)
		(pad "AG21" smd circle
			(at 5.5 11.5)
			(size 0.5 0.5)
			(property pad_prop_bga)
			(layers "F.Cu" "F.Mask" "F.Paste")
			(net 24 "+3V3")
			(pinfunction "VCCO_12")
			(pintype "passive")
			(solder_mask_margin 0.02)
		)
		(pad "AG22" smd circle
			(at 6.5 11.5)
			(size 0.5 0.5)
			(property pad_prop_bga)
			(layers "F.Cu" "F.Mask" "F.Paste")
			(net 493 "/FPGA Bank 12 & 13/CW_HEADER.IO4")
			(pinfunction "IO_L20P_T3_12")
			(pintype "bidirectional")
			(die_length 9.529)
			(solder_mask_margin 0.02)
		)
		(pad "AG23" smd circle
			(at 7.5 11.5)
			(size 0.5 0.5)
			(property pad_prop_bga)
			(layers "F.Cu" "F.Mask" "F.Paste")
			(net 1330 "/SUP_MCU.RX1")
			(pinfunction "IO_L13N_T2_MRCC_12")
			(pintype "bidirectional")
			(die_length 11.265)
			(solder_mask_margin 0.02)
		)
		(pad "AG24" smd circle
			(at 8.5 11.5)
			(size 0.5 0.5)
			(property pad_prop_bga)
			(layers "F.Cu" "F.Mask" "F.Paste")
			(net 1390 "/SUP_MCU.RD")
			(pinfunction "IO_L14P_T2_SRCC_12")
			(pintype "bidirectional")
			(die_length 11.801)
			(solder_mask_margin 0.02)
		)
		(pad "AG25" smd circle
			(at 9.5 11.5)
			(size 0.5 0.5)
			(property pad_prop_bga)
			(layers "F.Cu" "F.Mask" "F.Paste")
			(net 487 "/FPGA Bank 12 & 13/CW_HEADER.HS1")
			(pinfunction "IO_L18P_T2_12")
			(pintype "bidirectional")
			(die_length 14.835)
			(solder_mask_margin 0.02)
		)
		(pad "AG26" smd circle
			(at 10.5 11.5)
			(size 0.5 0.5)
			(property pad_prop_bga)
			(layers "F.Cu" "F.Mask" "F.Paste")
			(net 1 "GND")
			(pinfunction "GND")
			(pintype "passive")
			(solder_mask_margin 0.02)
		)
		(pad "AG27" smd circle
			(at 11.5 11.5)
			(size 0.5 0.5)
			(property pad_prop_bga)
			(layers "F.Cu" "F.Mask" "F.Paste")
			(net 569 "/FPGA Bank 12 & 13/USB_HOST.VBUS_PEN")
			(pinfunction "IO_L21P_T3_DQS_13")
			(pintype "bidirectional")
			(die_length 17.137)
			(solder_mask_margin 0.02)
		)
		(pad "AG28" smd circle
			(at 12.5 11.5)
			(size 0.5 0.5)
			(property pad_prop_bga)
			(layers "F.Cu" "F.Mask" "F.Paste")
			(net 631 "unconnected-(U1A-IO_L21N_T3_DQS_13-PadAG28)")
			(pinfunction "IO_L21N_T3_DQS_13")
			(pintype "bidirectional+no_connect")
			(die_length 16.984)
			(solder_mask_margin 0.02)
		)
		(pad "AG29" smd circle
			(at 13.5 11.5)
			(size 0.5 0.5)
			(property pad_prop_bga)
			(layers "F.Cu" "F.Mask" "F.Paste")
			(net 632 "unconnected-(U1A-IO_L13P_T2_MRCC_13-PadAG29)")
			(pinfunction "IO_L13P_T2_MRCC_13")
			(pintype "bidirectional+no_connect")
			(die_length 18.893)
			(solder_mask_margin 0.02)
		)
		(pad "AG30" smd circle
			(at 14.5 11.5)
			(size 0.5 0.5)
			(property pad_prop_bga)
			(layers "F.Cu" "F.Mask" "F.Paste")
			(net 633 "unconnected-(U1A-IO_L18P_T2_13-PadAG30)")
			(pinfunction "IO_L18P_T2_13")
			(pintype "bidirectional+no_connect")
			(die_length 20.457)
			(solder_mask_margin 0.02)
		)
		(pad "AH1" smd circle
			(at -14.5 12.5)
			(size 0.5 0.5)
			(property pad_prop_bga)
			(layers "F.Cu" "F.Mask" "F.Paste")
			(net 561 "/DRAM + SRAM/DDR.~{CS}")
			(pinfunction "IO_L15N_T2_DQS_34")
			(pintype "bidirectional")
			(die_length 22.335)
			(solder_mask_margin 0.02)
		)
		(pad "AH2" smd circle
			(at -13.5 12.5)
			(size 0.5 0.5)
			(property pad_prop_bga)
			(layers "F.Cu" "F.Mask" "F.Paste")
			(net 550 "/DRAM + SRAM/DDR.CKE")
			(pinfunction "IO_L16P_T2_34")
			(pintype "bidirectional")
			(die_length 23.594)
			(solder_mask_margin 0.02)
		)
		(pad "AH3" smd circle
			(at -12.5 12.5)
			(size 0.5 0.5)
			(property pad_prop_bga)
			(layers "F.Cu" "F.Mask" "F.Paste")
			(net 1 "GND")
			(pinfunction "GND")
			(pintype "passive")
			(solder_mask_margin 0.02)
		)
		(pad "AH4" smd circle
			(at -11.5 12.5)
			(size 0.5 0.5)
			(property pad_prop_bga)
			(layers "F.Cu" "F.Mask" "F.Paste")
			(net 554 "/DRAM + SRAM/DDR.~{RESET}")
			(pinfunction "IO_L13P_T2_MRCC_34")
			(pintype "bidirectional")
			(die_length 21.051)
			(solder_mask_margin 0.02)
		)
		(pad "AH5" smd circle
			(at -10.5 12.5)
			(size 0.5 0.5)
			(property pad_prop_bga)
			(layers "F.Cu" "F.Mask" "F.Paste")
			(net 635 "unconnected-(U1E-IO_L14N_T2_SRCC_34-PadAH5)")
			(pinfunction "IO_L14N_T2_SRCC_34")
			(pintype "bidirectional+no_connect")
			(die_length 23.368)
			(solder_mask_margin 0.02)
		)
		(pad "AH6" smd circle
			(at -9.5 12.5)
			(size 0.5 0.5)
			(property pad_prop_bga)
			(layers "F.Cu" "F.Mask" "F.Paste")
			(net 636 "unconnected-(U1E-IO_L14P_T2_SRCC_34-PadAH6)")
			(pinfunction "IO_L14P_T2_SRCC_34")
			(pintype "bidirectional+no_connect")
			(die_length 23.691)
			(solder_mask_margin 0.02)
		)
		(pad "AH7" smd circle
			(at -8.5 12.5)
			(size 0.5 0.5)
			(property pad_prop_bga)
			(layers "F.Cu" "F.Mask" "F.Paste")
			(net 656 "/DRAM + SRAM/DDR.DQS_P")
			(pinfunction "IO_L21P_T3_DQS_34")
			(pintype "bidirectional")
			(die_length 20.353)
			(solder_mask_margin 0.02)
		)
		(pad "AH8" smd circle
			(at -7.5 12.5)
			(size 0.5 0.5)
			(property pad_prop_bga)
			(layers "F.Cu" "F.Mask" "F.Paste")
			(net 25 "+1V35")
			(pinfunction "VCCO_34")
			(pintype "passive")
			(solder_mask_margin 0.02)
		)
		(pad "AH9" smd circle
			(at -6.5 12.5)
			(size 0.5 0.5)
			(property pad_prop_bga)
			(layers "F.Cu" "F.Mask" "F.Paste")
			(net 465 "unconnected-(U1E-IO_L16N_T2_33-PadAH9)")
			(pinfunction "IO_L16N_T2_33")
			(pintype "bidirectional+no_connect")
			(die_length 15.598)
			(solder_mask_margin 0.02)
		)
		(pad "AH10" smd circle
			(at -5.5 12.5)
			(size 0.5 0.5)
			(property pad_prop_bga)
			(layers "F.Cu" "F.Mask" "F.Paste")
			(net 466 "unconnected-(U1E-IO_L13N_T2_MRCC_33-PadAH10)")
			(pinfunction "IO_L13N_T2_MRCC_33")
			(pintype "bidirectional+no_connect")
			(die_length 19.153)
			(solder_mask_margin 0.02)
		)
		(pad "AH11" smd circle
			(at -4.5 12.5)
			(size 0.5 0.5)
			(property pad_prop_bga)
			(layers "F.Cu" "F.Mask" "F.Paste")
			(net 467 "unconnected-(U1E-IO_L18P_T2_33-PadAH11)")
			(pinfunction "IO_L18P_T2_33")
			(pintype "bidirectional+no_connect")
			(die_length 17.477)
			(solder_mask_margin 0.02)
		)
		(pad "AH12" smd circle
			(at -3.5 12.5)
			(size 0.5 0.5)
			(property pad_prop_bga)
			(layers "F.Cu" "F.Mask" "F.Paste")
			(net 404 "/FPGA Bank 33 & 34/USR_FLASH_0.DQ2")
			(pinfunction "IO_L24N_T3_33")
			(pintype "bidirectional")
			(die_length 19.902)
			(solder_mask_margin 0.02)
		)
		(pad "AH13" smd circle
			(at -2.5 12.5)
			(size 0.5 0.5)
			(property pad_prop_bga)
			(layers "F.Cu" "F.Mask" "F.Paste")
			(net 1 "GND")
			(pinfunction "GND")
			(pintype "passive")
			(solder_mask_margin 0.02)
		)
		(pad "AH14" smd circle
			(at -1.5 12.5)
			(size 0.5 0.5)
			(property pad_prop_bga)
			(layers "F.Cu" "F.Mask" "F.Paste")
			(net 469 "unconnected-(U1E-IO_L21P_T3_DQS_33-PadAH14)")
			(pinfunction "IO_L21P_T3_DQS_33")
			(pintype "bidirectional+no_connect")
			(die_length 23.831)
			(solder_mask_margin 0.02)
		)
		(pad "AH15" smd circle
			(at -0.5 12.5)
			(size 0.5 0.5)
			(property pad_prop_bga)
			(layers "F.Cu" "F.Mask" "F.Paste")
			(net 500 "/FPGA Bank 12 & 13/USB_USER.SUS")
			(pinfunction "IO_L2N_T0_32")
			(pintype "bidirectional")
			(die_length 20.849)
			(solder_mask_margin 0.02)
		)
		(pad "AH16" smd circle
			(at 0.5 12.5)
			(size 0.5 0.5)
			(property pad_prop_bga)
			(layers "F.Cu" "F.Mask" "F.Paste")
			(net 638 "unconnected-(U1D-IO_L3P_T0_DQS_32-PadAH16)")
			(pinfunction "IO_L3P_T0_DQS_32")
			(pintype "bidirectional+no_connect")
			(die_length 20.668)
			(solder_mask_margin 0.02)
		)
		(pad "AH17" smd circle
			(at 1.5 12.5)
			(size 0.5 0.5)
			(property pad_prop_bga)
			(layers "F.Cu" "F.Mask" "F.Paste")
			(net 639 "/FPGA Bank 12 & 13/USB_USER.VPO")
			(pinfunction "IO_L5P_T0_32")
			(pintype "bidirectional")
			(die_length 20.893)
			(solder_mask_margin 0.02)
		)
		(pad "AH18" smd circle
			(at 2.5 12.5)
			(size 0.5 0.5)
			(property pad_prop_bga)
			(layers "F.Cu" "F.Mask" "F.Paste")
			(net 26 "+1V8")
			(pinfunction "VCCO_32")
			(pintype "passive")
			(solder_mask_margin 0.02)
		)
		(pad "AH19" smd circle
			(at 3.5 12.5)
			(size 0.5 0.5)
			(property pad_prop_bga)
			(layers "F.Cu" "F.Mask" "F.Paste")
			(net 644 "unconnected-(U1D-IO_L8N_T1_32-PadAH19)")
			(pinfunction "IO_L8N_T1_32")
			(pintype "bidirectional+no_connect")
			(die_length 24.8)
			(solder_mask_margin 0.02)
		)
		(pad "AH20" smd circle
			(at 4.5 12.5)
			(size 0.5 0.5)
			(property pad_prop_bga)
			(layers "F.Cu" "F.Mask" "F.Paste")
			(net 492 "/FPGA Bank 12 & 13/CW_HEADER.IO3")
			(pinfunction "IO_L22N_T3_12")
			(pintype "bidirectional")
			(die_length 10.515)
			(solder_mask_margin 0.02)
		)
		(pad "AH21" smd circle
			(at 5.5 12.5)
			(size 0.5 0.5)
			(property pad_prop_bga)
			(layers "F.Cu" "F.Mask" "F.Paste")
			(net 1358 "/SUP_MCU.A2")
			(pinfunction "IO_L23P_T3_12")
			(pintype "bidirectional")
			(die_length 12.587)
			(solder_mask_margin 0.02)
		)
		(pad "AH22" smd circle
			(at 6.5 12.5)
			(size 0.5 0.5)
			(property pad_prop_bga)
			(layers "F.Cu" "F.Mask" "F.Paste")
			(net 491 "/FPGA Bank 12 & 13/CW_HEADER.IO2")
			(pinfunction "IO_L20N_T3_12")
			(pintype "bidirectional")
			(die_length 9.887)
			(solder_mask_margin 0.02)
		)
		(pad "AH23" smd circle
			(at 7.5 12.5)
			(size 0.5 0.5)
			(property pad_prop_bga)
			(layers "F.Cu" "F.Mask" "F.Paste")
			(net 1 "GND")
			(pinfunction "GND")
			(pintype "passive")
			(solder_mask_margin 0.02)
		)
		(pad "AH24" smd circle
			(at 8.5 12.5)
			(size 0.5 0.5)
			(property pad_prop_bga)
			(layers "F.Cu" "F.Mask" "F.Paste")
			(net 1359 "/SUP_MCU.A5")
			(pinfunction "IO_L14N_T2_SRCC_12")
			(pintype "bidirectional")
			(die_length 11.774)
			(solder_mask_margin 0.02)
		)
		(pad "AH25" smd circle
			(at 9.5 12.5)
			(size 0.5 0.5)
			(property pad_prop_bga)
			(layers "F.Cu" "F.Mask" "F.Paste")
			(net 1379 "/SUP_MCU.D2")
			(pinfunction "IO_L18N_T2_12")
			(pintype "bidirectional")
			(die_length 13.379)
			(solder_mask_margin 0.02)
		)
		(pad "AH26" smd circle
			(at 10.5 12.5)
			(size 0.5 0.5)
			(property pad_prop_bga)
			(layers "F.Cu" "F.Mask" "F.Paste")
			(net 645 "unconnected-(U1A-IO_L22P_T3_13-PadAH26)")
			(pinfunction "IO_L22P_T3_13")
			(pintype "bidirectional+no_connect")
			(die_length 18.804)
			(solder_mask_margin 0.02)
		)
		(pad "AH27" smd circle
			(at 11.5 12.5)
			(size 0.5 0.5)
			(property pad_prop_bga)
			(layers "F.Cu" "F.Mask" "F.Paste")
			(net 1300 "/USER_IO.LED_GREEN1")
			(pinfunction "IO_L22N_T3_13")
			(pintype "bidirectional")
			(die_length 17.115)
			(solder_mask_margin 0.02)
		)
		(pad "AH28" smd circle
			(at 12.5 12.5)
			(size 0.5 0.5)
			(property pad_prop_bga)
			(layers "F.Cu" "F.Mask" "F.Paste")
			(net 24 "+3V3")
			(pinfunction "VCCO_13")
			(pintype "passive")
			(solder_mask_margin 0.02)
		)
		(pad "AH29" smd circle
			(at 13.5 12.5)
			(size 0.5 0.5)
			(property pad_prop_bga)
			(layers "F.Cu" "F.Mask" "F.Paste")
			(net 646 "unconnected-(U1A-IO_L13N_T2_MRCC_13-PadAH29)")
			(pinfunction "IO_L13N_T2_MRCC_13")
			(pintype "bidirectional+no_connect")
			(die_length 19.428)
			(solder_mask_margin 0.02)
		)
		(pad "AH30" smd circle
			(at 14.5 12.5)
			(size 0.5 0.5)
			(property pad_prop_bga)
			(layers "F.Cu" "F.Mask" "F.Paste")
			(net 647 "unconnected-(U1A-IO_L18N_T2_13-PadAH30)")
			(pinfunction "IO_L18N_T2_13")
			(pintype "bidirectional+no_connect")
			(die_length 20.408)
			(solder_mask_margin 0.02)
		)
		(pad "AJ1" smd circle
			(at -14.5 13.5)
			(size 0.5 0.5)
			(property pad_prop_bga)
			(layers "F.Cu" "F.Mask" "F.Paste")
			(net 648 "unconnected-(U1E-IO_L17P_T2_34-PadAJ1)")
			(pinfunction "IO_L17P_T2_34")
			(pintype "bidirectional+no_connect")
			(die_length 25.396)
			(solder_mask_margin 0.02)
		)
		(pad "AJ2" smd circle
			(at -13.5 13.5)
			(size 0.5 0.5)
			(property pad_prop_bga)
			(layers "F.Cu" "F.Mask" "F.Paste")
			(net 553 "/DRAM + SRAM/DDR.ODT")
			(pinfunction "IO_L16N_T2_34")
			(pintype "bidirectional")
			(die_length 23.465)
			(solder_mask_margin 0.02)
		)
		(pad "AJ3" smd circle
			(at -12.5 13.5)
			(size 0.5 0.5)
			(property pad_prop_bga)
			(layers "F.Cu" "F.Mask" "F.Paste")
			(net 651 "unconnected-(U1E-IO_L18P_T2_34-PadAJ3)")
			(pinfunction "IO_L18P_T2_34")
			(pintype "bidirectional+no_connect")
			(die_length 23.099)
			(solder_mask_margin 0.02)
		)
		(pad "AJ4" smd circle
			(at -11.5 13.5)
			(size 0.5 0.5)
			(property pad_prop_bga)
			(layers "F.Cu" "F.Mask" "F.Paste")
			(net 652 "unconnected-(U1E-IO_L13N_T2_MRCC_34-PadAJ4)")
			(pinfunction "IO_L13N_T2_MRCC_34")
			(pintype "bidirectional+no_connect")
			(die_length 21.012)
			(solder_mask_margin 0.02)
		)
		(pad "AJ5" smd circle
			(at -10.5 13.5)
			(size 0.5 0.5)
			(property pad_prop_bga)
			(layers "F.Cu" "F.Mask" "F.Paste")
			(net 25 "+1V35")
			(pinfunction "VCCO_34")
			(pintype "passive")
			(solder_mask_margin 0.02)
		)
		(pad "AJ6" smd circle
			(at -9.5 13.5)
			(size 0.5 0.5)
			(property pad_prop_bga)
			(layers "F.Cu" "F.Mask" "F.Paste")
			(net 657 "/DRAM + SRAM/DDR.DQ3")
			(pinfunction "IO_L22P_T3_34")
			(pintype "bidirectional")
			(die_length 20.732)
			(solder_mask_margin 0.02)
		)
		(pad "AJ7" smd circle
			(at -8.5 13.5)
			(size 0.5 0.5)
			(property pad_prop_bga)
			(layers "F.Cu" "F.Mask" "F.Paste")
			(net 658 "/DRAM + SRAM/DDR.DQS_N")
			(pinfunction "IO_L21N_T3_DQS_34")
			(pintype "bidirectional")
			(die_length 20.068)
			(solder_mask_margin 0.02)
		)
		(pad "AJ8" smd circle
			(at -7.5 13.5)
			(size 0.5 0.5)
			(property pad_prop_bga)
			(layers "F.Cu" "F.Mask" "F.Paste")
			(net 659 "/DRAM + SRAM/DDR.DQ5")
			(pinfunction "IO_L23P_T3_34")
			(pintype "bidirectional")
			(die_length 21.132)
			(solder_mask_margin 0.02)
		)
		(pad "AJ9" smd circle
			(at -6.5 13.5)
			(size 0.5 0.5)
			(property pad_prop_bga)
			(layers "F.Cu" "F.Mask" "F.Paste")
			(net 481 "unconnected-(U1E-IO_L15P_T2_DQS_33-PadAJ9)")
			(pinfunction "IO_L15P_T2_DQS_33")
			(pintype "bidirectional+no_connect")
			(die_length 18.988)
			(solder_mask_margin 0.02)
		)
		(pad "AJ10" smd circle
			(at -5.5 13.5)
			(size 0.5 0.5)
			(property pad_prop_bga)
			(layers "F.Cu" "F.Mask" "F.Paste")
			(net 1 "GND")
			(pinfunction "GND")
			(pintype "passive")
			(solder_mask_margin 0.02)
		)
		(pad "AJ11" smd circle
			(at -4.5 13.5)
			(size 0.5 0.5)
			(property pad_prop_bga)
			(layers "F.Cu" "F.Mask" "F.Paste")
			(net 482 "unconnected-(U1E-IO_L18N_T2_33-PadAJ11)")
			(pinfunction "IO_L18N_T2_33")
			(pintype "bidirectional+no_connect")
			(die_length 18.518)
			(solder_mask_margin 0.02)
		)
		(pad "AJ12" smd circle
			(at -3.5 13.5)
			(size 0.5 0.5)
			(property pad_prop_bga)
			(layers "F.Cu" "F.Mask" "F.Paste")
			(net 408 "/FPGA Bank 33 & 34/USR_FLASH_0.CLK")
			(pinfunction "IO_L22N_T3_33")
			(pintype "bidirectional")
			(die_length 21.055)
			(solder_mask_margin 0.02)
		)
		(pad "AJ13" smd circle
			(at -2.5 13.5)
			(size 0.5 0.5)
			(property pad_prop_bga)
			(layers "F.Cu" "F.Mask" "F.Paste")
			(net 410 "/FPGA Bank 33 & 34/USR_FLASH_0.DQ0")
			(pinfunction "IO_L22P_T3_33")
			(pintype "bidirectional")
			(die_length 20.602)
			(solder_mask_margin 0.02)
		)
		(pad "AJ14" smd circle
			(at -1.5 13.5)
			(size 0.5 0.5)
			(property pad_prop_bga)
			(layers "F.Cu" "F.Mask" "F.Paste")
			(net 484 "unconnected-(U1E-IO_L21N_T3_DQS_33-PadAJ14)")
			(pinfunction "IO_L21N_T3_DQS_33")
			(pintype "bidirectional+no_connect")
			(die_length 23.179)
			(solder_mask_margin 0.02)
		)
		(pad "AJ15" smd circle
			(at -0.5 13.5)
			(size 0.5 0.5)
			(property pad_prop_bga)
			(layers "F.Cu" "F.Mask" "F.Paste")
			(net 26 "+1V8")
			(pinfunction "VCCO_32")
			(pintype "passive")
			(solder_mask_margin 0.02)
		)
		(pad "AJ16" smd circle
			(at 0.5 13.5)
			(size 0.5 0.5)
			(property pad_prop_bga)
			(layers "F.Cu" "F.Mask" "F.Paste")
			(net 653 "unconnected-(U1D-IO_L3N_T0_DQS_32-PadAJ16)")
			(pinfunction "IO_L3N_T0_DQS_32")
			(pintype "bidirectional+no_connect")
			(die_length 21.232)
			(solder_mask_margin 0.02)
		)
		(pad "AJ17" smd circle
			(at 1.5 13.5)
			(size 0.5 0.5)
			(property pad_prop_bga)
			(layers "F.Cu" "F.Mask" "F.Paste")
			(net 693 "/FPGA Bank 12 & 13/USB_USER.VMO")
			(pinfunction "IO_L5N_T0_32")
			(pintype "bidirectional")
			(die_length 21.569)
			(solder_mask_margin 0.02)
		)
		(pad "AJ18" smd circle
			(at 2.5 13.5)
			(size 0.5 0.5)
			(property pad_prop_bga)
			(layers "F.Cu" "F.Mask" "F.Paste")
			(net 694 "unconnected-(U1D-IO_L9P_T1_DQS_32-PadAJ18)")
			(pinfunction "IO_L9P_T1_DQS_32")
			(pintype "bidirectional+no_connect")
			(die_length 21.796)
			(solder_mask_margin 0.02)
		)
		(pad "AJ19" smd circle
			(at 3.5 13.5)
			(size 0.5 0.5)
			(property pad_prop_bga)
			(layers "F.Cu" "F.Mask" "F.Paste")
			(net 774 "unconnected-(U1D-IO_L7P_T1_32-PadAJ19)")
			(pinfunction "IO_L7P_T1_32")
			(pintype "bidirectional+no_connect")
			(die_length 23.335)
			(solder_mask_margin 0.02)
		)
		(pad "AJ20" smd circle
			(at 4.5 13.5)
			(size 0.5 0.5)
			(property pad_prop_bga)
			(layers "F.Cu" "F.Mask" "F.Paste")
			(net 1 "GND")
			(pinfunction "GND")
			(pintype "passive")
			(solder_mask_margin 0.02)
		)
		(pad "AJ21" smd circle
			(at 5.5 13.5)
			(size 0.5 0.5)
			(property pad_prop_bga)
			(layers "F.Cu" "F.Mask" "F.Paste")
			(net 489 "/FPGA Bank 12 & 13/CW_HEADER.IO1")
			(pinfunction "IO_L23N_T3_12")
			(pintype "bidirectional")
			(die_length 11.355)
			(solder_mask_margin 0.02)
		)
		(pad "AJ22" smd circle
			(at 6.5 13.5)
			(size 0.5 0.5)
			(property pad_prop_bga)
			(layers "F.Cu" "F.Mask" "F.Paste")
			(net 1353 "/SUP_MCU.A1")
			(pinfunction "IO_L21P_T3_DQS_12")
			(pintype "bidirectional")
			(die_length 12.698)
			(solder_mask_margin 0.02)
		)
		(pad "AJ23" smd circle
			(at 7.5 13.5)
			(size 0.5 0.5)
			(property pad_prop_bga)
			(layers "F.Cu" "F.Mask" "F.Paste")
			(net 1360 "/SUP_MCU.A3")
			(pinfunction "IO_L21N_T3_DQS_12")
			(pintype "bidirectional")
			(die_length 12.727)
			(solder_mask_margin 0.02)
		)
		(pad "AJ24" smd circle
			(at 8.5 13.5)
			(size 0.5 0.5)
			(property pad_prop_bga)
			(layers "F.Cu" "F.Mask" "F.Paste")
			(net 1367 "/SUP_MCU.A19")
			(pinfunction "IO_L15P_T2_DQS_12")
			(pintype "bidirectional")
			(die_length 14.604)
			(solder_mask_margin 0.02)
		)
		(pad "AJ25" smd circle
			(at 9.5 13.5)
			(size 0.5 0.5)
			(property pad_prop_bga)
			(layers "F.Cu" "F.Mask" "F.Paste")
			(net 24 "+3V3")
			(pinfunction "VCCO_13")
			(pintype "passive")
			(solder_mask_margin 0.02)
		)
		(pad "AJ26" smd circle
			(at 10.5 13.5)
			(size 0.5 0.5)
			(property pad_prop_bga)
			(layers "F.Cu" "F.Mask" "F.Paste")
			(net 776 "unconnected-(U1A-IO_L24P_T3_13-PadAJ26)")
			(pinfunction "IO_L24P_T3_13")
			(pintype "bidirectional+no_connect")
			(die_length 18.345)
			(solder_mask_margin 0.02)
		)
		(pad "AJ27" smd circle
			(at 11.5 13.5)
			(size 0.5 0.5)
			(property pad_prop_bga)
			(layers "F.Cu" "F.Mask" "F.Paste")
			(net 778 "unconnected-(U1A-IO_L20P_T3_13-PadAJ27)")
			(pinfunction "IO_L20P_T3_13")
			(pintype "bidirectional+no_connect")
			(die_length 19.574)
			(solder_mask_margin 0.02)
		)
		(pad "AJ28" smd circle
			(at 12.5 13.5)
			(size 0.5 0.5)
			(property pad_prop_bga)
			(layers "F.Cu" "F.Mask" "F.Paste")
			(net 461 "/FPGA Bank 12 & 13/PMOD_A.IO4")
			(pinfunction "IO_L17P_T2_13")
			(pintype "bidirectional")
			(die_length 19.784)
			(solder_mask_margin 0.02)
		)
		(pad "AJ29" smd circle
			(at 13.5 13.5)
			(size 0.5 0.5)
			(property pad_prop_bga)
			(layers "F.Cu" "F.Mask" "F.Paste")
			(net 439 "/FPGA Bank 12 & 13/PMOD_A.IO10")
			(pinfunction "IO_L17N_T2_13")
			(pintype "bidirectional")
			(die_length 19.876)
			(solder_mask_margin 0.02)
		)
		(pad "AJ30" smd circle
			(at 14.5 13.5)
			(size 0.5 0.5)
			(property pad_prop_bga)
			(layers "F.Cu" "F.Mask" "F.Paste")
			(net 1 "GND")
			(pinfunction "GND")
			(pintype "passive")
			(solder_mask_margin 0.02)
		)
		(pad "AK1" smd circle
			(at -14.5 14.5)
			(size 0.5 0.5)
			(property pad_prop_bga)
			(layers "F.Cu" "F.Mask" "F.Paste")
			(net 784 "unconnected-(U1E-IO_L17N_T2_34-PadAK1)")
			(pinfunction "IO_L17N_T2_34")
			(pintype "bidirectional+no_connect")
			(die_length 24.656)
			(solder_mask_margin 0.02)
		)
		(pad "AK2" smd circle
			(at -13.5 14.5)
			(size 0.5 0.5)
			(property pad_prop_bga)
			(layers "F.Cu" "F.Mask" "F.Paste")
			(net 25 "+1V35")
			(pinfunction "VCCO_34")
			(pintype "passive")
			(solder_mask_margin 0.02)
		)
		(pad "AK3" smd circle
			(at -12.5 14.5)
			(size 0.5 0.5)
			(property pad_prop_bga)
			(layers "F.Cu" "F.Mask" "F.Paste")
			(net 786 "unconnected-(U1E-IO_L18N_T2_34-PadAK3)")
			(pinfunction "IO_L18N_T2_34")
			(pintype "bidirectional+no_connect")
			(die_length 23.037)
			(solder_mask_margin 0.02)
		)
		(pad "AK4" smd circle
			(at -11.5 14.5)
			(size 0.5 0.5)
			(property pad_prop_bga)
			(layers "F.Cu" "F.Mask" "F.Paste")
			(net 660 "/DRAM + SRAM/DDR.DQ6")
			(pinfunction "IO_L24N_T3_34")
			(pintype "bidirectional")
			(die_length 23.568)
			(solder_mask_margin 0.02)
		)
		(pad "AK5" smd circle
			(at -10.5 14.5)
			(size 0.5 0.5)
			(property pad_prop_bga)
			(layers "F.Cu" "F.Mask" "F.Paste")
			(net 661 "/DRAM + SRAM/DDR.DQ0")
			(pinfunction "IO_L24P_T3_34")
			(pintype "bidirectional")
			(die_length 22.516)
			(solder_mask_margin 0.02)
		)
		(pad "AK6" smd circle
			(at -9.5 14.5)
			(size 0.5 0.5)
			(property pad_prop_bga)
			(layers "F.Cu" "F.Mask" "F.Paste")
			(net 662 "/DRAM + SRAM/DDR.DQ2")
			(pinfunction "IO_L22N_T3_34")
			(pintype "bidirectional")
			(die_length 21.012)
			(solder_mask_margin 0.02)
		)
		(pad "AK7" smd circle
			(at -8.5 14.5)
			(size 0.5 0.5)
			(property pad_prop_bga)
			(layers "F.Cu" "F.Mask" "F.Paste")
			(net 1 "GND")
			(pinfunction "GND")
			(pintype "passive")
			(solder_mask_margin 0.02)
		)
		(pad "AK8" smd circle
			(at -7.5 14.5)
			(size 0.5 0.5)
			(property pad_prop_bga)
			(layers "F.Cu" "F.Mask" "F.Paste")
			(net 663 "/DRAM + SRAM/DDR.DQ1")
			(pinfunction "IO_L23N_T3_34")
			(pintype "bidirectional")
			(die_length 21.371)
			(solder_mask_margin 0.02)
		)
		(pad "AK9" smd circle
			(at -6.5 14.5)
			(size 0.5 0.5)
			(property pad_prop_bga)
			(layers "F.Cu" "F.Mask" "F.Paste")
			(net 512 "unconnected-(U1E-IO_L15N_T2_DQS_33-PadAK9)")
			(pinfunction "IO_L15N_T2_DQS_33")
			(pintype "bidirectional+no_connect")
			(die_length 18.854)
			(solder_mask_margin 0.02)
		)
		(pad "AK10" smd circle
			(at -5.5 14.5)
			(size 0.5 0.5)
			(property pad_prop_bga)
			(layers "F.Cu" "F.Mask" "F.Paste")
			(net 518 "unconnected-(U1E-IO_L17N_T2_33-PadAK10)")
			(pinfunction "IO_L17N_T2_33")
			(pintype "bidirectional+no_connect")
			(die_length 19.289)
			(solder_mask_margin 0.02)
		)
		(pad "AK11" smd circle
			(at -4.5 14.5)
			(size 0.5 0.5)
			(property pad_prop_bga)
			(layers "F.Cu" "F.Mask" "F.Paste")
			(net 625 "unconnected-(U1E-IO_L17P_T2_33-PadAK11)")
			(pinfunction "IO_L17P_T2_33")
			(pintype "bidirectional+no_connect")
			(die_length 20.52)
			(solder_mask_margin 0.02)
		)
		(pad "AK12" smd circle
			(at -3.5 14.5)
			(size 0.5 0.5)
			(property pad_prop_bga)
			(layers "F.Cu" "F.Mask" "F.Paste")
			(net 26 "+1V8")
			(pinfunction "VCCO_33")
			(pintype "passive")
			(solder_mask_margin 0.02)
		)
		(pad "AK13" smd circle
			(at -2.5 14.5)
			(size 0.5 0.5)
			(property pad_prop_bga)
			(layers "F.Cu" "F.Mask" "F.Paste")
			(net 411 "/FPGA Bank 33 & 34/USR_FLASH_0.DQ1")
			(pinfunction "IO_L20N_T3_33")
			(pintype "bidirectional")
			(die_length 21.609)
			(solder_mask_margin 0.02)
		)
		(pad "AK14" smd circle
			(at -1.5 14.5)
			(size 0.5 0.5)
			(property pad_prop_bga)
			(layers "F.Cu" "F.Mask" "F.Paste")
			(net 395 "/FPGA Bank 33 & 34/SD_CARD.DAT0")
			(pinfunction "IO_L20P_T3_33")
			(pintype "bidirectional")
			(die_length 23.027)
			(solder_mask_margin 0.02)
		)
		(pad "AK15" smd circle
			(at -0.5 14.5)
			(size 0.5 0.5)
			(property pad_prop_bga)
			(layers "F.Cu" "F.Mask" "F.Paste")
			(net 788 "unconnected-(U1D-IO_L1N_T0_32-PadAK15)")
			(pinfunction "IO_L1N_T0_32")
			(pintype "bidirectional+no_connect")
			(die_length 21.665)
			(solder_mask_margin 0.02)
		)
		(pad "AK16" smd circle
			(at 0.5 14.5)
			(size 0.5 0.5)
			(property pad_prop_bga)
			(layers "F.Cu" "F.Mask" "F.Paste")
			(net 796 "unconnected-(U1D-IO_L1P_T0_32-PadAK16)")
			(pinfunction "IO_L1P_T0_32")
			(pintype "bidirectional+no_connect")
			(die_length 22.612)
			(solder_mask_margin 0.02)
		)
		(pad "AK17" smd circle
			(at 1.5 14.5)
			(size 0.5 0.5)
			(property pad_prop_bga)
			(layers "F.Cu" "F.Mask" "F.Paste")
			(net 1 "GND")
			(pinfunction "GND")
			(pintype "passive")
			(solder_mask_margin 0.02)
		)
		(pad "AK18" smd circle
			(at 2.5 14.5)
			(size 0.5 0.5)
			(property pad_prop_bga)
			(layers "F.Cu" "F.Mask" "F.Paste")
			(net 818 "unconnected-(U1D-IO_L9N_T1_DQS_32-PadAK18)")
			(pinfunction "IO_L9N_T1_DQS_32")
			(pintype "bidirectional+no_connect")
			(die_length 22.005)
			(solder_mask_margin 0.02)
		)
		(pad "AK19" smd circle
			(at 3.5 14.5)
			(size 0.5 0.5)
			(property pad_prop_bga)
			(layers "F.Cu" "F.Mask" "F.Paste")
			(net 819 "unconnected-(U1D-IO_L7N_T1_32-PadAK19)")
			(pinfunction "IO_L7N_T1_32")
			(pintype "bidirectional+no_connect")
			(die_length 23.523)
			(solder_mask_margin 0.02)
		)
		(pad "AK20" smd circle
			(at 4.5 14.5)
			(size 0.5 0.5)
			(property pad_prop_bga)
			(layers "F.Cu" "F.Mask" "F.Paste")
			(net 477 "/FPGA Bank 12 & 13/CW_HEADER.TSCK")
			(pinfunction "IO_L24P_T3_12")
			(pintype "bidirectional")
			(die_length 12.709)
			(solder_mask_margin 0.02)
		)
		(pad "AK21" smd circle
			(at 5.5 14.5)
			(size 0.5 0.5)
			(property pad_prop_bga)
			(layers "F.Cu" "F.Mask" "F.Paste")
			(net 476 "/FPGA Bank 12 & 13/CW_HEADER.MOSI")
			(pinfunction "IO_L24N_T3_12")
			(pintype "bidirectional")
			(die_length 13.051)
			(solder_mask_margin 0.02)
		)
		(pad "AK22" smd circle
			(at 6.5 14.5)
			(size 0.5 0.5)
			(property pad_prop_bga)
			(layers "F.Cu" "F.Mask" "F.Paste")
			(net 24 "+3V3")
			(pinfunction "VCCO_12")
			(pintype "passive")
			(solder_mask_margin 0.02)
		)
		(pad "AK23" smd circle
			(at 7.5 14.5)
			(size 0.5 0.5)
			(property pad_prop_bga)
			(layers "F.Cu" "F.Mask" "F.Paste")
			(net 1331 "/SUP_MCU.RX0")
			(pinfunction "IO_L17P_T2_12")
			(pintype "bidirectional")
			(die_length 14.198)
			(solder_mask_margin 0.02)
		)
		(pad "AK24" smd circle
			(at 8.5 14.5)
			(size 0.5 0.5)
			(property pad_prop_bga)
			(layers "F.Cu" "F.Mask" "F.Paste")
			(net 692 "unconnected-(U1A-IO_L17N_T2_12-PadAK24)")
			(pinfunction "IO_L17N_T2_12")
			(pintype "bidirectional+no_connect")
			(die_length 14.315)
			(solder_mask_margin 0.02)
		)
		(pad "AK25" smd circle
			(at 9.5 14.5)
			(size 0.5 0.5)
			(property pad_prop_bga)
			(layers "F.Cu" "F.Mask" "F.Paste")
			(net 1371 "/SUP_MCU.A12")
			(pinfunction "IO_L15N_T2_DQS_12")
			(pintype "bidirectional")
			(die_length 14.925)
			(solder_mask_margin 0.02)
		)
		(pad "AK26" smd circle
			(at 10.5 14.5)
			(size 0.5 0.5)
			(property pad_prop_bga)
			(layers "F.Cu" "F.Mask" "F.Paste")
			(net 497 "/FPGA Bank 12 & 13/USB_USER.VDET")
			(pinfunction "IO_L24N_T3_13")
			(pintype "bidirectional")
			(die_length 18.616)
			(solder_mask_margin 0.02)
		)
		(pad "AK27" smd circle
			(at 11.5 14.5)
			(size 0.5 0.5)
			(property pad_prop_bga)
			(layers "F.Cu" "F.Mask" "F.Paste")
			(net 1 "GND")
			(pinfunction "GND")
			(pintype "passive")
			(solder_mask_margin 0.02)
		)
		(pad "AK28" smd circle
			(at 12.5 14.5)
			(size 0.5 0.5)
			(property pad_prop_bga)
			(layers "F.Cu" "F.Mask" "F.Paste")
			(net 456 "/FPGA Bank 12 & 13/PMOD_A.IO1")
			(pinfunction "IO_L20N_T3_13")
			(pintype "bidirectional")
			(die_length 20.362)
			(solder_mask_margin 0.02)
		)
		(pad "AK29" smd circle
			(at 13.5 14.5)
			(size 0.5 0.5)
			(property pad_prop_bga)
			(layers "F.Cu" "F.Mask" "F.Paste")
			(net 871 "unconnected-(U1A-IO_L15P_T2_DQS_13-PadAK29)")
			(pinfunction "IO_L15P_T2_DQS_13")
			(pintype "bidirectional+no_connect")
			(die_length 22.007)
			(solder_mask_margin 0.02)
		)
		(pad "AK30" smd circle
			(at 14.5 14.5)
			(size 0.5 0.5)
			(property pad_prop_bga)
			(layers "F.Cu" "F.Mask" "F.Paste")
			(net 1377 "/SUP_MCU.SPARE0")
			(pinfunction "IO_L15N_T2_DQS_13")
			(pintype "bidirectional")
			(die_length 21.946)
			(solder_mask_margin 0.02)
		)
		(pad "B1" smd circle
			(at -14.5 -13.5)
			(size 0.5 0.5)
			(property pad_prop_bga)
			(layers "F.Cu" "F.Mask" "F.Paste")
			(net 873 "unconnected-(U1G-MGTXTXN2_118-PadB1)")
			(pinfunction "MGTXTXN2_118")
			(pintype "bidirectional+no_connect")
			(die_length 16.521)
			(solder_mask_margin 0.02)
		)
		(pad "B2" smd circle
			(at -13.5 -13.5)
			(size 0.5 0.5)
			(property pad_prop_bga)
			(layers "F.Cu" "F.Mask" "F.Paste")
			(net 874 "unconnected-(U1G-MGTXTXP2_118-PadB2)")
			(pinfunction "MGTXTXP2_118")
			(pintype "bidirectional+no_connect")
			(die_length 16.53)
			(solder_mask_margin 0.02)
		)
		(pad "B3" smd circle
			(at -12.5 -13.5)
			(size 0.5 0.5)
			(property pad_prop_bga)
			(layers "F.Cu" "F.Mask" "F.Paste")
			(net 8 "+1V2_MGTAVTT")
			(pinfunction "MGTAVTT")
			(pintype "bidirectional")
			(solder_mask_margin 0.02)
		)
		(pad "B4" smd circle
			(at -11.5 -13.5)
			(size 0.5 0.5)
			(property pad_prop_bga)
			(layers "F.Cu" "F.Mask" "F.Paste")
			(net 1 "GND")
			(pinfunction "GND")
			(pintype "passive")
			(solder_mask_margin 0.02)
		)
		(pad "B5" smd circle
			(at -10.5 -13.5)
			(size 0.5 0.5)
			(property pad_prop_bga)
			(layers "F.Cu" "F.Mask" "F.Paste")
			(net 890 "unconnected-(U1G-MGTXRXN2_118-PadB5)")
			(pinfunction "MGTXRXN2_118")
			(pintype "bidirectional+no_connect")
			(die_length 12.709)
			(solder_mask_margin 0.02)
		)
		(pad "B6" smd circle
			(at -9.5 -13.5)
			(size 0.5 0.5)
			(property pad_prop_bga)
			(layers "F.Cu" "F.Mask" "F.Paste")
			(net 892 "unconnected-(U1G-MGTXRXP2_118-PadB6)")
			(pinfunction "MGTXRXP2_118")
			(pintype "bidirectional+no_connect")
			(die_length 12.944)
			(solder_mask_margin 0.02)
		)
		(pad "B7" smd circle
			(at -8.5 -13.5)
			(size 0.5 0.5)
			(property pad_prop_bga)
			(layers "F.Cu" "F.Mask" "F.Paste")
			(net 6 "+1V0_MGTAVCC")
			(pinfunction "MGTAVCC")
			(pintype "bidirectional")
			(solder_mask_margin 0.02)
		)
		(pad "B8" smd circle
			(at -7.5 -13.5)
			(size 0.5 0.5)
			(property pad_prop_bga)
			(layers "F.Cu" "F.Mask" "F.Paste")
			(net 1 "GND")
			(pinfunction "GND")
			(pintype "passive")
			(solder_mask_margin 0.02)
		)
		(pad "B9" smd circle
			(at -6.5 -13.5)
			(size 0.5 0.5)
			(property pad_prop_bga)
			(layers "F.Cu" "F.Mask" "F.Paste")
			(net 1 "GND")
			(pinfunction "GND")
			(pintype "passive")
			(solder_mask_margin 0.02)
		)
		(pad "B10" smd circle
			(at -5.5 -13.5)
			(size 0.5 0.5)
			(property pad_prop_bga)
			(layers "F.Cu" "F.Mask" "F.Paste")
			(net 56 "/FPGA Bank 14 & 15/SYSTEM_FLASH.CLK")
			(pinfunction "CCLK_0")
			(pintype "bidirectional")
			(die_length 29.155)
			(solder_mask_margin 0.02)
		)
		(pad "B11" smd circle
			(at -4.5 -13.5)
			(size 0.5 0.5)
			(property pad_prop_bga)
			(layers "F.Cu" "F.Mask" "F.Paste")
			(net 1 "GND")
			(pinfunction "GND")
			(pintype "passive")
			(solder_mask_margin 0.02)
		)
		(pad "B12" smd circle
			(at -3.5 -13.5)
			(size 0.5 0.5)
			(property pad_prop_bga)
			(layers "F.Cu" "F.Mask" "F.Paste")
			(net 641 "/FMC+ HSPC/FMC.IO15_N")
			(pinfunction "IO_L15N_T2_DQS_18")
			(pintype "bidirectional")
			(die_length 25.173)
			(solder_mask_margin 0.02)
		)
		(pad "B13" smd circle
			(at -2.5 -13.5)
			(size 0.5 0.5)
			(property pad_prop_bga)
			(layers "F.Cu" "F.Mask" "F.Paste")
			(net 642 "/FMC+ HSPC/FMC.IO22_P")
			(pinfunction "IO_L22P_T3_18")
			(pintype "bidirectional")
			(die_length 24.88)
			(solder_mask_margin 0.02)
		)
		(pad "B14" smd circle
			(at -1.5 -13.5)
			(size 0.5 0.5)
			(property pad_prop_bga)
			(layers "F.Cu" "F.Mask" "F.Paste")
			(net 350 "/FMC+ HSPC/FMC.IO24_P")
			(pinfunction "IO_L24P_T3_18")
			(pintype "bidirectional")
			(die_length 24.532)
			(solder_mask_margin 0.02)
		)
		(pad "B15" smd circle
			(at -0.5 -13.5)
			(size 0.5 0.5)
			(property pad_prop_bga)
			(layers "F.Cu" "F.Mask" "F.Paste")
			(net 444 "/FMC+ HSPC/FMC.IO23_N")
			(pinfunction "IO_L23N_T3_18")
			(pintype "bidirectional")
			(die_length 22.701)
			(solder_mask_margin 0.02)
		)
		(pad "B16" smd circle
			(at 0.5 -13.5)
			(size 0.5 0.5)
			(property pad_prop_bga)
			(layers "F.Cu" "F.Mask" "F.Paste")
			(net 24 "+3V3")
			(pinfunction "VCCO_17")
			(pintype "passive")
			(solder_mask_margin 0.02)
		)
		(pad "B17" smd circle
			(at 1.5 -13.5)
			(size 0.5 0.5)
			(property pad_prop_bga)
			(layers "F.Cu" "F.Mask" "F.Paste")
			(net 893 "/FPGA Bank 12 & 13/USB_HOST.~{CS}")
			(pinfunction "IO_L17N_T2_17")
			(pintype "bidirectional")
			(die_length 23.879)
			(solder_mask_margin 0.02)
		)
		(pad "B18" smd circle
			(at 2.5 -13.5)
			(size 0.5 0.5)
			(property pad_prop_bga)
			(layers "F.Cu" "F.Mask" "F.Paste")
			(net 495 "/FPGA Bank 12 & 13/USB_HOST.INT")
			(pinfunction "IO_L22P_T3_17")
			(pintype "bidirectional")
			(die_length 24.881)
			(solder_mask_margin 0.02)
		)
		(pad "B19" smd circle
			(at 3.5 -13.5)
			(size 0.5 0.5)
			(property pad_prop_bga)
			(layers "F.Cu" "F.Mask" "F.Paste")
			(net 525 "/FPGA Bank 16 & 17/HDMI.D2_N")
			(pinfunction "IO_L24N_T3_17")
			(pintype "bidirectional")
			(die_length 25.226)
			(solder_mask_margin 0.02)
		)
		(pad "B20" smd circle
			(at 4.5 -13.5)
			(size 0.5 0.5)
			(property pad_prop_bga)
			(layers "F.Cu" "F.Mask" "F.Paste")
			(net 527 "/FPGA Bank 16 & 17/HDMI.D1_N")
			(pinfunction "IO_L19N_T3_VREF_17")
			(pintype "bidirectional")
			(die_length 21.681)
			(solder_mask_margin 0.02)
		)
		(pad "B21" smd circle
			(at 5.5 -13.5)
			(size 0.5 0.5)
			(property pad_prop_bga)
			(layers "F.Cu" "F.Mask" "F.Paste")
			(net 1 "GND")
			(pinfunction "GND")
			(pintype "passive")
			(solder_mask_margin 0.02)
		)
		(pad "B22" smd circle
			(at 6.5 -13.5)
			(size 0.5 0.5)
			(property pad_prop_bga)
			(layers "F.Cu" "F.Mask" "F.Paste")
			(net 530 "/FPGA Bank 16 & 17/HDMI.CLK_P")
			(pinfunction "IO_L23P_T3_17")
			(pintype "bidirectional")
			(die_length 21.288)
			(solder_mask_margin 0.02)
		)
		(pad "B23" smd circle
			(at 7.5 -13.5)
			(size 0.5 0.5)
			(property pad_prop_bga)
			(layers "F.Cu" "F.Mask" "F.Paste")
			(net 780 "unconnected-(U1C-IO_L1P_T0_16-PadB23)")
			(pinfunction "IO_L1P_T0_16")
			(pintype "bidirectional+no_connect")
			(die_length 20.406)
			(solder_mask_margin 0.02)
		)
		(pad "B24" smd circle
			(at 8.5 -13.5)
			(size 0.5 0.5)
			(property pad_prop_bga)
			(layers "F.Cu" "F.Mask" "F.Paste")
			(net 1278 "/USER_IO.B16")
			(pinfunction "IO_L8N_T1_16")
			(pintype "bidirectional")
			(die_length 22.133)
			(solder_mask_margin 0.02)
		)
		(pad "B25" smd circle
			(at 9.5 -13.5)
			(size 0.5 0.5)
			(property pad_prop_bga)
			(layers "F.Cu" "F.Mask" "F.Paste")
			(net 1286 "/USER_IO.B26")
			(pinfunction "IO_L12N_T1_MRCC_16")
			(pintype "bidirectional")
			(die_length 22.219)
			(solder_mask_margin 0.02)
		)
		(pad "B26" smd circle
			(at 10.5 -13.5)
			(size 0.5 0.5)
			(property pad_prop_bga)
			(layers "F.Cu" "F.Mask" "F.Paste")
			(net 3 "VCC_USR_B")
			(pinfunction "VCCO_16")
			(pintype "passive")
			(solder_mask_margin 0.02)
		)
		(pad "B27" smd circle
			(at 11.5 -13.5)
			(size 0.5 0.5)
			(property pad_prop_bga)
			(layers "F.Cu" "F.Mask" "F.Paste")
			(net 1275 "/USER_IO.B12")
			(pinfunction "IO_L7P_T1_16")
			(pintype "bidirectional")
			(die_length 20.903)
			(solder_mask_margin 0.02)
		)
		(pad "B28" smd circle
			(at 12.5 -13.5)
			(size 0.5 0.5)
			(property pad_prop_bga)
			(layers "F.Cu" "F.Mask" "F.Paste")
			(net 1277 "/USER_IO.B15")
			(pinfunction "IO_L9P_T1_DQS_16")
			(pintype "bidirectional")
			(die_length 23.114)
			(solder_mask_margin 0.02)
		)
		(pad "B29" smd circle
			(at 13.5 -13.5)
			(size 0.5 0.5)
			(property pad_prop_bga)
			(layers "F.Cu" "F.Mask" "F.Paste")
			(net 417 "/FPGA Bank 16 & 17/USR_FLASH_1.DQ3")
			(pinfunction "IO_L15N_T2_DQS_16")
			(pintype "bidirectional")
			(die_length 22.831)
			(solder_mask_margin 0.02)
		)
		(pad "B30" smd circle
			(at 14.5 -13.5)
			(size 0.5 0.5)
			(property pad_prop_bga)
			(layers "F.Cu" "F.Mask" "F.Paste")
			(net 782 "unconnected-(U1C-IO_L17P_T2_16-PadB30)")
			(pinfunction "IO_L17P_T2_16")
			(pintype "bidirectional+no_connect")
			(die_length 24.67)
			(solder_mask_margin 0.02)
		)
		(pad "C1" smd circle
			(at -14.5 -12.5)
			(size 0.5 0.5)
			(property pad_prop_bga)
			(layers "F.Cu" "F.Mask" "F.Paste")
			(net 1 "GND")
			(pinfunction "GND")
			(pintype "passive")
			(solder_mask_margin 0.02)
		)
		(pad "C2" smd circle
			(at -13.5 -12.5)
			(size 0.5 0.5)
			(property pad_prop_bga)
			(layers "F.Cu" "F.Mask" "F.Paste")
			(net 1 "GND")
			(pinfunction "GND")
			(pintype "passive")
			(solder_mask_margin 0.02)
		)
		(pad "C3" smd circle
			(at -12.5 -12.5)
			(size 0.5 0.5)
			(property pad_prop_bga)
			(layers "F.Cu" "F.Mask" "F.Paste")
			(net 929 "unconnected-(U1G-MGTXTXN1_118-PadC3)")
			(pinfunction "MGTXTXN1_118")
			(pintype "bidirectional+no_connect")
			(die_length 14.029)
			(solder_mask_margin 0.02)
		)
		(pad "C4" smd circle
			(at -11.5 -12.5)
			(size 0.5 0.5)
			(property pad_prop_bga)
			(layers "F.Cu" "F.Mask" "F.Paste")
			(net 930 "unconnected-(U1G-MGTXTXP1_118-PadC4)")
			(pinfunction "MGTXTXP1_118")
			(pintype "bidirectional+no_connect")
			(die_length 14.008)
			(solder_mask_margin 0.02)
		)
		(pad "C5" smd circle
			(at -10.5 -12.5)
			(size 0.5 0.5)
			(property pad_prop_bga)
			(layers "F.Cu" "F.Mask" "F.Paste")
			(net 8 "+1V2_MGTAVTT")
			(pinfunction "MGTAVTT")
			(pintype "passive")
			(solder_mask_margin 0.02)
		)
		(pad "C6" smd circle
			(at -9.5 -12.5)
			(size 0.5 0.5)
			(property pad_prop_bga)
			(layers "F.Cu" "F.Mask" "F.Paste")
			(net 1 "GND")
			(pinfunction "GND")
			(pintype "passive")
			(solder_mask_margin 0.02)
		)
		(pad "C7" smd circle
			(at -8.5 -12.5)
			(size 0.5 0.5)
			(property pad_prop_bga)
			(layers "F.Cu" "F.Mask" "F.Paste")
			(net 931 "unconnected-(U1G-MGTREFCLK0N_118-PadC7)")
			(pinfunction "MGTREFCLK0N_118")
			(pintype "bidirectional+no_connect")
			(die_length 12.106)
			(solder_mask_margin 0.02)
		)
		(pad "C8" smd circle
			(at -7.5 -12.5)
			(size 0.5 0.5)
			(property pad_prop_bga)
			(layers "F.Cu" "F.Mask" "F.Paste")
			(net 932 "unconnected-(U1G-MGTREFCLK0P_118-PadC8)")
			(pinfunction "MGTREFCLK0P_118")
			(pintype "bidirectional+no_connect")
			(die_length 11.647)
			(solder_mask_margin 0.02)
		)
		(pad "C9" smd circle
			(at -6.5 -12.5)
			(size 0.5 0.5)
			(property pad_prop_bga)
			(layers "F.Cu" "F.Mask" "F.Paste")
			(net 1 "GND")
			(pinfunction "GND")
			(pintype "passive")
			(solder_mask_margin 0.02)
		)
		(pad "C10" smd circle
			(at -5.5 -12.5)
			(size 0.5 0.5)
			(property pad_prop_bga)
			(layers "F.Cu" "F.Mask" "F.Paste")
			(net 800 "unconnected-(U1J-VCCBATT_0-PadC10)")
			(pinfunction "VCCBATT_0")
			(pintype "bidirectional+no_connect")
			(die_length 28.237)
			(solder_mask_margin 0.02)
		)
		(pad "C11" smd circle
			(at -4.5 -12.5)
			(size 0.5 0.5)
			(property pad_prop_bga)
			(layers "F.Cu" "F.Mask" "F.Paste")
			(net 241 "/FMC+ HSPC/FMC.IO18_N")
			(pinfunction "IO_L18N_T2_18")
			(pintype "bidirectional")
			(die_length 23.774)
			(solder_mask_margin 0.02)
		)
		(pad "C12" smd circle
			(at -3.5 -12.5)
			(size 0.5 0.5)
			(property pad_prop_bga)
			(layers "F.Cu" "F.Mask" "F.Paste")
			(net 643 "/FMC+ HSPC/FMC.IO15_P")
			(pinfunction "IO_L15P_T2_DQS_18")
			(pintype "bidirectional")
			(die_length 25.474)
			(solder_mask_margin 0.02)
		)
		(pad "C13" smd circle
			(at -2.5 -12.5)
			(size 0.5 0.5)
			(property pad_prop_bga)
			(layers "F.Cu" "F.Mask" "F.Paste")
			(net 24 "+3V3")
			(pinfunction "VCCO_18")
			(pintype "bidirectional")
			(solder_mask_margin 0.02)
		)
		(pad "C14" smd circle
			(at -1.5 -12.5)
			(size 0.5 0.5)
			(property pad_prop_bga)
			(layers "F.Cu" "F.Mask" "F.Paste")
			(net 437 "/FMC+ HSPC/FMC.IO21_N")
			(pinfunction "IO_L21N_T3_DQS_18")
			(pintype "bidirectional")
			(die_length 22.366)
			(solder_mask_margin 0.02)
		)
		(pad "C15" smd circle
			(at -0.5 -12.5)
			(size 0.5 0.5)
			(property pad_prop_bga)
			(layers "F.Cu" "F.Mask" "F.Paste")
			(net 445 "/FMC+ HSPC/FMC.IO23_P")
			(pinfunction "IO_L23P_T3_18")
			(pintype "bidirectional")
			(die_length 22.399)
			(solder_mask_margin 0.02)
		)
		(pad "C16" smd circle
			(at 0.5 -12.5)
			(size 0.5 0.5)
			(property pad_prop_bga)
			(layers "F.Cu" "F.Mask" "F.Paste")
			(net 496 "/FPGA Bank 12 & 13/USB_HOST.~{RESET}")
			(pinfunction "IO_L15N_T2_DQS_17")
			(pintype "bidirectional")
			(die_length 23.846)
			(solder_mask_margin 0.02)
		)
		(pad "C17" smd circle
			(at 1.5 -12.5)
			(size 0.5 0.5)
			(property pad_prop_bga)
			(layers "F.Cu" "F.Mask" "F.Paste")
			(net 938 "/FPGA Bank 12 & 13/USB_HOST.MOSI")
			(pinfunction "IO_L17P_T2_17")
			(pintype "bidirectional")
			(die_length 23.901)
			(solder_mask_margin 0.02)
		)
		(pad "C18" smd circle
			(at 2.5 -12.5)
			(size 0.5 0.5)
			(property pad_prop_bga)
			(layers "F.Cu" "F.Mask" "F.Paste")
			(net 1 "GND")
			(pinfunction "GND")
			(pintype "passive")
			(solder_mask_margin 0.02)
		)
		(pad "C19" smd circle
			(at 3.5 -12.5)
			(size 0.5 0.5)
			(property pad_prop_bga)
			(layers "F.Cu" "F.Mask" "F.Paste")
			(net 524 "/FPGA Bank 16 & 17/HDMI.D2_P")
			(pinfunction "IO_L24P_T3_17")
			(pintype "bidirectional")
			(die_length 25.069)
			(solder_mask_margin 0.02)
		)
		(pad "C20" smd circle
			(at 4.5 -12.5)
			(size 0.5 0.5)
			(property pad_prop_bga)
			(layers "F.Cu" "F.Mask" "F.Paste")
			(net 526 "/FPGA Bank 16 & 17/HDMI.D1_P")
			(pinfunction "IO_L19P_T3_17")
			(pintype "bidirectional")
			(die_length 23.681)
			(solder_mask_margin 0.02)
		)
		(pad "C21" smd circle
			(at 5.5 -12.5)
			(size 0.5 0.5)
			(property pad_prop_bga)
			(layers "F.Cu" "F.Mask" "F.Paste")
			(net 529 "/FPGA Bank 16 & 17/HDMI.D0_N")
			(pinfunction "IO_L8N_T1_17")
			(pintype "bidirectional")
			(die_length 16.277)
			(solder_mask_margin 0.02)
		)
		(pad "C22" smd circle
			(at 6.5 -12.5)
			(size 0.5 0.5)
			(property pad_prop_bga)
			(layers "F.Cu" "F.Mask" "F.Paste")
			(net 939 "/FPGA Bank 16 & 17/GBE_RGMII.TXD0")
			(pinfunction "IO_L10N_T1_17")
			(pintype "bidirectional")
			(die_length 16.905)
			(solder_mask_margin 0.02)
		)
		(pad "C23" smd circle
			(at 7.5 -12.5)
			(size 0.5 0.5)
			(property pad_prop_bga)
			(layers "F.Cu" "F.Mask" "F.Paste")
			(net 3 "VCC_USR_B")
			(pinfunction "VCCO_16")
			(pintype "passive")
			(solder_mask_margin 0.02)
		)
		(pad "C24" smd circle
			(at 8.5 -12.5)
			(size 0.5 0.5)
			(property pad_prop_bga)
			(layers "F.Cu" "F.Mask" "F.Paste")
			(net 1280 "/USER_IO.B18")
			(pinfunction "IO_L8P_T1_16")
			(pintype "bidirectional")
			(die_length 20.699)
			(solder_mask_margin 0.02)
		)
		(pad "C25" smd circle
			(at 9.5 -12.5)
			(size 0.5 0.5)
			(property pad_prop_bga)
			(layers "F.Cu" "F.Mask" "F.Paste")
			(net 1276 "/USER_IO.B14")
			(pinfunction "IO_L12P_T1_MRCC_16")
			(pintype "bidirectional")
			(die_length 21.617)
			(solder_mask_margin 0.02)
		)
		(pad "C26" smd circle
			(at 10.5 -12.5)
			(size 0.5 0.5)
			(property pad_prop_bga)
			(layers "F.Cu" "F.Mask" "F.Paste")
			(net 1269 "/USER_IO.B6")
			(pinfunction "IO_L11N_T1_SRCC_16")
			(pintype "bidirectional")
			(die_length 20.862)
			(solder_mask_margin 0.02)
		)
		(pad "C27" smd circle
			(at 11.5 -12.5)
			(size 0.5 0.5)
			(property pad_prop_bga)
			(layers "F.Cu" "F.Mask" "F.Paste")
			(net 1290 "/USER_IO.B30")
			(pinfunction "IO_L13N_T2_MRCC_16")
			(pintype "bidirectional")
			(die_length 20.889)
			(solder_mask_margin 0.02)
		)
		(pad "C28" smd circle
			(at 12.5 -12.5)
			(size 0.5 0.5)
			(property pad_prop_bga)
			(layers "F.Cu" "F.Mask" "F.Paste")
			(net 1 "GND")
			(pinfunction "GND")
			(pintype "passive")
			(solder_mask_margin 0.02)
		)
		(pad "C29" smd circle
			(at 13.5 -12.5)
			(size 0.5 0.5)
			(property pad_prop_bga)
			(layers "F.Cu" "F.Mask" "F.Paste")
			(net 420 "/FPGA Bank 16 & 17/USR_FLASH_1.~{CS}")
			(pinfunction "IO_L15P_T2_DQS_16")
			(pintype "bidirectional")
			(die_length 22.768)
			(solder_mask_margin 0.02)
		)
		(pad "C30" smd circle
			(at 14.5 -12.5)
			(size 0.5 0.5)
			(property pad_prop_bga)
			(layers "F.Cu" "F.Mask" "F.Paste")
			(net 427 "/FPGA Bank 16 & 17/USR_FLASH_1.CLK")
			(pinfunction "IO_L16N_T2_16")
			(pintype "bidirectional")
			(die_length 23.33)
			(solder_mask_margin 0.02)
		)
		(pad "D1" smd circle
			(at -14.5 -11.5)
			(size 0.5 0.5)
			(property pad_prop_bga)
			(layers "F.Cu" "F.Mask" "F.Paste")
			(net 976 "unconnected-(U1G-MGTXTXN0_118-PadD1)")
			(pinfunction "MGTXTXN0_118")
			(pintype "bidirectional+no_connect")
			(die_length 16.063)
			(solder_mask_margin 0.02)
		)
		(pad "D2" smd circle
			(at -13.5 -11.5)
			(size 0.5 0.5)
			(property pad_prop_bga)
			(layers "F.Cu" "F.Mask" "F.Paste")
			(net 977 "unconnected-(U1G-MGTXTXP0_118-PadD2)")
			(pinfunction "MGTXTXP0_118")
			(pintype "bidirectional+no_connect")
			(die_length 16.112)
			(solder_mask_margin 0.02)
		)
		(pad "D3" smd circle
			(at -12.5 -11.5)
			(size 0.5 0.5)
			(property pad_prop_bga)
			(layers "F.Cu" "F.Mask" "F.Paste")
			(net 8 "+1V2_MGTAVTT")
			(pinfunction "MGTAVTT")
			(pintype "passive")
			(solder_mask_margin 0.02)
		)
		(pad "D4" smd circle
			(at -11.5 -11.5)
			(size 0.5 0.5)
			(property pad_prop_bga)
			(layers "F.Cu" "F.Mask" "F.Paste")
			(net 1 "GND")
			(pinfunction "GND")
			(pintype "passive")
			(solder_mask_margin 0.02)
		)
		(pad "D5" smd circle
			(at -10.5 -11.5)
			(size 0.5 0.5)
			(property pad_prop_bga)
			(layers "F.Cu" "F.Mask" "F.Paste")
			(net 978 "unconnected-(U1G-MGTXRXN1_118-PadD5)")
			(pinfunction "MGTXRXN1_118")
			(pintype "bidirectional+no_connect")
			(die_length 11.844)
			(solder_mask_margin 0.02)
		)
		(pad "D6" smd circle
			(at -9.5 -11.5)
			(size 0.5 0.5)
			(property pad_prop_bga)
			(layers "F.Cu" "F.Mask" "F.Paste")
			(net 982 "unconnected-(U1G-MGTXRXP1_118-PadD6)")
			(pinfunction "MGTXRXP1_118")
			(pintype "bidirectional+no_connect")
			(die_length 12)
			(solder_mask_margin 0.02)
		)
		(pad "D7" smd circle
			(at -8.5 -11.5)
			(size 0.5 0.5)
			(property pad_prop_bga)
			(layers "F.Cu" "F.Mask" "F.Paste")
			(net 6 "+1V0_MGTAVCC")
			(pinfunction "MGTAVCC")
			(pintype "passive")
			(solder_mask_margin 0.02)
		)
		(pad "D8" smd circle
			(at -7.5 -11.5)
			(size 0.5 0.5)
			(property pad_prop_bga)
			(layers "F.Cu" "F.Mask" "F.Paste")
			(net 1 "GND")
			(pinfunction "GND")
			(pintype "passive")
			(solder_mask_margin 0.02)
		)
		(pad "D9" smd circle
			(at -6.5 -11.5)
			(size 0.5 0.5)
			(property pad_prop_bga)
			(layers "F.Cu" "F.Mask" "F.Paste")
			(net 1 "GND")
			(pinfunction "GND")
			(pintype "passive")
			(solder_mask_margin 0.02)
		)
		(pad "D10" smd circle
			(at -5.5 -11.5)
			(size 0.5 0.5)
			(property pad_prop_bga)
			(layers "F.Cu" "F.Mask" "F.Paste")
			(net 24 "+3V3")
			(pinfunction "VCCO_18")
			(pintype "passive")
			(solder_mask_margin 0.02)
		)
		(pad "D11" smd circle
			(at -4.5 -11.5)
			(size 0.5 0.5)
			(property pad_prop_bga)
			(layers "F.Cu" "F.Mask" "F.Paste")
			(net 254 "/FMC+ HSPC/FMC.IO18_P")
			(pinfunction "IO_L18P_T2_18")
			(pintype "bidirectional")
			(die_length 23.711)
			(solder_mask_margin 0.02)
		)
		(pad "D12" smd circle
			(at -3.5 -11.5)
			(size 0.5 0.5)
			(property pad_prop_bga)
			(layers "F.Cu" "F.Mask" "F.Paste")
			(net 424 "/FMC+ HSPC/FMC.IO13_P")
			(pinfunction "IO_L13P_T2_MRCC_18")
			(pintype "bidirectional")
			(die_length 22.434)
			(solder_mask_margin 0.02)
		)
		(pad "D13" smd circle
			(at -2.5 -11.5)
			(size 0.5 0.5)
			(property pad_prop_bga)
			(layers "F.Cu" "F.Mask" "F.Paste")
			(net 423 "/FMC+ HSPC/FMC.IO13_N")
			(pinfunction "IO_L13N_T2_MRCC_18")
			(pintype "bidirectional")
			(die_length 22.524)
			(solder_mask_margin 0.02)
		)
		(pad "D14" smd circle
			(at -1.5 -11.5)
			(size 0.5 0.5)
			(property pad_prop_bga)
			(layers "F.Cu" "F.Mask" "F.Paste")
			(net 239 "/FMC+ HSPC/FMC.IO21_P")
			(pinfunction "IO_L21P_T3_DQS_18")
			(pintype "bidirectional")
			(die_length 22.264)
			(solder_mask_margin 0.02)
		)
		(pad "D15" smd circle
			(at -0.5 -11.5)
			(size 0.5 0.5)
			(property pad_prop_bga)
			(layers "F.Cu" "F.Mask" "F.Paste")
			(net 1 "GND")
			(pinfunction "GND")
			(pintype "passive")
			(solder_mask_margin 0.02)
		)
		(pad "D16" smd circle
			(at 0.5 -11.5)
			(size 0.5 0.5)
			(property pad_prop_bga)
			(layers "F.Cu" "F.Mask" "F.Paste")
			(net 505 "/FPGA Bank 16 & 17/GBE_RGMII.RXD1")
			(pinfunction "IO_L15P_T2_DQS_17")
			(pintype "bidirectional")
			(die_length 23.582)
			(solder_mask_margin 0.02)
		)
		(pad "D17" smd circle
			(at 1.5 -11.5)
			(size 0.5 0.5)
			(property pad_prop_bga)
			(layers "F.Cu" "F.Mask" "F.Paste")
			(net 507 "/FPGA Bank 16 & 17/GBE_RGMII.GTR_CLK")
			(pinfunction "IO_L13P_T2_MRCC_17")
			(pintype "bidirectional")
			(die_length 21.562)
			(solder_mask_margin 0.02)
		)
		(pad "D18" smd circle
			(at 2.5 -11.5)
			(size 0.5 0.5)
			(property pad_prop_bga)
			(layers "F.Cu" "F.Mask" "F.Paste")
			(net 523 "/FPGA Bank 16 & 17/GBE_RGMII.MDIO")
			(pinfunction "IO_L13N_T2_MRCC_17")
			(pintype "bidirectional")
			(die_length 21.659)
			(solder_mask_margin 0.02)
		)
		(pad "D19" smd circle
			(at 3.5 -11.5)
			(size 0.5 0.5)
			(property pad_prop_bga)
			(layers "F.Cu" "F.Mask" "F.Paste")
			(net 522 "/FPGA Bank 16 & 17/GBE_RGMII.~{RESET}")
			(pinfunction "IO_L14N_T2_SRCC_17")
			(pintype "bidirectional")
			(die_length 20.704)
			(solder_mask_margin 0.02)
		)
		(pad "D20" smd circle
			(at 4.5 -11.5)
			(size 0.5 0.5)
			(property pad_prop_bga)
			(layers "F.Cu" "F.Mask" "F.Paste")
			(net 24 "+3V3")
			(pinfunction "VCCO_17")
			(pintype "passive")
			(solder_mask_margin 0.02)
		)
		(pad "D21" smd circle
			(at 5.5 -11.5)
			(size 0.5 0.5)
			(property pad_prop_bga)
			(layers "F.Cu" "F.Mask" "F.Paste")
			(net 528 "/FPGA Bank 16 & 17/HDMI.D0_P")
			(pinfunction "IO_L8P_T1_17")
			(pintype "bidirectional")
			(die_length 15.622)
			(solder_mask_margin 0.02)
		)
		(pad "D22" smd circle
			(at 6.5 -11.5)
			(size 0.5 0.5)
			(property pad_prop_bga)
			(layers "F.Cu" "F.Mask" "F.Paste")
			(net 984 "unconnected-(U1C-IO_L10P_T1_17-PadD22)")
			(pinfunction "IO_L10P_T1_17")
			(pintype "bidirectional+no_connect")
			(die_length 15.866)
			(solder_mask_margin 0.02)
		)
		(pad "D23" smd circle
			(at 7.5 -11.5)
			(size 0.5 0.5)
			(property pad_prop_bga)
			(layers "F.Cu" "F.Mask" "F.Paste")
			(net 875 "unconnected-(U1C-IO_L2N_T0_16-PadD23)")
			(pinfunction "IO_L2N_T0_16")
			(pintype "bidirectional+no_connect")
			(die_length 19.449)
			(solder_mask_margin 0.02)
		)
		(pad "D24" smd circle
			(at 8.5 -11.5)
			(size 0.5 0.5)
			(property pad_prop_bga)
			(layers "F.Cu" "F.Mask" "F.Paste")
			(net 877 "unconnected-(U1C-IO_L4N_T0_16-PadD24)")
			(pinfunction "IO_L4N_T0_16")
			(pintype "bidirectional+no_connect")
			(die_length 20.101)
			(solder_mask_margin 0.02)
		)
		(pad "D25" smd circle
			(at 9.5 -11.5)
			(size 0.5 0.5)
			(property pad_prop_bga)
			(layers "F.Cu" "F.Mask" "F.Paste")
			(net 1 "GND")
			(pinfunction "GND")
			(pintype "passive")
			(solder_mask_margin 0.02)
		)
		(pad "D26" smd circle
			(at 10.5 -11.5)
			(size 0.5 0.5)
			(property pad_prop_bga)
			(layers "F.Cu" "F.Mask" "F.Paste")
			(net 879 "unconnected-(U1C-IO_L11P_T1_SRCC_16-PadD26)")
			(pinfunction "IO_L11P_T1_SRCC_16")
			(pintype "bidirectional+no_connect")
			(die_length 20.509)
			(solder_mask_margin 0.02)
		)
		(pad "D27" smd circle
			(at 11.5 -11.5)
			(size 0.5 0.5)
			(property pad_prop_bga)
			(layers "F.Cu" "F.Mask" "F.Paste")
			(net 1266 "/USER_IO.B1")
			(pinfunction "IO_L13P_T2_MRCC_16")
			(pintype "bidirectional")
			(die_length 20.812)
			(solder_mask_margin 0.02)
		)
		(pad "D28" smd circle
			(at 12.5 -11.5)
			(size 0.5 0.5)
			(property pad_prop_bga)
			(layers "F.Cu" "F.Mask" "F.Paste")
			(net 1292 "/USER_IO.B32")
			(pinfunction "IO_L14N_T2_SRCC_16")
			(pintype "bidirectional")
			(die_length 21.301)
			(solder_mask_margin 0.02)
		)
		(pad "D29" smd circle
			(at 13.5 -11.5)
			(size 0.5 0.5)
			(property pad_prop_bga)
			(layers "F.Cu" "F.Mask" "F.Paste")
			(net 884 "unconnected-(U1C-IO_L16P_T2_16-PadD29)")
			(pinfunction "IO_L16P_T2_16")
			(pintype "bidirectional+no_connect")
			(die_length 22.353)
			(solder_mask_margin 0.02)
		)
		(pad "D30" smd circle
			(at 14.5 -11.5)
			(size 0.5 0.5)
			(property pad_prop_bga)
			(layers "F.Cu" "F.Mask" "F.Paste")
			(net 3 "VCC_USR_B")
			(pinfunction "VCCO_16")
			(pintype "passive")
			(solder_mask_margin 0.02)
		)
		(pad "E1" smd circle
			(at -14.5 -10.5)
			(size 0.5 0.5)
			(property pad_prop_bga)
			(layers "F.Cu" "F.Mask" "F.Paste")
			(net 1 "GND")
			(pinfunction "GND")
			(pintype "passive")
			(solder_mask_margin 0.02)
		)
		(pad "E2" smd circle
			(at -13.5 -10.5)
			(size 0.5 0.5)
			(property pad_prop_bga)
			(layers "F.Cu" "F.Mask" "F.Paste")
			(net 1 "GND")
			(pinfunction "GND")
			(pintype "passive")
			(solder_mask_margin 0.02)
		)
		(pad "E3" smd circle
			(at -12.5 -10.5)
			(size 0.5 0.5)
			(property pad_prop_bga)
			(layers "F.Cu" "F.Mask" "F.Paste")
			(net 985 "unconnected-(U1G-MGTXRXN0_118-PadE3)")
			(pinfunction "MGTXRXN0_118")
			(pintype "bidirectional+no_connect")
			(die_length 14.064)
			(solder_mask_margin 0.02)
		)
		(pad "E4" smd circle
			(at -11.5 -10.5)
			(size 0.5 0.5)
			(property pad_prop_bga)
			(layers "F.Cu" "F.Mask" "F.Paste")
			(net 986 "unconnected-(U1G-MGTXRXP0_118-PadE4)")
			(pinfunction "MGTXRXP0_118")
			(pintype "bidirectional+no_connect")
			(die_length 14.131)
			(solder_mask_margin 0.02)
		)
		(pad "E5" smd circle
			(at -10.5 -10.5)
			(size 0.5 0.5)
			(property pad_prop_bga)
			(layers "F.Cu" "F.Mask" "F.Paste")
			(net 8 "+1V2_MGTAVTT")
			(pinfunction "MGTAVTT")
			(pintype "passive")
			(solder_mask_margin 0.02)
		)
		(pad "E6" smd circle
			(at -9.5 -10.5)
			(size 0.5 0.5)
			(property pad_prop_bga)
			(layers "F.Cu" "F.Mask" "F.Paste")
			(net 1 "GND")
			(pinfunction "GND")
			(pintype "passive")
			(solder_mask_margin 0.02)
		)
		(pad "E7" smd circle
			(at -8.5 -10.5)
			(size 0.5 0.5)
			(property pad_prop_bga)
			(layers "F.Cu" "F.Mask" "F.Paste")
			(net 987 "unconnected-(U1G-MGTREFCLK1N_118-PadE7)")
			(pinfunction "MGTREFCLK1N_118")
			(pintype "bidirectional+no_connect")
			(die_length 12.062)
			(solder_mask_margin 0.02)
		)
		(pad "E8" smd circle
			(at -7.5 -10.5)
			(size 0.5 0.5)
			(property pad_prop_bga)
			(layers "F.Cu" "F.Mask" "F.Paste")
			(net 991 "unconnected-(U1G-MGTREFCLK1P_118-PadE8)")
			(pinfunction "MGTREFCLK1P_118")
			(pintype "bidirectional+no_connect")
			(die_length 11.842)
			(solder_mask_margin 0.02)
		)
		(pad "E9" smd circle
			(at -6.5 -10.5)
			(size 0.5 0.5)
			(property pad_prop_bga)
			(layers "F.Cu" "F.Mask" "F.Paste")
			(net 1 "GND")
			(pinfunction "GND")
			(pintype "passive")
			(solder_mask_margin 0.02)
		)
		(pad "E10" smd circle
			(at -5.5 -10.5)
			(size 0.5 0.5)
			(property pad_prop_bga)
			(layers "F.Cu" "F.Mask" "F.Paste")
			(net 165 "/FPGA Config/JTAG.TCK")
			(pinfunction "TCK_0")
			(pintype "bidirectional")
			(die_length 26.06)
			(solder_mask_margin 0.02)
		)
		(pad "E11" smd circle
			(at -4.5 -10.5)
			(size 0.5 0.5)
			(property pad_prop_bga)
			(layers "F.Cu" "F.Mask" "F.Paste")
			(net 268 "/FMC+ HSPC/FMC.IO16_N")
			(pinfunction "IO_L16N_T2_18")
			(pintype "bidirectional")
			(die_length 22.276)
			(solder_mask_margin 0.02)
		)
		(pad "E12" smd circle
			(at -3.5 -10.5)
			(size 0.5 0.5)
			(property pad_prop_bga)
			(layers "F.Cu" "F.Mask" "F.Paste")
			(net 1 "GND")
			(pinfunction "GND")
			(pintype "passive")
			(solder_mask_margin 0.02)
		)
		(pad "E13" smd circle
			(at -2.5 -10.5)
			(size 0.5 0.5)
			(property pad_prop_bga)
			(layers "F.Cu" "F.Mask" "F.Paste")
			(net 351 "/FMC+ HSPC/FMC.IO14_N")
			(pinfunction "IO_L14N_T2_SRCC_18")
			(pintype "bidirectional")
			(die_length 22.055)
			(solder_mask_margin 0.02)
		)
		(pad "E14" smd circle
			(at -1.5 -10.5)
			(size 0.5 0.5)
			(property pad_prop_bga)
			(layers "F.Cu" "F.Mask" "F.Paste")
			(net 337 "/FMC+ HSPC/FMC.IO20_P")
			(pinfunction "IO_L20P_T3_18")
			(pintype "bidirectional")
			(die_length 20.074)
			(solder_mask_margin 0.02)
		)
		(pad "E15" smd circle
			(at -0.5 -10.5)
			(size 0.5 0.5)
			(property pad_prop_bga)
			(layers "F.Cu" "F.Mask" "F.Paste")
			(net 335 "/FMC+ HSPC/FMC.IO20_N")
			(pinfunction "IO_L20N_T3_18")
			(pintype "bidirectional")
			(die_length 20.086)
			(solder_mask_margin 0.02)
		)
		(pad "E16" smd circle
			(at 0.5 -10.5)
			(size 0.5 0.5)
			(property pad_prop_bga)
			(layers "F.Cu" "F.Mask" "F.Paste")
			(net 409 "/FMC+ HSPC/FMC.IO19_N")
			(pinfunction "IO_L19N_T3_VREF_18")
			(pintype "bidirectional")
			(die_length 19.757)
			(solder_mask_margin 0.02)
		)
		(pad "E17" smd circle
			(at 1.5 -10.5)
			(size 0.5 0.5)
			(property pad_prop_bga)
			(layers "F.Cu" "F.Mask" "F.Paste")
			(net 24 "+3V3")
			(pinfunction "VCCO_17")
			(pintype "passive")
			(solder_mask_margin 0.02)
		)
		(pad "E18" smd circle
			(at 2.5 -10.5)
			(size 0.5 0.5)
			(property pad_prop_bga)
			(layers "F.Cu" "F.Mask" "F.Paste")
			(net 509 "/FPGA Bank 16 & 17/GBE_RGMII.RX_DV")
			(pinfunction "IO_25_17")
			(pintype "bidirectional")
			(die_length 22.737)
			(solder_mask_margin 0.02)
		)
		(pad "E19" smd circle
			(at 3.5 -10.5)
			(size 0.5 0.5)
			(property pad_prop_bga)
			(layers "F.Cu" "F.Mask" "F.Paste")
			(net 992 "unconnected-(U1C-IO_L14P_T2_SRCC_17-PadE19)")
			(pinfunction "IO_L14P_T2_SRCC_17")
			(pintype "bidirectional+no_connect")
			(die_length 20.56)
			(solder_mask_margin 0.02)
		)
		(pad "E20" smd circle
			(at 4.5 -10.5)
			(size 0.5 0.5)
			(property pad_prop_bga)
			(layers "F.Cu" "F.Mask" "F.Paste")
			(net 503 "/FPGA Bank 16 & 17/GBE_RGMII.RXD3")
			(pinfunction "IO_L12N_T1_MRCC_17")
			(pintype "bidirectional")
			(die_length 16.829)
			(solder_mask_margin 0.02)
		)
		(pad "E21" smd circle
			(at 5.5 -10.5)
			(size 0.5 0.5)
			(property pad_prop_bga)
			(layers "F.Cu" "F.Mask" "F.Paste")
			(net 993 "/FPGA Bank 16 & 17/GBE_RGMII.TXD3")
			(pinfunction "IO_L11N_T1_SRCC_17")
			(pintype "bidirectional")
			(die_length 16.731)
			(solder_mask_margin 0.02)
		)
		(pad "E22" smd circle
			(at 6.5 -10.5)
			(size 0.5 0.5)
			(property pad_prop_bga)
			(layers "F.Cu" "F.Mask" "F.Paste")
			(net 1 "GND")
			(pinfunction "GND")
			(pintype "passive")
			(solder_mask_margin 0.02)
		)
		(pad "E23" smd circle
			(at 7.5 -10.5)
			(size 0.5 0.5)
			(property pad_prop_bga)
			(layers "F.Cu" "F.Mask" "F.Paste")
			(net 933 "unconnected-(U1C-IO_L2P_T0_16-PadE23)")
			(pinfunction "IO_L2P_T0_16")
			(pintype "bidirectional+no_connect")
			(die_length 18.705)
			(solder_mask_margin 0.02)
		)
		(pad "E24" smd circle
			(at 8.5 -10.5)
			(size 0.5 0.5)
			(property pad_prop_bga)
			(layers "F.Cu" "F.Mask" "F.Paste")
			(net 935 "unconnected-(U1C-IO_L4P_T0_16-PadE24)")
			(pinfunction "IO_L4P_T0_16")
			(pintype "bidirectional+no_connect")
			(die_length 18.397)
			(solder_mask_margin 0.02)
		)
		(pad "E25" smd circle
			(at 9.5 -10.5)
			(size 0.5 0.5)
			(property pad_prop_bga)
			(layers "F.Cu" "F.Mask" "F.Paste")
			(net 936 "unconnected-(U1C-IO_L3N_T0_DQS_16-PadE25)")
			(pinfunction "IO_L3N_T0_DQS_16")
			(pintype "bidirectional+no_connect")
			(die_length 18.213)
			(solder_mask_margin 0.02)
		)
		(pad "E26" smd circle
			(at 10.5 -10.5)
			(size 0.5 0.5)
			(property pad_prop_bga)
			(layers "F.Cu" "F.Mask" "F.Paste")
			(net 937 "unconnected-(U1C-IO_L5N_T0_16-PadE26)")
			(pinfunction "IO_L5N_T0_16")
			(pintype "bidirectional+no_connect")
			(die_length 17.221)
			(solder_mask_margin 0.02)
		)
		(pad "E27" smd circle
			(at 11.5 -10.5)
			(size 0.5 0.5)
			(property pad_prop_bga)
			(layers "F.Cu" "F.Mask" "F.Paste")
			(net 3 "VCC_USR_B")
			(pinfunction "VCCO_16")
			(pintype "passive")
			(solder_mask_margin 0.02)
		)
		(pad "E28" smd circle
			(at 12.5 -10.5)
			(size 0.5 0.5)
			(property pad_prop_bga)
			(layers "F.Cu" "F.Mask" "F.Paste")
			(net 429 "/FPGA Bank 16 & 17/USR_FLASH_1.DQ0")
			(pinfunction "IO_L14P_T2_SRCC_16")
			(pintype "bidirectional")
			(die_length 20.92)
			(solder_mask_margin 0.02)
		)
		(pad "E29" smd circle
			(at 13.5 -10.5)
			(size 0.5 0.5)
			(property pad_prop_bga)
			(layers "F.Cu" "F.Mask" "F.Paste")
			(net 1270 "/USER_IO.B7")
			(pinfunction "IO_L18P_T2_16")
			(pintype "bidirectional")
			(die_length 21.495)
			(solder_mask_margin 0.02)
		)
		(pad "E30" smd circle
			(at 14.5 -10.5)
			(size 0.5 0.5)
			(property pad_prop_bga)
			(layers "F.Cu" "F.Mask" "F.Paste")
			(net 1288 "/USER_IO.B28")
			(pinfunction "IO_L18N_T2_16")
			(pintype "bidirectional")
			(die_length 21.444)
			(solder_mask_margin 0.02)
		)
		(pad "F1" smd circle
			(at -14.5 -9.5)
			(size 0.5 0.5)
			(property pad_prop_bga)
			(layers "F.Cu" "F.Mask" "F.Paste")
			(net 994 "unconnected-(U1G-MGTXTXN3_117-PadF1)")
			(pinfunction "MGTXTXN3_117")
			(pintype "bidirectional+no_connect")
			(die_length 14.68)
			(solder_mask_margin 0.02)
		)
		(pad "F2" smd circle
			(at -13.5 -9.5)
			(size 0.5 0.5)
			(property pad_prop_bga)
			(layers "F.Cu" "F.Mask" "F.Paste")
			(net 995 "unconnected-(U1G-MGTXTXP3_117-PadF2)")
			(pinfunction "MGTXTXP3_117")
			(pintype "bidirectional+no_connect")
			(die_length 14.728)
			(solder_mask_margin 0.02)
		)
		(pad "F3" smd circle
			(at -12.5 -9.5)
			(size 0.5 0.5)
			(property pad_prop_bga)
			(layers "F.Cu" "F.Mask" "F.Paste")
			(net 8 "+1V2_MGTAVTT")
			(pinfunction "MGTAVTT")
			(pintype "passive")
			(solder_mask_margin 0.02)
		)
		(pad "F4" smd circle
			(at -11.5 -9.5)
			(size 0.5 0.5)
			(property pad_prop_bga)
			(layers "F.Cu" "F.Mask" "F.Paste")
			(net 1 "GND")
			(pinfunction "GND")
			(pintype "passive")
			(solder_mask_margin 0.02)
		)
		(pad "F5" smd circle
			(at -10.5 -9.5)
			(size 0.5 0.5)
			(property pad_prop_bga)
			(layers "F.Cu" "F.Mask" "F.Paste")
			(net 999 "unconnected-(U1G-MGTXRXN3_117-PadF5)")
			(pinfunction "MGTXRXN3_117")
			(pintype "bidirectional+no_connect")
			(die_length 10.765)
			(solder_mask_margin 0.02)
		)
		(pad "F6" smd circle
			(at -9.5 -9.5)
			(size 0.5 0.5)
			(property pad_prop_bga)
			(layers "F.Cu" "F.Mask" "F.Paste")
			(net 1000 "unconnected-(U1G-MGTXRXP3_117-PadF6)")
			(pinfunction "MGTXRXP3_117")
			(pintype "bidirectional+no_connect")
			(die_length 10.959)
			(solder_mask_margin 0.02)
		)
		(pad "F7" smd circle
			(at -8.5 -9.5)
			(size 0.5 0.5)
			(property pad_prop_bga)
			(layers "F.Cu" "F.Mask" "F.Paste")
			(net 6 "+1V0_MGTAVCC")
			(pinfunction "MGTAVCC")
			(pintype "passive")
			(solder_mask_margin 0.02)
		)
		(pad "F8" smd circle
			(at -7.5 -9.5)
			(size 0.5 0.5)
			(property pad_prop_bga)
			(layers "F.Cu" "F.Mask" "F.Paste")
			(net 1 "GND")
			(pinfunction "GND")
			(pintype "passive")
			(solder_mask_margin 0.02)
		)
		(pad "F9" smd circle
			(at -6.5 -9.5)
			(size 0.5 0.5)
			(property pad_prop_bga)
			(layers "F.Cu" "F.Mask" "F.Paste")
			(net 1 "GND")
			(pinfunction "GND")
			(pintype "passive")
			(solder_mask_margin 0.02)
		)
		(pad "F10" smd circle
			(at -5.5 -9.5)
			(size 0.5 0.5)
			(property pad_prop_bga)
			(layers "F.Cu" "F.Mask" "F.Paste")
			(net 161 "/FPGA Config/JTAG.TMS")
			(pinfunction "TMS_0")
			(pintype "bidirectional")
			(die_length 26.323)
			(solder_mask_margin 0.02)
		)
		(pad "F11" smd circle
			(at -4.5 -9.5)
			(size 0.5 0.5)
			(property pad_prop_bga)
			(layers "F.Cu" "F.Mask" "F.Paste")
			(net 278 "/FMC+ HSPC/FMC.IO16_P")
			(pinfunction "IO_L16P_T2_18")
			(pintype "bidirectional")
			(die_length 22.906)
			(solder_mask_margin 0.02)
		)
		(pad "F12" smd circle
			(at -3.5 -9.5)
			(size 0.5 0.5)
			(property pad_prop_bga)
			(layers "F.Cu" "F.Mask" "F.Paste")
			(net 352 "/FMC+ HSPC/FMC.IO14_P")
			(pinfunction "IO_L14P_T2_SRCC_18")
			(pintype "bidirectional")
			(die_length 22.763)
			(solder_mask_margin 0.02)
		)
		(pad "F13" smd circle
			(at -2.5 -9.5)
			(size 0.5 0.5)
			(property pad_prop_bga)
			(layers "F.Cu" "F.Mask" "F.Paste")
			(net 353 "/FMC+ HSPC/FMC.IO12_N")
			(pinfunction "IO_L12N_T1_MRCC_18")
			(pintype "bidirectional")
			(die_length 18.979)
			(solder_mask_margin 0.02)
		)
		(pad "F14" smd circle
			(at -1.5 -9.5)
			(size 0.5 0.5)
			(property pad_prop_bga)
			(layers "F.Cu" "F.Mask" "F.Paste")
			(net 24 "+3V3")
			(pinfunction "VCCO_18")
			(pintype "passive")
			(solder_mask_margin 0.02)
		)
		(pad "F15" smd circle
			(at -0.5 -9.5)
			(size 0.5 0.5)
			(property pad_prop_bga)
			(layers "F.Cu" "F.Mask" "F.Paste")
			(net 413 "/FMC+ HSPC/FMC.IO19_P")
			(pinfunction "IO_L19P_T3_18")
			(pintype "bidirectional")
			(die_length 20.661)
			(solder_mask_margin 0.02)
		)
		(pad "F16" smd circle
			(at 0.5 -9.5)
			(size 0.5 0.5)
			(property pad_prop_bga)
			(layers "F.Cu" "F.Mask" "F.Paste")
			(net 334 "/FMC+ HSPC/FMC.IO25")
			(pinfunction "IO_25_18")
			(pintype "bidirectional")
			(die_length 20.14)
			(solder_mask_margin 0.02)
		)
		(pad "F17" smd circle
			(at 1.5 -9.5)
			(size 0.5 0.5)
			(property pad_prop_bga)
			(layers "F.Cu" "F.Mask" "F.Paste")
			(net 1001 "/FPGA Bank 16 & 17/GBE_RGMII.MDC")
			(pinfunction "IO_L18N_T2_17")
			(pintype "bidirectional")
			(die_length 21.72)
			(solder_mask_margin 0.02)
		)
		(pad "F18" smd circle
			(at 2.5 -9.5)
			(size 0.5 0.5)
			(property pad_prop_bga)
			(layers "F.Cu" "F.Mask" "F.Paste")
			(net 508 "/FPGA Bank 16 & 17/GBE_RGMII.~{INT}")
			(pinfunction "IO_L16N_T2_17")
			(pintype "bidirectional")
			(die_length 20.739)
			(solder_mask_margin 0.02)
		)
		(pad "F19" smd circle
			(at 3.5 -9.5)
			(size 0.5 0.5)
			(property pad_prop_bga)
			(layers "F.Cu" "F.Mask" "F.Paste")
			(net 1 "GND")
			(pinfunction "GND")
			(pintype "passive")
			(solder_mask_margin 0.02)
		)
		(pad "F20" smd circle
			(at 4.5 -9.5)
			(size 0.5 0.5)
			(property pad_prop_bga)
			(layers "F.Cu" "F.Mask" "F.Paste")
			(net 504 "/FPGA Bank 16 & 17/GBE_RGMII.RXD2")
			(pinfunction "IO_L12P_T1_MRCC_17")
			(pintype "bidirectional")
			(die_length 16.91)
			(solder_mask_margin 0.02)
		)
		(pad "F21" smd circle
			(at 5.5 -9.5)
			(size 0.5 0.5)
			(property pad_prop_bga)
			(layers "F.Cu" "F.Mask" "F.Paste")
			(net 1002 "/FPGA Bank 16 & 17/GBE_RGMII.TXD2")
			(pinfunction "IO_L11P_T1_SRCC_17")
			(pintype "bidirectional")
			(die_length 16.319)
			(solder_mask_margin 0.02)
		)
		(pad "F22" smd circle
			(at 6.5 -9.5)
			(size 0.5 0.5)
			(property pad_prop_bga)
			(layers "F.Cu" "F.Mask" "F.Paste")
			(net 1003 "unconnected-(U1C-IO_L9N_T1_DQS_17-PadF22)")
			(pinfunction "IO_L9N_T1_DQS_17")
			(pintype "bidirectional+no_connect")
			(die_length 13.808)
			(solder_mask_margin 0.02)
		)
		(pad "F23" smd circle
			(at 7.5 -9.5)
			(size 0.5 0.5)
			(property pad_prop_bga)
			(layers "F.Cu" "F.Mask" "F.Paste")
			(net 979 "unconnected-(U1C-IO_0_16-PadF23)")
			(pinfunction "IO_0_16")
			(pintype "bidirectional+no_connect")
			(die_length 17.681)
			(solder_mask_margin 0.02)
		)
		(pad "F24" smd circle
			(at 8.5 -9.5)
			(size 0.5 0.5)
			(property pad_prop_bga)
			(layers "F.Cu" "F.Mask" "F.Paste")
			(net 3 "VCC_USR_B")
			(pinfunction "VCCO_16")
			(pintype "passive")
			(solder_mask_margin 0.02)
		)
		(pad "F25" smd circle
			(at 9.5 -9.5)
			(size 0.5 0.5)
			(property pad_prop_bga)
			(layers "F.Cu" "F.Mask" "F.Paste")
			(net 980 "unconnected-(U1C-IO_L3P_T0_DQS_16-PadF25)")
			(pinfunction "IO_L3P_T0_DQS_16")
			(pintype "bidirectional+no_connect")
			(die_length 18.196)
			(solder_mask_margin 0.02)
		)
		(pad "F26" smd circle
			(at 10.5 -9.5)
			(size 0.5 0.5)
			(property pad_prop_bga)
			(layers "F.Cu" "F.Mask" "F.Paste")
			(net 981 "unconnected-(U1C-IO_L5P_T0_16-PadF26)")
			(pinfunction "IO_L5P_T0_16")
			(pintype "bidirectional+no_connect")
			(die_length 17.252)
			(solder_mask_margin 0.02)
		)
		(pad "F27" smd circle
			(at 11.5 -9.5)
			(size 0.5 0.5)
			(property pad_prop_bga)
			(layers "F.Cu" "F.Mask" "F.Paste")
			(net 1291 "/USER_IO.B31")
			(pinfunction "IO_L21N_T3_DQS_16")
			(pintype "bidirectional")
			(die_length 19.729)
			(solder_mask_margin 0.02)
		)
		(pad "F28" smd circle
			(at 12.5 -9.5)
			(size 0.5 0.5)
			(property pad_prop_bga)
			(layers "F.Cu" "F.Mask" "F.Paste")
			(net 1282 "/USER_IO.B21")
			(pinfunction "IO_L20N_T3_16")
			(pintype "bidirectional")
			(die_length 20.204)
			(solder_mask_margin 0.02)
		)
		(pad "F29" smd circle
			(at 13.5 -9.5)
			(size 0.5 0.5)
			(property pad_prop_bga)
			(layers "F.Cu" "F.Mask" "F.Paste")
			(net 1 "GND")
			(pinfunction "GND")
			(pintype "passive")
			(solder_mask_margin 0.02)
		)
		(pad "F30" smd circle
			(at 14.5 -9.5)
			(size 0.5 0.5)
			(property pad_prop_bga)
			(layers "F.Cu" "F.Mask" "F.Paste")
			(net 1281 "/USER_IO.B19")
			(pinfunction "IO_L22N_T3_16")
			(pintype "bidirectional")
			(die_length 20.812)
			(solder_mask_margin 0.02)
		)
		(pad "G1" smd circle
			(at -14.5 -8.5)
			(size 0.5 0.5)
			(property pad_prop_bga)
			(layers "F.Cu" "F.Mask" "F.Paste")
			(net 1 "GND")
			(pinfunction "GND")
			(pintype "passive")
			(solder_mask_margin 0.02)
		)
		(pad "G2" smd circle
			(at -13.5 -8.5)
			(size 0.5 0.5)
			(property pad_prop_bga)
			(layers "F.Cu" "F.Mask" "F.Paste")
			(net 1 "GND")
			(pinfunction "GND")
			(pintype "passive")
			(solder_mask_margin 0.02)
		)
		(pad "G3" smd circle
			(at -12.5 -8.5)
			(size 0.5 0.5)
			(property pad_prop_bga)
			(layers "F.Cu" "F.Mask" "F.Paste")
			(net 1004 "unconnected-(U1G-MGTXRXN2_117-PadG3)")
			(pinfunction "MGTXRXN2_117")
			(pintype "bidirectional+no_connect")
			(die_length 12.896)
			(solder_mask_margin 0.02)
		)
		(pad "G4" smd circle
			(at -11.5 -8.5)
			(size 0.5 0.5)
			(property pad_prop_bga)
			(layers "F.Cu" "F.Mask" "F.Paste")
			(net 1005 "unconnected-(U1G-MGTXRXP2_117-PadG4)")
			(pinfunction "MGTXRXP2_117")
			(pintype "bidirectional+no_connect")
			(die_length 12.853)
			(solder_mask_margin 0.02)
		)
		(pad "G5" smd circle
			(at -10.5 -8.5)
			(size 0.5 0.5)
			(property pad_prop_bga)
			(layers "F.Cu" "F.Mask" "F.Paste")
			(net 8 "+1V2_MGTAVTT")
			(pinfunction "MGTAVTT")
			(pintype "passive")
			(solder_mask_margin 0.02)
		)
		(pad "G6" smd circle
			(at -9.5 -8.5)
			(size 0.5 0.5)
			(property pad_prop_bga)
			(layers "F.Cu" "F.Mask" "F.Paste")
			(net 1 "GND")
			(pinfunction "GND")
			(pintype "passive")
			(solder_mask_margin 0.02)
		)
		(pad "G7" smd circle
			(at -8.5 -8.5)
			(size 0.5 0.5)
			(property pad_prop_bga)
			(layers "F.Cu" "F.Mask" "F.Paste")
			(net 1006 "unconnected-(U1G-MGTREFCLK0N_117-PadG7)")
			(pinfunction "MGTREFCLK0N_117")
			(pintype "bidirectional+no_connect")
			(die_length 10.176)
			(solder_mask_margin 0.02)
		)
		(pad "G8" smd circle
			(at -7.5 -8.5)
			(size 0.5 0.5)
			(property pad_prop_bga)
			(layers "F.Cu" "F.Mask" "F.Paste")
			(net 1007 "unconnected-(U1G-MGTREFCLK0P_117-PadG8)")
			(pinfunction "MGTREFCLK0P_117")
			(pintype "bidirectional+no_connect")
			(die_length 9.73)
			(solder_mask_margin 0.02)
		)
		(pad "G9" smd circle
			(at -6.5 -8.5)
			(size 0.5 0.5)
			(property pad_prop_bga)
			(layers "F.Cu" "F.Mask" "F.Paste")
			(net 1 "GND")
			(pinfunction "GND")
			(pintype "passive")
			(solder_mask_margin 0.02)
		)
		(pad "G10" smd circle
			(at -5.5 -8.5)
			(size 0.5 0.5)
			(property pad_prop_bga)
			(layers "F.Cu" "F.Mask" "F.Paste")
			(net 190 "/FPGA Config/JTAG.TDO")
			(pinfunction "TDO_0")
			(pintype "bidirectional")
			(die_length 23.572)
			(solder_mask_margin 0.02)
		)
		(pad "G11" smd circle
			(at -4.5 -8.5)
			(size 0.5 0.5)
			(property pad_prop_bga)
			(layers "F.Cu" "F.Mask" "F.Paste")
			(net 24 "+3V3")
			(pinfunction "VCCO_18")
			(pintype "passive")
			(solder_mask_margin 0.02)
		)
		(pad "G12" smd circle
			(at -3.5 -8.5)
			(size 0.5 0.5)
			(property pad_prop_bga)
			(layers "F.Cu" "F.Mask" "F.Paste")
			(net 373 "/FMC+ HSPC/FMC.IO0")
			(pinfunction "IO_0_18")
			(pintype "bidirectional")
			(die_length 15.365)
			(solder_mask_margin 0.02)
		)
		(pad "G13" smd circle
			(at -2.5 -8.5)
			(size 0.5 0.5)
			(property pad_prop_bga)
			(layers "F.Cu" "F.Mask" "F.Paste")
			(net 354 "/FMC+ HSPC/FMC.IO12_P")
			(pinfunction "IO_L12P_T1_MRCC_18")
			(pintype "bidirectional")
			(die_length 18.803)
			(solder_mask_margin 0.02)
		)
		(pad "G14" smd circle
			(at -1.5 -8.5)
			(size 0.5 0.5)
			(property pad_prop_bga)
			(layers "F.Cu" "F.Mask" "F.Paste")
			(net 339 "/FMC+ HSPC/FMC.IO11_N")
			(pinfunction "IO_L11N_T1_SRCC_18")
			(pintype "bidirectional")
			(die_length 18.243)
			(solder_mask_margin 0.02)
		)
		(pad "G15" smd circle
			(at -0.5 -8.5)
			(size 0.5 0.5)
			(property pad_prop_bga)
			(layers "F.Cu" "F.Mask" "F.Paste")
			(net 384 "/FMC+ HSPC/FMC.IO7_N")
			(pinfunction "IO_L7N_T1_18")
			(pintype "bidirectional")
			(die_length 15.863)
			(solder_mask_margin 0.02)
		)
		(pad "G16" smd circle
			(at 0.5 -8.5)
			(size 0.5 0.5)
			(property pad_prop_bga)
			(layers "F.Cu" "F.Mask" "F.Paste")
			(net 1 "GND")
			(pinfunction "GND")
			(pintype "passive")
			(solder_mask_margin 0.02)
		)
		(pad "G17" smd circle
			(at 1.5 -8.5)
			(size 0.5 0.5)
			(property pad_prop_bga)
			(layers "F.Cu" "F.Mask" "F.Paste")
			(net 506 "/FPGA Bank 16 & 17/GBE_RGMII.RXD0")
			(pinfunction "IO_L18P_T2_17")
			(pintype "bidirectional")
			(die_length 20.206)
			(solder_mask_margin 0.02)
		)
		(pad "G18" smd circle
			(at 2.5 -8.5)
			(size 0.5 0.5)
			(property pad_prop_bga)
			(layers "F.Cu" "F.Mask" "F.Paste")
			(net 510 "/FPGA Bank 16 & 17/GBE_RGMII.REFCLK")
			(pinfunction "IO_L16P_T2_17")
			(pintype "bidirectional")
			(die_length 20.974)
			(solder_mask_margin 0.02)
		)
		(pad "G19" smd circle
			(at 3.5 -8.5)
			(size 0.5 0.5)
			(property pad_prop_bga)
			(layers "F.Cu" "F.Mask" "F.Paste")
			(net 695 "/FMC+ HSPC/FMC.~{PERST}")
			(pinfunction "IO_0_17")
			(pintype "bidirectional")
			(die_length 9.384)
			(solder_mask_margin 0.02)
		)
		(pad "G20" smd circle
			(at 4.5 -8.5)
			(size 0.5 0.5)
			(property pad_prop_bga)
			(layers "F.Cu" "F.Mask" "F.Paste")
			(net 1008 "/FPGA Bank 16 & 17/GBE_RGMII.TX_EN")
			(pinfunction "IO_L2N_T0_17")
			(pintype "bidirectional")
			(die_length 9.241)
			(solder_mask_margin 0.02)
		)
		(pad "G21" smd circle
			(at 5.5 -8.5)
			(size 0.5 0.5)
			(property pad_prop_bga)
			(layers "F.Cu" "F.Mask" "F.Paste")
			(net 24 "+3V3")
			(pinfunction "VCCO_17")
			(pintype "passive")
			(solder_mask_margin 0.02)
		)
		(pad "G22" smd circle
			(at 6.5 -8.5)
			(size 0.5 0.5)
			(property pad_prop_bga)
			(layers "F.Cu" "F.Mask" "F.Paste")
			(net 1009 "unconnected-(U1C-IO_L9P_T1_DQS_17-PadG22)")
			(pinfunction "IO_L9P_T1_DQS_17")
			(pintype "bidirectional+no_connect")
			(die_length 13.687)
			(solder_mask_margin 0.02)
		)
		(pad "G23" smd circle
			(at 7.5 -8.5)
			(size 0.5 0.5)
			(property pad_prop_bga)
			(layers "F.Cu" "F.Mask" "F.Paste")
			(net 988 "unconnected-(U1C-IO_L6P_T0_16-PadG23)")
			(pinfunction "IO_L6P_T0_16")
			(pintype "bidirectional+no_connect")
			(die_length 17.196)
			(solder_mask_margin 0.02)
		)
		(pad "G24" smd circle
			(at 8.5 -8.5)
			(size 0.5 0.5)
			(property pad_prop_bga)
			(layers "F.Cu" "F.Mask" "F.Paste")
			(net 989 "unconnected-(U1C-IO_L6N_T0_VREF_16-PadG24)")
			(pinfunction "IO_L6N_T0_VREF_16")
			(pintype "bidirectional+no_connect")
			(die_length 16.995)
			(solder_mask_margin 0.02)
		)
		(pad "G25" smd circle
			(at 9.5 -8.5)
			(size 0.5 0.5)
			(property pad_prop_bga)
			(layers "F.Cu" "F.Mask" "F.Paste")
			(net 990 "unconnected-(U1C-IO_25_16-PadG25)")
			(pinfunction "IO_25_16")
			(pintype "bidirectional+no_connect")
			(die_length 20.465)
			(solder_mask_margin 0.02)
		)
		(pad "G26" smd circle
			(at 10.5 -8.5)
			(size 0.5 0.5)
			(property pad_prop_bga)
			(layers "F.Cu" "F.Mask" "F.Paste")
			(net 1 "GND")
			(pinfunction "GND")
			(pintype "passive")
			(solder_mask_margin 0.02)
		)
		(pad "G27" smd circle
			(at 11.5 -8.5)
			(size 0.5 0.5)
			(property pad_prop_bga)
			(layers "F.Cu" "F.Mask" "F.Paste")
			(net 1293 "/USER_IO.B33")
			(pinfunction "IO_L21P_T3_DQS_16")
			(pintype "bidirectional")
			(die_length 19.597)
			(solder_mask_margin 0.02)
		)
		(pad "G28" smd circle
			(at 12.5 -8.5)
			(size 0.5 0.5)
			(property pad_prop_bga)
			(layers "F.Cu" "F.Mask" "F.Paste")
			(net 1283 "/USER_IO.B23")
			(pinfunction "IO_L20P_T3_16")
			(pintype "bidirectional")
			(die_length 19.625)
			(solder_mask_margin 0.02)
		)
		(pad "G29" smd circle
			(at 13.5 -8.5)
			(size 0.5 0.5)
			(property pad_prop_bga)
			(layers "F.Cu" "F.Mask" "F.Paste")
			(net 1279 "/USER_IO.B17")
			(pinfunction "IO_L22P_T3_16")
			(pintype "bidirectional")
			(die_length 20.638)
			(solder_mask_margin 0.02)
		)
		(pad "G30" smd circle
			(at 14.5 -8.5)
			(size 0.5 0.5)
			(property pad_prop_bga)
			(layers "F.Cu" "F.Mask" "F.Paste")
			(net 1285 "/USER_IO.B25")
			(pinfunction "IO_L24N_T3_16")
			(pintype "bidirectional")
			(die_length 20.043)
			(solder_mask_margin 0.02)
		)
		(pad "H1" smd circle
			(at -14.5 -7.5)
			(size 0.5 0.5)
			(property pad_prop_bga)
			(layers "F.Cu" "F.Mask" "F.Paste")
			(net 1010 "unconnected-(U1G-MGTXTXN2_117-PadH1)")
			(pinfunction "MGTXTXN2_117")
			(pintype "bidirectional+no_connect")
			(die_length 14.476)
			(solder_mask_margin 0.02)
		)
		(pad "H2" smd circle
			(at -13.5 -7.5)
			(size 0.5 0.5)
			(property pad_prop_bga)
			(layers "F.Cu" "F.Mask" "F.Paste")
			(net 1011 "unconnected-(U1G-MGTXTXP2_117-PadH2)")
			(pinfunction "MGTXTXP2_117")
			(pintype "bidirectional+no_connect")
			(die_length 14.439)
			(solder_mask_margin 0.02)
		)
		(pad "H3" smd circle
			(at -12.5 -7.5)
			(size 0.5 0.5)
			(property pad_prop_bga)
			(layers "F.Cu" "F.Mask" "F.Paste")
			(net 8 "+1V2_MGTAVTT")
			(pinfunction "MGTAVTT")
			(pintype "passive")
			(solder_mask_margin 0.02)
		)
		(pad "H4" smd circle
			(at -11.5 -7.5)
			(size 0.5 0.5)
			(property pad_prop_bga)
			(layers "F.Cu" "F.Mask" "F.Paste")
			(net 1 "GND")
			(pinfunction "GND")
			(pintype "passive")
			(solder_mask_margin 0.02)
		)
		(pad "H5" smd circle
			(at -10.5 -7.5)
			(size 0.5 0.5)
			(property pad_prop_bga)
			(layers "F.Cu" "F.Mask" "F.Paste")
			(net 1012 "unconnected-(U1G-MGTXRXN1_117-PadH5)")
			(pinfunction "MGTXRXN1_117")
			(pintype "bidirectional+no_connect")
			(die_length 11.235)
			(solder_mask_margin 0.02)
		)
		(pad "H6" smd circle
			(at -9.5 -7.5)
			(size 0.5 0.5)
			(property pad_prop_bga)
			(layers "F.Cu" "F.Mask" "F.Paste")
			(net 1013 "unconnected-(U1G-MGTXRXP1_117-PadH6)")
			(pinfunction "MGTXRXP1_117")
			(pintype "bidirectional+no_connect")
			(die_length 11.4)
			(solder_mask_margin 0.02)
		)
		(pad "H7" smd circle
			(at -8.5 -7.5)
			(size 0.5 0.5)
			(property pad_prop_bga)
			(layers "F.Cu" "F.Mask" "F.Paste")
			(net 6 "+1V0_MGTAVCC")
			(pinfunction "MGTAVCC")
			(pintype "passive")
			(solder_mask_margin 0.02)
		)
		(pad "H8" smd circle
			(at -7.5 -7.5)
			(size 0.5 0.5)
			(property pad_prop_bga)
			(layers "F.Cu" "F.Mask" "F.Paste")
			(net 1 "GND")
			(pinfunction "GND")
			(pintype "passive")
			(solder_mask_margin 0.02)
		)
		(pad "H9" smd circle
			(at -6.5 -7.5)
			(size 0.5 0.5)
			(property pad_prop_bga)
			(layers "F.Cu" "F.Mask" "F.Paste")
			(net 1 "GND")
			(pinfunction "GND")
			(pintype "passive")
			(solder_mask_margin 0.02)
		)
		(pad "H10" smd circle
			(at -5.5 -7.5)
			(size 0.5 0.5)
			(property pad_prop_bga)
			(layers "F.Cu" "F.Mask" "F.Paste")
			(net 220 "/FPGA Config/JTAG.TDI")
			(pinfunction "TDI_0")
			(pintype "bidirectional")
			(die_length 23.171)
			(solder_mask_margin 0.02)
		)
		(pad "H11" smd circle
			(at -4.5 -7.5)
			(size 0.5 0.5)
			(property pad_prop_bga)
			(layers "F.Cu" "F.Mask" "F.Paste")
			(net 400 "/FMC+ HSPC/FMC.IO10_P")
			(pinfunction "IO_L10P_T1_18")
			(pintype "bidirectional")
			(die_length 20.026)
			(solder_mask_margin 0.02)
		)
		(pad "H12" smd circle
			(at -3.5 -7.5)
			(size 0.5 0.5)
			(property pad_prop_bga)
			(layers "F.Cu" "F.Mask" "F.Paste")
			(net 396 "/FMC+ HSPC/FMC.IO10_N")
			(pinfunction "IO_L10N_T1_18")
			(pintype "bidirectional")
			(die_length 20.278)
			(solder_mask_margin 0.02)
		)
		(pad "H13" smd circle
			(at -2.5 -7.5)
			(size 0.5 0.5)
			(property pad_prop_bga)
			(layers "F.Cu" "F.Mask" "F.Paste")
			(net 1 "GND")
			(pinfunction "GND")
			(pintype "passive")
			(solder_mask_margin 0.02)
		)
		(pad "H14" smd circle
			(at -1.5 -7.5)
			(size 0.5 0.5)
			(property pad_prop_bga)
			(layers "F.Cu" "F.Mask" "F.Paste")
			(net 340 "/FMC+ HSPC/FMC.IO11_P")
			(pinfunction "IO_L11P_T1_SRCC_18")
			(pintype "bidirectional")
			(die_length 18.828)
			(solder_mask_margin 0.02)
		)
		(pad "H15" smd circle
			(at -0.5 -7.5)
			(size 0.5 0.5)
			(property pad_prop_bga)
			(layers "F.Cu" "F.Mask" "F.Paste")
			(net 387 "/FMC+ HSPC/FMC.IO7_P")
			(pinfunction "IO_L7P_T1_18")
			(pintype "bidirectional")
			(die_length 15.975)
			(solder_mask_margin 0.02)
		)
		(pad "H16" smd circle
			(at 0.5 -7.5)
			(size 0.5 0.5)
			(property pad_prop_bga)
			(layers "F.Cu" "F.Mask" "F.Paste")
			(net 377 "/FMC+ HSPC/FMC.IO9_N")
			(pinfunction "IO_L9N_T1_DQS_18")
			(pintype "bidirectional")
			(die_length 18.63)
			(solder_mask_margin 0.02)
		)
		(pad "H17" smd circle
			(at 1.5 -7.5)
			(size 0.5 0.5)
			(property pad_prop_bga)
			(layers "F.Cu" "F.Mask" "F.Paste")
			(net 1014 "unconnected-(U1C-IO_L3N_T0_DQS_17-PadH17)")
			(pinfunction "IO_L3N_T0_DQS_17")
			(pintype "bidirectional+no_connect")
			(die_length 10.161)
			(solder_mask_margin 0.02)
		)
		(pad "H18" smd circle
			(at 2.5 -7.5)
			(size 0.5 0.5)
			(property pad_prop_bga)
			(layers "F.Cu" "F.Mask" "F.Paste")
			(net 24 "+3V3")
			(pinfunction "VCCO_17")
			(pintype "passive")
			(solder_mask_margin 0.02)
		)
		(pad "H19" smd circle
			(at 3.5 -7.5)
			(size 0.5 0.5)
			(property pad_prop_bga)
			(layers "F.Cu" "F.Mask" "F.Paste")
			(net 696 "/FMC+ HSPC/FMC.PRSNT_M2C")
			(pinfunction "IO_L4N_T0_17")
			(pintype "bidirectional")
			(die_length 11.623)
			(solder_mask_margin 0.02)
		)
		(pad "H20" smd circle
			(at 4.5 -7.5)
			(size 0.5 0.5)
			(property pad_prop_bga)
			(layers "F.Cu" "F.Mask" "F.Paste")
			(net 1019 "/FPGA Bank 16 & 17/GBE_RGMII.GTX_CLK")
			(pinfunction "IO_L2P_T0_17")
			(pintype "bidirectional")
			(die_length 9.042)
			(solder_mask_margin 0.02)
		)
		(pad "H21" smd circle
			(at 5.5 -7.5)
			(size 0.5 0.5)
			(property pad_prop_bga)
			(layers "F.Cu" "F.Mask" "F.Paste")
			(net 1021 "/FPGA Bank 16 & 17/GBE_RGMII.TXD1")
			(pinfunction "IO_L7P_T1_17")
			(pintype "bidirectional")
			(die_length 11.269)
			(solder_mask_margin 0.02)
		)
		(pad "H22" smd circle
			(at 6.5 -7.5)
			(size 0.5 0.5)
			(property pad_prop_bga)
			(layers "F.Cu" "F.Mask" "F.Paste")
			(net 1022 "unconnected-(U1C-IO_L7N_T1_17-PadH22)")
			(pinfunction "IO_L7N_T1_17")
			(pintype "bidirectional+no_connect")
			(die_length 11.039)
			(solder_mask_margin 0.02)
		)
		(pad "H23" smd circle
			(at 7.5 -7.5)
			(size 0.5 0.5)
			(property pad_prop_bga)
			(layers "F.Cu" "F.Mask" "F.Paste")
			(net 1 "GND")
			(pinfunction "GND")
			(pintype "passive")
			(solder_mask_margin 0.02)
		)
		(pad "H24" smd circle
			(at 8.5 -7.5)
			(size 0.5 0.5)
			(property pad_prop_bga)
			(layers "F.Cu" "F.Mask" "F.Paste")
			(net 1289 "/USER_IO.B29")
			(pinfunction "IO_L19P_T3_16")
			(pintype "bidirectional")
			(die_length 18.78)
			(solder_mask_margin 0.02)
		)
		(pad "H25" smd circle
			(at 9.5 -7.5)
			(size 0.5 0.5)
			(property pad_prop_bga)
			(layers "F.Cu" "F.Mask" "F.Paste")
			(net 1268 "/USER_IO.B5")
			(pinfunction "IO_L19N_T3_VREF_16")
			(pintype "bidirectional")
			(die_length 17.174)
			(solder_mask_margin 0.02)
		)
		(pad "H26" smd circle
			(at 10.5 -7.5)
			(size 0.5 0.5)
			(property pad_prop_bga)
			(layers "F.Cu" "F.Mask" "F.Paste")
			(net 419 "/FPGA Bank 16 & 17/USR_FLASH_1.DQ2")
			(pinfunction "IO_L23P_T3_16")
			(pintype "bidirectional")
			(die_length 18.226)
			(solder_mask_margin 0.02)
		)
		(pad "H27" smd circle
			(at 11.5 -7.5)
			(size 0.5 0.5)
			(property pad_prop_bga)
			(layers "F.Cu" "F.Mask" "F.Paste")
			(net 430 "/FPGA Bank 16 & 17/USR_FLASH_1.DQ1")
			(pinfunction "IO_L23N_T3_16")
			(pintype "bidirectional")
			(die_length 17.224)
			(solder_mask_margin 0.02)
		)
		(pad "H28" smd circle
			(at 12.5 -7.5)
			(size 0.5 0.5)
			(property pad_prop_bga)
			(layers "F.Cu" "F.Mask" "F.Paste")
			(net 3 "VCC_USR_B")
			(pinfunction "VCCO_16")
			(pintype "passive")
			(solder_mask_margin 0.02)
		)
		(pad "H29" smd circle
			(at 13.5 -7.5)
			(size 0.5 0.5)
			(property pad_prop_bga)
			(layers "F.Cu" "F.Mask" "F.Paste")
			(net 1241 "/USER_IO.A13")
			(pinfunction "IO_L7N_T1_AD10N_15")
			(pintype "bidirectional")
			(die_length 19.337)
			(solder_mask_margin 0.02)
		)
		(pad "H30" smd circle
			(at 14.5 -7.5)
			(size 0.5 0.5)
			(property pad_prop_bga)
			(layers "F.Cu" "F.Mask" "F.Paste")
			(net 1287 "/USER_IO.B27")
			(pinfunction "IO_L24P_T3_16")
			(pintype "bidirectional")
			(die_length 21.292)
			(solder_mask_margin 0.02)
		)
		(pad "J1" smd circle
			(at -14.5 -6.5)
			(size 0.5 0.5)
			(property pad_prop_bga)
			(layers "F.Cu" "F.Mask" "F.Paste")
			(net 1 "GND")
			(pinfunction "GND")
			(pintype "passive")
			(solder_mask_margin 0.02)
		)
		(pad "J2" smd circle
			(at -13.5 -6.5)
			(size 0.5 0.5)
			(property pad_prop_bga)
			(layers "F.Cu" "F.Mask" "F.Paste")
			(net 1 "GND")
			(pinfunction "GND")
			(pintype "passive")
			(solder_mask_margin 0.02)
		)
		(pad "J3" smd circle
			(at -12.5 -6.5)
			(size 0.5 0.5)
			(property pad_prop_bga)
			(layers "F.Cu" "F.Mask" "F.Paste")
			(net 1026 "unconnected-(U1G-MGTXTXN1_117-PadJ3)")
			(pinfunction "MGTXTXN1_117")
			(pintype "bidirectional+no_connect")
			(die_length 11.925)
			(solder_mask_margin 0.02)
		)
		(pad "J4" smd circle
			(at -11.5 -6.5)
			(size 0.5 0.5)
			(property pad_prop_bga)
			(layers "F.Cu" "F.Mask" "F.Paste")
			(net 1027 "unconnected-(U1G-MGTXTXP1_117-PadJ4)")
			(pinfunction "MGTXTXP1_117")
			(pintype "bidirectional+no_connect")
			(die_length 11.887)
			(solder_mask_margin 0.02)
		)
		(pad "J5" smd circle
			(at -10.5 -6.5)
			(size 0.5 0.5)
			(property pad_prop_bga)
			(layers "F.Cu" "F.Mask" "F.Paste")
			(net 8 "+1V2_MGTAVTT")
			(pinfunction "MGTAVTT")
			(pintype "passive")
			(solder_mask_margin 0.02)
		)
		(pad "J6" smd circle
			(at -9.5 -6.5)
			(size 0.5 0.5)
			(property pad_prop_bga)
			(layers "F.Cu" "F.Mask" "F.Paste")
			(net 1 "GND")
			(pinfunction "GND")
			(pintype "passive")
			(solder_mask_margin 0.02)
		)
		(pad "J7" smd circle
			(at -8.5 -6.5)
			(size 0.5 0.5)
			(property pad_prop_bga)
			(layers "F.Cu" "F.Mask" "F.Paste")
			(net 1028 "unconnected-(U1G-MGTREFCLK1N_117-PadJ7)")
			(pinfunction "MGTREFCLK1N_117")
			(pintype "bidirectional+no_connect")
			(die_length 9.91)
			(solder_mask_margin 0.02)
		)
		(pad "J8" smd circle
			(at -7.5 -6.5)
			(size 0.5 0.5)
			(property pad_prop_bga)
			(layers "F.Cu" "F.Mask" "F.Paste")
			(net 1029 "unconnected-(U1G-MGTREFCLK1P_117-PadJ8)")
			(pinfunction "MGTREFCLK1P_117")
			(pintype "bidirectional+no_connect")
			(die_length 9.161)
			(solder_mask_margin 0.02)
		)
		(pad "J9" smd circle
			(at -6.5 -6.5)
			(size 0.5 0.5)
			(property pad_prop_bga)
			(layers "F.Cu" "F.Mask" "F.Paste")
			(net 1 "GND")
			(pinfunction "GND")
			(pintype "passive")
			(solder_mask_margin 0.02)
		)
		(pad "J10" smd circle
			(at -5.5 -6.5)
			(size 0.5 0.5)
			(property pad_prop_bga)
			(layers "F.Cu" "F.Mask" "F.Paste")
			(net 1 "GND")
			(pinfunction "GND")
			(pintype "passive")
			(solder_mask_margin 0.02)
		)
		(pad "J11" smd circle
			(at -4.5 -6.5)
			(size 0.5 0.5)
			(property pad_prop_bga)
			(layers "F.Cu" "F.Mask" "F.Paste")
			(net 392 "/FMC+ HSPC/FMC.IO8_P")
			(pinfunction "IO_L8P_T1_18")
			(pintype "bidirectional")
			(die_length 21.323)
			(solder_mask_margin 0.02)
		)
		(pad "J12" smd circle
			(at -3.5 -6.5)
			(size 0.5 0.5)
			(property pad_prop_bga)
			(layers "F.Cu" "F.Mask" "F.Paste")
			(net 388 "/FMC+ HSPC/FMC.IO8_N")
			(pinfunction "IO_L8N_T1_18")
			(pintype "bidirectional")
			(die_length 20.125)
			(solder_mask_margin 0.02)
		)
		(pad "J13" smd circle
			(at -2.5 -6.5)
			(size 0.5 0.5)
			(property pad_prop_bga)
			(layers "F.Cu" "F.Mask" "F.Paste")
			(net 460 "/FMC+ HSPC/FMC.IO4_N")
			(pinfunction "IO_L4N_T0_18")
			(pintype "bidirectional")
			(die_length 18.187)
			(solder_mask_margin 0.02)
		)
		(pad "J14" smd circle
			(at -1.5 -6.5)
			(size 0.5 0.5)
			(property pad_prop_bga)
			(layers "F.Cu" "F.Mask" "F.Paste")
			(net 440 "/FMC+ HSPC/FMC.IO5_N")
			(pinfunction "IO_L5N_T0_18")
			(pintype "bidirectional")
			(die_length 17.741)
			(solder_mask_margin 0.02)
		)
		(pad "J15" smd circle
			(at -0.5 -6.5)
			(size 0.5 0.5)
			(property pad_prop_bga)
			(layers "F.Cu" "F.Mask" "F.Paste")
			(net 24 "+3V3")
			(pinfunction "VCCO_18")
			(pintype "passive")
			(solder_mask_margin 0.02)
		)
		(pad "J16" smd circle
			(at 0.5 -6.5)
			(size 0.5 0.5)
			(property pad_prop_bga)
			(layers "F.Cu" "F.Mask" "F.Paste")
			(net 381 "/FMC+ HSPC/FMC.IO9_P")
			(pinfunction "IO_L9P_T1_DQS_18")
			(pintype "bidirectional")
			(die_length 18.593)
			(solder_mask_margin 0.02)
		)
		(pad "J17" smd circle
			(at 1.5 -6.5)
			(size 0.5 0.5)
			(property pad_prop_bga)
			(layers "F.Cu" "F.Mask" "F.Paste")
			(net 1030 "unconnected-(U1C-IO_L3P_T0_DQS_17-PadJ17)")
			(pinfunction "IO_L3P_T0_DQS_17")
			(pintype "bidirectional+no_connect")
			(die_length 10.515)
			(solder_mask_margin 0.02)
		)
		(pad "J18" smd circle
			(at 2.5 -6.5)
			(size 0.5 0.5)
			(property pad_prop_bga)
			(layers "F.Cu" "F.Mask" "F.Paste")
			(net 1031 "unconnected-(U1C-IO_L1N_T0_17-PadJ18)")
			(pinfunction "IO_L1N_T0_17")
			(pintype "bidirectional+no_connect")
			(die_length 8.317)
			(solder_mask_margin 0.02)
		)
		(pad "J19" smd circle
			(at 3.5 -6.5)
			(size 0.5 0.5)
			(property pad_prop_bga)
			(layers "F.Cu" "F.Mask" "F.Paste")
			(net 514 "/FMC+ HSPC/FMC.CLK_DIR")
			(pinfunction "IO_L4P_T0_17")
			(pintype "bidirectional")
			(die_length 9.052)
			(solder_mask_margin 0.02)
		)
		(pad "J20" smd circle
			(at 4.5 -6.5)
			(size 0.5 0.5)
			(property pad_prop_bga)
			(layers "F.Cu" "F.Mask" "F.Paste")
			(net 1 "GND")
			(pinfunction "GND")
			(pintype "passive")
			(solder_mask_margin 0.02)
		)
		(pad "J21" smd circle
			(at 5.5 -6.5)
			(size 0.5 0.5)
			(property pad_prop_bga)
			(layers "F.Cu" "F.Mask" "F.Paste")
			(net 1032 "unconnected-(U1B-IO_L5P_T0_AD2P_15-PadJ21)")
			(pinfunction "IO_L5P_T0_AD2P_15")
			(pintype "bidirectional+no_connect")
			(die_length 12.084)
			(solder_mask_margin 0.02)
		)
		(pad "J22" smd circle
			(at 6.5 -6.5)
			(size 0.5 0.5)
			(property pad_prop_bga)
			(layers "F.Cu" "F.Mask" "F.Paste")
			(net 1252 "/USER_IO.A26")
			(pinfunction "IO_L5N_T0_AD2N_15")
			(pintype "bidirectional")
			(die_length 11.925)
			(solder_mask_margin 0.02)
		)
		(pad "J23" smd circle
			(at 7.5 -6.5)
			(size 0.5 0.5)
			(property pad_prop_bga)
			(layers "F.Cu" "F.Mask" "F.Paste")
			(net 1033 "unconnected-(U1B-IO_L1P_T0_AD0P_15-PadJ23)")
			(pinfunction "IO_L1P_T0_AD0P_15")
			(pintype "bidirectional+no_connect")
			(die_length 15.063)
			(solder_mask_margin 0.02)
		)
		(pad "J24" smd circle
			(at 8.5 -6.5)
			(size 0.5 0.5)
			(property pad_prop_bga)
			(layers "F.Cu" "F.Mask" "F.Paste")
			(net 1034 "unconnected-(U1B-IO_L1N_T0_AD0N_15-PadJ24)")
			(pinfunction "IO_L1N_T0_AD0N_15")
			(pintype "bidirectional+no_connect")
			(die_length 14.83)
			(solder_mask_margin 0.02)
		)
		(pad "J25" smd circle
			(at 9.5 -6.5)
			(size 0.5 0.5)
			(property pad_prop_bga)
			(layers "F.Cu" "F.Mask" "F.Paste")
			(net 2 "VCC_USR_A")
			(pinfunction "VCCO_15")
			(pintype "bidirectional")
			(solder_mask_margin 0.02)
		)
		(pad "J26" smd circle
			(at 10.5 -6.5)
			(size 0.5 0.5)
			(property pad_prop_bga)
			(layers "F.Cu" "F.Mask" "F.Paste")
			(net 1246 "/USER_IO.A17")
			(pinfunction "IO_L10N_T1_AD4N_15")
			(pintype "bidirectional")
			(die_length 18.197)
			(solder_mask_margin 0.02)
		)
		(pad "J27" smd circle
			(at 11.5 -6.5)
			(size 0.5 0.5)
			(property pad_prop_bga)
			(layers "F.Cu" "F.Mask" "F.Paste")
			(net 1240 "/USER_IO.A12")
			(pinfunction "IO_L8P_T1_AD3P_15")
			(pintype "bidirectional")
			(die_length 18.459)
			(solder_mask_margin 0.02)
		)
		(pad "J28" smd circle
			(at 12.5 -6.5)
			(size 0.5 0.5)
			(property pad_prop_bga)
			(layers "F.Cu" "F.Mask" "F.Paste")
			(net 1242 "/USER_IO.A14")
			(pinfunction "IO_L8N_T1_AD3N_15")
			(pintype "bidirectional")
			(die_length 18.849)
			(solder_mask_margin 0.02)
		)
		(pad "J29" smd circle
			(at 13.5 -6.5)
			(size 0.5 0.5)
			(property pad_prop_bga)
			(layers "F.Cu" "F.Mask" "F.Paste")
			(net 1238 "/USER_IO.A9")
			(pinfunction "IO_L7P_T1_AD10P_15")
			(pintype "bidirectional")
			(die_length 17.885)
			(solder_mask_margin 0.02)
		)
		(pad "J30" smd circle
			(at 14.5 -6.5)
			(size 0.5 0.5)
			(property pad_prop_bga)
			(layers "F.Cu" "F.Mask" "F.Paste")
			(net 1 "GND")
			(pinfunction "GND")
			(pintype "passive")
			(solder_mask_margin 0.02)
		)
		(pad "K1" smd circle
			(at -14.5 -5.5)
			(size 0.5 0.5)
			(property pad_prop_bga)
			(layers "F.Cu" "F.Mask" "F.Paste")
			(net 1035 "unconnected-(U1G-MGTXTXN0_117-PadK1)")
			(pinfunction "MGTXTXN0_117")
			(pintype "bidirectional+no_connect")
			(die_length 14.162)
			(solder_mask_margin 0.02)
		)
		(pad "K2" smd circle
			(at -13.5 -5.5)
			(size 0.5 0.5)
			(property pad_prop_bga)
			(layers "F.Cu" "F.Mask" "F.Paste")
			(net 1036 "unconnected-(U1G-MGTXTXP0_117-PadK2)")
			(pinfunction "MGTXTXP0_117")
			(pintype "bidirectional+no_connect")
			(die_length 14.111)
			(solder_mask_margin 0.02)
		)
		(pad "K3" smd circle
			(at -12.5 -5.5)
			(size 0.5 0.5)
			(property pad_prop_bga)
			(layers "F.Cu" "F.Mask" "F.Paste")
			(net 8 "+1V2_MGTAVTT")
			(pinfunction "MGTAVTT")
			(pintype "passive")
			(solder_mask_margin 0.02)
		)
		(pad "K4" smd circle
			(at -11.5 -5.5)
			(size 0.5 0.5)
			(property pad_prop_bga)
			(layers "F.Cu" "F.Mask" "F.Paste")
			(net 1 "GND")
			(pinfunction "GND")
			(pintype "passive")
			(solder_mask_margin 0.02)
		)
		(pad "K5" smd circle
			(at -10.5 -5.5)
			(size 0.5 0.5)
			(property pad_prop_bga)
			(layers "F.Cu" "F.Mask" "F.Paste")
			(net 1037 "unconnected-(U1G-MGTXRXN0_117-PadK5)")
			(pinfunction "MGTXRXN0_117")
			(pintype "bidirectional+no_connect")
			(die_length 9.726)
			(solder_mask_margin 0.02)
		)
		(pad "K6" smd circle
			(at -9.5 -5.5)
			(size 0.5 0.5)
			(property pad_prop_bga)
			(layers "F.Cu" "F.Mask" "F.Paste")
			(net 1038 "unconnected-(U1G-MGTXRXP0_117-PadK6)")
			(pinfunction "MGTXRXP0_117")
			(pintype "bidirectional+no_connect")
			(die_length 9.905)
			(solder_mask_margin 0.02)
		)
		(pad "K7" smd circle
			(at -8.5 -5.5)
			(size 0.5 0.5)
			(property pad_prop_bga)
			(layers "F.Cu" "F.Mask" "F.Paste")
			(net 6 "+1V0_MGTAVCC")
			(pinfunction "MGTAVCC")
			(pintype "passive")
			(solder_mask_margin 0.02)
		)
		(pad "K8" smd circle
			(at -7.5 -5.5)
			(size 0.5 0.5)
			(property pad_prop_bga)
			(layers "F.Cu" "F.Mask" "F.Paste")
			(net 1 "GND")
			(pinfunction "GND")
			(pintype "passive")
			(solder_mask_margin 0.02)
		)
		(pad "K9" smd circle
			(at -6.5 -5.5)
			(size 0.5 0.5)
			(property pad_prop_bga)
			(layers "F.Cu" "F.Mask" "F.Paste")
			(net 1 "GND")
			(pinfunction "GND")
			(pintype "passive")
			(solder_mask_margin 0.02)
		)
		(pad "K10" smd circle
			(at -5.5 -5.5)
			(size 0.5 0.5)
			(property pad_prop_bga)
			(layers "F.Cu" "F.Mask" "F.Paste")
			(net 301 "/FPGA Config/PROGRAM_B")
			(pinfunction "PROGRAM_B_0")
			(pintype "bidirectional")
			(die_length 20.153)
			(solder_mask_margin 0.02)
		)
		(pad "K11" smd circle
			(at -4.5 -5.5)
			(size 0.5 0.5)
			(property pad_prop_bga)
			(layers "F.Cu" "F.Mask" "F.Paste")
			(net 401 "/FMC+ HSPC/FMC.IO6_N")
			(pinfunction "IO_L6N_T0_VREF_18")
			(pintype "bidirectional")
			(die_length 21.727)
			(solder_mask_margin 0.02)
		)
		(pad "K12" smd circle
			(at -3.5 -5.5)
			(size 0.5 0.5)
			(property pad_prop_bga)
			(layers "F.Cu" "F.Mask" "F.Paste")
			(net 24 "+3V3")
			(pinfunction "VCCO_18")
			(pintype "passive")
			(solder_mask_margin 0.02)
		)
		(pad "K13" smd circle
			(at -2.5 -5.5)
			(size 0.5 0.5)
			(property pad_prop_bga)
			(layers "F.Cu" "F.Mask" "F.Paste")
			(net 464 "/FMC+ HSPC/FMC.IO4_P")
			(pinfunction "IO_L4P_T0_18")
			(pintype "bidirectional")
			(die_length 17.821)
			(solder_mask_margin 0.02)
		)
		(pad "K14" smd circle
			(at -1.5 -5.5)
			(size 0.5 0.5)
			(property pad_prop_bga)
			(layers "F.Cu" "F.Mask" "F.Paste")
			(net 441 "/FMC+ HSPC/FMC.IO5_P")
			(pinfunction "IO_L5P_T0_18")
			(pintype "bidirectional")
			(die_length 17.482)
			(solder_mask_margin 0.02)
		)
		(pad "K15" smd circle
			(at -0.5 -5.5)
			(size 0.5 0.5)
			(property pad_prop_bga)
			(layers "F.Cu" "F.Mask" "F.Paste")
			(net 450 "/FMC+ HSPC/FMC.IO2_N")
			(pinfunction "IO_L2N_T0_18")
			(pintype "bidirectional")
			(die_length 17.67)
			(solder_mask_margin 0.02)
		)
		(pad "K16" smd circle
			(at 0.5 -5.5)
			(size 0.5 0.5)
			(property pad_prop_bga)
			(layers "F.Cu" "F.Mask" "F.Paste")
			(net 414 "/FMC+ HSPC/FMC.IO1_N")
			(pinfunction "IO_L1N_T0_18")
			(pintype "bidirectional")
			(die_length 17.367)
			(solder_mask_margin 0.02)
		)
		(pad "K17" smd circle
			(at 1.5 -5.5)
			(size 0.5 0.5)
			(property pad_prop_bga)
			(layers "F.Cu" "F.Mask" "F.Paste")
			(net 1 "GND")
			(pinfunction "GND")
			(pintype "passive")
			(solder_mask_margin 0.02)
		)
		(pad "K18" smd circle
			(at 2.5 -5.5)
			(size 0.5 0.5)
			(property pad_prop_bga)
			(layers "F.Cu" "F.Mask" "F.Paste")
			(net 1039 "unconnected-(U1C-IO_L1P_T0_17-PadK18)")
			(pinfunction "IO_L1P_T0_17")
			(pintype "bidirectional+no_connect")
			(die_length 8.927)
			(solder_mask_margin 0.02)
		)
		(pad "K19" smd circle
			(at 3.5 -5.5)
			(size 0.5 0.5)
			(property pad_prop_bga)
			(layers "F.Cu" "F.Mask" "F.Paste")
			(net 1040 "unconnected-(U1C-IO_L6P_T0_17-PadK19)")
			(pinfunction "IO_L6P_T0_17")
			(pintype "bidirectional+no_connect")
			(die_length 7.177)
			(solder_mask_margin 0.02)
		)
		(pad "K20" smd circle
			(at 4.5 -5.5)
			(size 0.5 0.5)
			(property pad_prop_bga)
			(layers "F.Cu" "F.Mask" "F.Paste")
			(net 1041 "unconnected-(U1C-IO_L6N_T0_VREF_17-PadK20)")
			(pinfunction "IO_L6N_T0_VREF_17")
			(pintype "bidirectional+no_connect")
			(die_length 8.379)
			(solder_mask_margin 0.02)
		)
		(pad "K21" smd circle
			(at 5.5 -5.5)
			(size 0.5 0.5)
			(property pad_prop_bga)
			(layers "F.Cu" "F.Mask" "F.Paste")
			(net 1265 "/USER_IO.A40")
			(pinfunction "IO_L4N_T0_AD9N_15")
			(pintype "bidirectional")
			(die_length 13.872)
			(solder_mask_margin 0.02)
		)
		(pad "K22" smd circle
			(at 6.5 -5.5)
			(size 0.5 0.5)
			(property pad_prop_bga)
			(layers "F.Cu" "F.Mask" "F.Paste")
			(net 2 "VCC_USR_A")
			(pinfunction "VCCO_15")
			(pintype "passive")
			(solder_mask_margin 0.02)
		)
		(pad "K23" smd circle
			(at 7.5 -5.5)
			(size 0.5 0.5)
			(property pad_prop_bga)
			(layers "F.Cu" "F.Mask" "F.Paste")
			(net 1042 "unconnected-(U1B-IO_L3P_T0_DQS_AD1P_15-PadK23)")
			(pinfunction "IO_L3P_T0_DQS_AD1P_15")
			(pintype "bidirectional+no_connect")
			(die_length 12.884)
			(solder_mask_margin 0.02)
		)
		(pad "K24" smd circle
			(at 8.5 -5.5)
			(size 0.5 0.5)
			(property pad_prop_bga)
			(layers "F.Cu" "F.Mask" "F.Paste")
			(net 1043 "unconnected-(U1B-IO_L3N_T0_DQS_AD1N_15-PadK24)")
			(pinfunction "IO_L3N_T0_DQS_AD1N_15")
			(pintype "bidirectional+no_connect")
			(die_length 13.276)
			(solder_mask_margin 0.02)
		)
		(pad "K25" smd circle
			(at 9.5 -5.5)
			(size 0.5 0.5)
			(property pad_prop_bga)
			(layers "F.Cu" "F.Mask" "F.Paste")
			(net 1044 "unconnected-(U1B-IO_L12N_T1_MRCC_AD5N_15-PadK25)")
			(pinfunction "IO_L12N_T1_MRCC_AD5N_15")
			(pintype "bidirectional+no_connect")
			(die_length 15.47)
			(solder_mask_margin 0.02)
		)
		(pad "K26" smd circle
			(at 10.5 -5.5)
			(size 0.5 0.5)
			(property pad_prop_bga)
			(layers "F.Cu" "F.Mask" "F.Paste")
			(net 1264 "/USER_IO.A39")
			(pinfunction "IO_L10P_T1_AD4P_15")
			(pintype "bidirectional")
			(die_length 16.347)
			(solder_mask_margin 0.02)
		)
		(pad "K27" smd circle
			(at 11.5 -5.5)
			(size 0.5 0.5)
			(property pad_prop_bga)
			(layers "F.Cu" "F.Mask" "F.Paste")
			(net 1 "GND")
			(pinfunction "GND")
			(pintype "passive")
			(solder_mask_margin 0.02)
		)
		(pad "K28" smd circle
			(at 12.5 -5.5)
			(size 0.5 0.5)
			(property pad_prop_bga)
			(layers "F.Cu" "F.Mask" "F.Paste")
			(net 1258 "/USER_IO.A32")
			(pinfunction "IO_L13P_T2_MRCC_15")
			(pintype "bidirectional")
			(die_length 18.837)
			(solder_mask_margin 0.02)
		)
		(pad "K29" smd circle
			(at 13.5 -5.5)
			(size 0.5 0.5)
			(property pad_prop_bga)
			(layers "F.Cu" "F.Mask" "F.Paste")
			(net 1050 "unconnected-(U1B-IO_L13N_T2_MRCC_15-PadK29)")
			(pinfunction "IO_L13N_T2_MRCC_15")
			(pintype "bidirectional+no_connect")
			(die_length 18.782)
			(solder_mask_margin 0.02)
		)
		(pad "K30" smd circle
			(at 14.5 -5.5)
			(size 0.5 0.5)
			(property pad_prop_bga)
			(layers "F.Cu" "F.Mask" "F.Paste")
			(net 1237 "/USER_IO.A7")
			(pinfunction "IO_L9N_T1_DQS_AD11N_15")
			(pintype "bidirectional")
			(die_length 18.721)
			(solder_mask_margin 0.02)
		)
		(pad "L1" smd circle
			(at -14.5 -4.5)
			(size 0.5 0.5)
			(property pad_prop_bga)
			(layers "F.Cu" "F.Mask" "F.Paste")
			(net 1 "GND")
			(pinfunction "GND")
			(pintype "passive")
			(solder_mask_margin 0.02)
		)
		(pad "L2" smd circle
			(at -13.5 -4.5)
			(size 0.5 0.5)
			(property pad_prop_bga)
			(layers "F.Cu" "F.Mask" "F.Paste")
			(net 1 "GND")
			(pinfunction "GND")
			(pintype "passive")
			(solder_mask_margin 0.02)
		)
		(pad "L3" smd circle
			(at -12.5 -4.5)
			(size 0.5 0.5)
			(property pad_prop_bga)
			(layers "F.Cu" "F.Mask" "F.Paste")
			(net 63 "/FMC+ HSPC/GTX116.TX3_N")
			(pinfunction "MGTXTXN3_116")
			(pintype "bidirectional")
			(die_length 11.585)
			(solder_mask_margin 0.02)
		)
		(pad "L4" smd circle
			(at -11.5 -4.5)
			(size 0.5 0.5)
			(property pad_prop_bga)
			(layers "F.Cu" "F.Mask" "F.Paste")
			(net 61 "/FMC+ HSPC/GTX116.TX3_P")
			(pinfunction "MGTXTXP3_116")
			(pintype "bidirectional")
			(die_length 11.561)
			(solder_mask_margin 0.02)
		)
		(pad "L5" smd circle
			(at -10.5 -4.5)
			(size 0.5 0.5)
			(property pad_prop_bga)
			(layers "F.Cu" "F.Mask" "F.Paste")
			(net 8 "+1V2_MGTAVTT")
			(pinfunction "MGTAVTT")
			(pintype "passive")
			(solder_mask_margin 0.02)
		)
		(pad "L6" smd circle
			(at -9.5 -4.5)
			(size 0.5 0.5)
			(property pad_prop_bga)
			(layers "F.Cu" "F.Mask" "F.Paste")
			(net 1 "GND")
			(pinfunction "GND")
			(pintype "passive")
			(solder_mask_margin 0.02)
		)
		(pad "L7" smd circle
			(at -8.5 -4.5)
			(size 0.5 0.5)
			(property pad_prop_bga)
			(layers "F.Cu" "F.Mask" "F.Paste")
			(net 596 "/FMC+ HSPC/GTX116.REFCLK0_N")
			(pinfunction "MGTREFCLK0N_116")
			(pintype "bidirectional")
			(die_length 8.449)
			(solder_mask_margin 0.02)
		)
		(pad "L8" smd circle
			(at -7.5 -4.5)
			(size 0.5 0.5)
			(property pad_prop_bga)
			(layers "F.Cu" "F.Mask" "F.Paste")
			(net 594 "/FMC+ HSPC/GTX116.REFCLK0_P")
			(pinfunction "MGTREFCLK0P_116")
			(pintype "bidirectional")
			(die_length 8.298)
			(solder_mask_margin 0.02)
		)
		(pad "L9" smd circle
			(at -6.5 -4.5)
			(size 0.5 0.5)
			(property pad_prop_bga)
			(layers "F.Cu" "F.Mask" "F.Paste")
			(net 1 "GND")
			(pinfunction "GND")
			(pintype "passive")
			(solder_mask_margin 0.02)
		)
		(pad "L10" smd circle
			(at -5.5 -4.5)
			(size 0.5 0.5)
			(property pad_prop_bga)
			(layers "F.Cu" "F.Mask" "F.Paste")
			(net 1051 "unconnected-(U1I-CFGBVS_0-PadL10)")
			(pinfunction "CFGBVS_0")
			(pintype "bidirectional+no_connect")
			(die_length 19.652)
			(solder_mask_margin 0.02)
		)
		(pad "L11" smd circle
			(at -4.5 -4.5)
			(size 0.5 0.5)
			(property pad_prop_bga)
			(layers "F.Cu" "F.Mask" "F.Paste")
			(net 405 "/FMC+ HSPC/FMC.IO6_P")
			(pinfunction "IO_L6P_T0_18")
			(pintype "bidirectional")
			(die_length 20.929)
			(solder_mask_margin 0.02)
		)
		(pad "L12" smd circle
			(at -3.5 -4.5)
			(size 0.5 0.5)
			(property pad_prop_bga)
			(layers "F.Cu" "F.Mask" "F.Paste")
			(net 449 "/FMC+ HSPC/FMC.IO3_P")
			(pinfunction "IO_L3P_T0_DQS_18")
			(pintype "bidirectional")
			(die_length 19.179)
			(solder_mask_margin 0.02)
		)
		(pad "L13" smd circle
			(at -2.5 -4.5)
			(size 0.5 0.5)
			(property pad_prop_bga)
			(layers "F.Cu" "F.Mask" "F.Paste")
			(net 446 "/FMC+ HSPC/FMC.IO3_N")
			(pinfunction "IO_L3N_T0_DQS_18")
			(pintype "bidirectional")
			(die_length 19.134)
			(solder_mask_margin 0.02)
		)
		(pad "L14" smd circle
			(at -1.5 -4.5)
			(size 0.5 0.5)
			(property pad_prop_bga)
			(layers "F.Cu" "F.Mask" "F.Paste")
			(net 1 "GND")
			(pinfunction "GND")
			(pintype "passive")
			(solder_mask_margin 0.02)
		)
		(pad "L15" smd circle
			(at -0.5 -4.5)
			(size 0.5 0.5)
			(property pad_prop_bga)
			(layers "F.Cu" "F.Mask" "F.Paste")
			(net 455 "/FMC+ HSPC/FMC.IO2_P")
			(pinfunction "IO_L2P_T0_18")
			(pintype "bidirectional")
			(die_length 17.689)
			(solder_mask_margin 0.02)
		)
		(pad "L16" smd circle
			(at 0.5 -4.5)
			(size 0.5 0.5)
			(property pad_prop_bga)
			(layers "F.Cu" "F.Mask" "F.Paste")
			(net 418 "/FMC+ HSPC/FMC.IO1_P")
			(pinfunction "IO_L1P_T0_18")
			(pintype "bidirectional")
			(die_length 18.303)
			(solder_mask_margin 0.02)
		)
		(pad "L17" smd circle
			(at 1.5 -4.5)
			(size 0.5 0.5)
			(property pad_prop_bga)
			(layers "F.Cu" "F.Mask" "F.Paste")
			(net 1056 "unconnected-(U1C-IO_L5P_T0_17-PadL17)")
			(pinfunction "IO_L5P_T0_17")
			(pintype "bidirectional+no_connect")
			(die_length 9.576)
			(solder_mask_margin 0.02)
		)
		(pad "L18" smd circle
			(at 2.5 -4.5)
			(size 0.5 0.5)
			(property pad_prop_bga)
			(layers "F.Cu" "F.Mask" "F.Paste")
			(net 1057 "unconnected-(U1C-IO_L5N_T0_17-PadL18)")
			(pinfunction "IO_L5N_T0_17")
			(pintype "bidirectional+no_connect")
			(die_length 8.081)
			(solder_mask_margin 0.02)
		)
		(pad "L19" smd circle
			(at 3.5 -4.5)
			(size 0.5 0.5)
			(property pad_prop_bga)
			(layers "F.Cu" "F.Mask" "F.Paste")
			(net 24 "+3V3")
			(pinfunction "VCCO_17")
			(pintype "passive")
			(solder_mask_margin 0.02)
		)
		(pad "L20" smd circle
			(at 4.5 -4.5)
			(size 0.5 0.5)
			(property pad_prop_bga)
			(layers "F.Cu" "F.Mask" "F.Paste")
			(net 1247 "/USER_IO.A18")
			(pinfunction "IO_L6N_T0_VREF_15")
			(pintype "bidirectional")
			(die_length 13.878)
			(solder_mask_margin 0.02)
		)
		(pad "L21" smd circle
			(at 5.5 -4.5)
			(size 0.5 0.5)
			(property pad_prop_bga)
			(layers "F.Cu" "F.Mask" "F.Paste")
			(net 1251 "/USER_IO.A25")
			(pinfunction "IO_L4P_T0_AD9P_15")
			(pintype "bidirectional")
			(die_length 11.376)
			(solder_mask_margin 0.02)
		)
		(pad "L22" smd circle
			(at 6.5 -4.5)
			(size 0.5 0.5)
			(property pad_prop_bga)
			(layers "F.Cu" "F.Mask" "F.Paste")
			(net 1193 "unconnected-(U1B-IO_L2P_T0_AD8P_15-PadL22)")
			(pinfunction "IO_L2P_T0_AD8P_15")
			(pintype "bidirectional+no_connect")
			(die_length 12.134)
			(solder_mask_margin 0.02)
		)
		(pad "L23" smd circle
			(at 7.5 -4.5)
			(size 0.5 0.5)
			(property pad_prop_bga)
			(layers "F.Cu" "F.Mask" "F.Paste")
			(net 1194 "unconnected-(U1B-IO_L2N_T0_AD8N_15-PadL23)")
			(pinfunction "IO_L2N_T0_AD8N_15")
			(pintype "bidirectional+no_connect")
			(die_length 12.328)
			(solder_mask_margin 0.02)
		)
		(pad "L24" smd circle
			(at 8.5 -4.5)
			(size 0.5 0.5)
			(property pad_prop_bga)
			(layers "F.Cu" "F.Mask" "F.Paste")
			(net 1 "GND")
			(pinfunction "GND")
			(pintype "passive")
			(solder_mask_margin 0.02)
		)
		(pad "L25" smd circle
			(at 9.5 -4.5)
			(size 0.5 0.5)
			(property pad_prop_bga)
			(layers "F.Cu" "F.Mask" "F.Paste")
			(net 1260 "/USER_IO.A35")
			(pinfunction "IO_L12P_T1_MRCC_AD5P_15")
			(pintype "bidirectional")
			(die_length 15.993)
			(solder_mask_margin 0.02)
		)
		(pad "L26" smd circle
			(at 10.5 -4.5)
			(size 0.5 0.5)
			(property pad_prop_bga)
			(layers "F.Cu" "F.Mask" "F.Paste")
			(net 1257 "/USER_IO.A31")
			(pinfunction "IO_L11P_T1_SRCC_AD12P_15")
			(pintype "bidirectional")
			(die_length 15.575)
			(solder_mask_margin 0.02)
		)
		(pad "L27" smd circle
			(at 11.5 -4.5)
			(size 0.5 0.5)
			(property pad_prop_bga)
			(layers "F.Cu" "F.Mask" "F.Paste")
			(net 1262 "/USER_IO.A37")
			(pinfunction "IO_L11N_T1_SRCC_AD12N_15")
			(pintype "bidirectional")
			(die_length 15.25)
			(solder_mask_margin 0.02)
		)
		(pad "L28" smd circle
			(at 12.5 -4.5)
			(size 0.5 0.5)
			(property pad_prop_bga)
			(layers "F.Cu" "F.Mask" "F.Paste")
			(net 1259 "/USER_IO.A33")
			(pinfunction "IO_L14N_T2_SRCC_15")
			(pintype "bidirectional")
			(die_length 15.833)
			(solder_mask_margin 0.02)
		)
		(pad "L29" smd circle
			(at 13.5 -4.5)
			(size 0.5 0.5)
			(property pad_prop_bga)
			(layers "F.Cu" "F.Mask" "F.Paste")
			(net 2 "VCC_USR_A")
			(pinfunction "VCCO_15")
			(pintype "passive")
			(solder_mask_margin 0.02)
		)
		(pad "L30" smd circle
			(at 14.5 -4.5)
			(size 0.5 0.5)
			(property pad_prop_bga)
			(layers "F.Cu" "F.Mask" "F.Paste")
			(net 1235 "/USER_IO.A3")
			(pinfunction "IO_L9P_T1_DQS_AD11P_15")
			(pintype "bidirectional")
			(die_length 18.142)
			(solder_mask_margin 0.02)
		)
		(pad "M1" smd circle
			(at -14.5 -3.5)
			(size 0.5 0.5)
			(property pad_prop_bga)
			(layers "F.Cu" "F.Mask" "F.Paste")
			(net 69 "/FMC+ HSPC/GTX116.TX2_N")
			(pinfunction "MGTXTXN2_116")
			(pintype "bidirectional")
			(die_length 13.468)
			(solder_mask_margin 0.02)
		)
		(pad "M2" smd circle
			(at -13.5 -3.5)
			(size 0.5 0.5)
			(property pad_prop_bga)
			(layers "F.Cu" "F.Mask" "F.Paste")
			(net 65 "/FMC+ HSPC/GTX116.TX2_P")
			(pinfunction "MGTXTXP2_116")
			(pintype "bidirectional")
			(die_length 13.415)
			(solder_mask_margin 0.02)
		)
		(pad "M3" smd circle
			(at -12.5 -3.5)
			(size 0.5 0.5)
			(property pad_prop_bga)
			(layers "F.Cu" "F.Mask" "F.Paste")
			(net 8 "+1V2_MGTAVTT")
			(pinfunction "MGTAVTT")
			(pintype "passive")
			(solder_mask_margin 0.02)
		)
		(pad "M4" smd circle
			(at -11.5 -3.5)
			(size 0.5 0.5)
			(property pad_prop_bga)
			(layers "F.Cu" "F.Mask" "F.Paste")
			(net 1 "GND")
			(pinfunction "GND")
			(pintype "passive")
			(solder_mask_margin 0.02)
		)
		(pad "M5" smd circle
			(at -10.5 -3.5)
			(size 0.5 0.5)
			(property pad_prop_bga)
			(layers "F.Cu" "F.Mask" "F.Paste")
			(net 283 "/FMC+ HSPC/GTX116.RX1_N")
			(pinfunction "MGTXRXN3_116")
			(pintype "bidirectional")
			(die_length 9.574)
			(solder_mask_margin 0.02)
		)
		(pad "M6" smd circle
			(at -9.5 -3.5)
			(size 0.5 0.5)
			(property pad_prop_bga)
			(layers "F.Cu" "F.Mask" "F.Paste")
			(net 288 "/FMC+ HSPC/GTX116.RX1_P")
			(pinfunction "MGTXRXP3_116")
			(pintype "bidirectional")
			(die_length 9.789)
			(solder_mask_margin 0.02)
		)
		(pad "M7" smd circle
			(at -8.5 -3.5)
			(size 0.5 0.5)
			(property pad_prop_bga)
			(layers "F.Cu" "F.Mask" "F.Paste")
			(net 6 "+1V0_MGTAVCC")
			(pinfunction "MGTAVCC")
			(pintype "passive")
			(solder_mask_margin 0.02)
		)
		(pad "M8" smd circle
			(at -7.5 -3.5)
			(size 0.5 0.5)
			(property pad_prop_bga)
			(layers "F.Cu" "F.Mask" "F.Paste")
			(net 1 "GND")
			(pinfunction "GND")
			(pintype "passive")
			(solder_mask_margin 0.02)
		)
		(pad "M9" smd circle
			(at -6.5 -3.5)
			(size 0.5 0.5)
			(property pad_prop_bga)
			(layers "F.Cu" "F.Mask" "F.Paste")
			(net 1 "GND")
			(pinfunction "GND")
			(pintype "passive")
			(solder_mask_margin 0.02)
		)
		(pad "M10" smd circle
			(at -5.5 -3.5)
			(size 0.5 0.5)
			(property pad_prop_bga)
			(layers "F.Cu" "F.Mask" "F.Paste")
			(net 246 "/FPGA Config/DONE")
			(pinfunction "DONE_0")
			(pintype "bidirectional")
			(die_length 19.51)
			(solder_mask_margin 0.02)
		)
		(pad "M11" smd circle
			(at -4.5 -3.5)
			(size 0.5 0.5)
			(property pad_prop_bga)
			(layers "F.Cu" "F.Mask" "F.Paste")
			(net 650 "+1V0")
			(pinfunction "VCCINT")
			(pintype "bidirectional")
			(solder_mask_margin 0.02)
		)
		(pad "M12" smd circle
			(at -3.5 -3.5)
			(size 0.5 0.5)
			(property pad_prop_bga)
			(layers "F.Cu" "F.Mask" "F.Paste")
			(net 1 "GND")
			(pinfunction "GND")
			(pintype "passive")
			(solder_mask_margin 0.02)
		)
		(pad "M13" smd circle
			(at -2.5 -3.5)
			(size 0.5 0.5)
			(property pad_prop_bga)
			(layers "F.Cu" "F.Mask" "F.Paste")
			(net 650 "+1V0")
			(pinfunction "VCCINT")
			(pintype "passive")
			(solder_mask_margin 0.02)
		)
		(pad "M14" smd circle
			(at -1.5 -3.5)
			(size 0.5 0.5)
			(property pad_prop_bga)
			(layers "F.Cu" "F.Mask" "F.Paste")
			(net 1 "GND")
			(pinfunction "GND")
			(pintype "passive")
			(solder_mask_margin 0.02)
		)
		(pad "M15" smd circle
			(at -0.5 -3.5)
			(size 0.5 0.5)
			(property pad_prop_bga)
			(layers "F.Cu" "F.Mask" "F.Paste")
			(net 650 "+1V0")
			(pinfunction "VCCINT")
			(pintype "passive")
			(solder_mask_margin 0.02)
		)
		(pad "M16" smd circle
			(at 0.5 -3.5)
			(size 0.5 0.5)
			(property pad_prop_bga)
			(layers "F.Cu" "F.Mask" "F.Paste")
			(net 1 "GND")
			(pinfunction "GND")
			(pintype "passive")
			(solder_mask_margin 0.02)
		)
		(pad "M17" smd circle
			(at 1.5 -3.5)
			(size 0.5 0.5)
			(property pad_prop_bga)
			(layers "F.Cu" "F.Mask" "F.Paste")
			(net 650 "+1V0")
			(pinfunction "VCCINT")
			(pintype "passive")
			(solder_mask_margin 0.02)
		)
		(pad "M18" smd circle
			(at 2.5 -3.5)
			(size 0.5 0.5)
			(property pad_prop_bga)
			(layers "F.Cu" "F.Mask" "F.Paste")
			(net 1 "GND")
			(pinfunction "GND")
			(pintype "passive")
			(solder_mask_margin 0.02)
		)
		(pad "M19" smd circle
			(at 3.5 -3.5)
			(size 0.5 0.5)
			(property pad_prop_bga)
			(layers "F.Cu" "F.Mask" "F.Paste")
			(net 1234 "/USER_IO.A1")
			(pinfunction "IO_0_15")
			(pintype "bidirectional")
			(die_length 10.051)
			(solder_mask_margin 0.02)
		)
		(pad "M20" smd circle
			(at 4.5 -3.5)
			(size 0.5 0.5)
			(property pad_prop_bga)
			(layers "F.Cu" "F.Mask" "F.Paste")
			(net 1245 "/USER_IO.A16")
			(pinfunction "IO_L6P_T0_15")
			(pintype "bidirectional")
			(die_length 12.146)
			(solder_mask_margin 0.02)
		)
		(pad "M21" smd circle
			(at 5.5 -3.5)
			(size 0.5 0.5)
			(property pad_prop_bga)
			(layers "F.Cu" "F.Mask" "F.Paste")
			(net 1 "GND")
			(pinfunction "GND")
			(pintype "passive")
			(solder_mask_margin 0.02)
		)
		(pad "M22" smd circle
			(at 6.5 -3.5)
			(size 0.5 0.5)
			(property pad_prop_bga)
			(layers "F.Cu" "F.Mask" "F.Paste")
			(net 1298 "unconnected-(U1B-IO_L24P_T3_RS1_15-PadM22)")
			(pinfunction "IO_L24P_T3_RS1_15")
			(pintype "bidirectional+no_connect")
			(die_length 14.019)
			(solder_mask_margin 0.02)
		)
		(pad "M23" smd circle
			(at 7.5 -3.5)
			(size 0.5 0.5)
			(property pad_prop_bga)
			(layers "F.Cu" "F.Mask" "F.Paste")
			(net 1255 "/USER_IO.A29")
			(pinfunction "IO_L24N_T3_RS0_15")
			(pintype "bidirectional")
			(die_length 12.184)
			(solder_mask_margin 0.02)
		)
		(pad "M24" smd circle
			(at 8.5 -3.5)
			(size 0.5 0.5)
			(property pad_prop_bga)
			(layers "F.Cu" "F.Mask" "F.Paste")
			(net 1333 "unconnected-(U1B-IO_L23P_T3_FOE_B_15-PadM24)")
			(pinfunction "IO_L23P_T3_FOE_B_15")
			(pintype "bidirectional+no_connect")
			(die_length 14.067)
			(solder_mask_margin 0.02)
		)
		(pad "M25" smd circle
			(at 9.5 -3.5)
			(size 0.5 0.5)
			(property pad_prop_bga)
			(layers "F.Cu" "F.Mask" "F.Paste")
			(net 1341 "unconnected-(U1B-IO_L23N_T3_FWE_B_15-PadM25)")
			(pinfunction "IO_L23N_T3_FWE_B_15")
			(pintype "bidirectional+no_connect")
			(die_length 13.167)
			(solder_mask_margin 0.02)
		)
		(pad "M26" smd circle
			(at 10.5 -3.5)
			(size 0.5 0.5)
			(property pad_prop_bga)
			(layers "F.Cu" "F.Mask" "F.Paste")
			(net 2 "VCC_USR_A")
			(pinfunction "VCCO_15")
			(pintype "passive")
			(solder_mask_margin 0.02)
		)
		(pad "M27" smd circle
			(at 11.5 -3.5)
			(size 0.5 0.5)
			(property pad_prop_bga)
			(layers "F.Cu" "F.Mask" "F.Paste")
			(net 1248 "/USER_IO.A21")
			(pinfunction "IO_L16N_T2_A27_15")
			(pintype "bidirectional")
			(die_length 14.949)
			(solder_mask_margin 0.02)
		)
		(pad "M28" smd circle
			(at 12.5 -3.5)
			(size 0.5 0.5)
			(property pad_prop_bga)
			(layers "F.Cu" "F.Mask" "F.Paste")
			(net 1239 "/USER_IO.A11")
			(pinfunction "IO_L14P_T2_SRCC_15")
			(pintype "bidirectional")
			(die_length 15.521)
			(solder_mask_margin 0.02)
		)
		(pad "M29" smd circle
			(at 13.5 -3.5)
			(size 0.5 0.5)
			(property pad_prop_bga)
			(layers "F.Cu" "F.Mask" "F.Paste")
			(net 1249 "/USER_IO.A23")
			(pinfunction "IO_L15P_T2_DQS_15")
			(pintype "bidirectional")
			(die_length 16.261)
			(solder_mask_margin 0.02)
		)
		(pad "M30" smd circle
			(at 14.5 -3.5)
			(size 0.5 0.5)
			(property pad_prop_bga)
			(layers "F.Cu" "F.Mask" "F.Paste")
			(net 1254 "/USER_IO.A28")
			(pinfunction "IO_L15N_T2_DQS_ADV_B_15")
			(pintype "bidirectional")
			(die_length 16.654)
			(solder_mask_margin 0.02)
		)
		(pad "N1" smd circle
			(at -14.5 -2.5)
			(size 0.5 0.5)
			(property pad_prop_bga)
			(layers "F.Cu" "F.Mask" "F.Paste")
			(net 1 "GND")
			(pinfunction "GND")
			(pintype "passive")
			(solder_mask_margin 0.02)
		)
		(pad "N2" smd circle
			(at -13.5 -2.5)
			(size 0.5 0.5)
			(property pad_prop_bga)
			(layers "F.Cu" "F.Mask" "F.Paste")
			(net 1 "GND")
			(pinfunction "GND")
			(pintype "passive")
			(solder_mask_margin 0.02)
		)
		(pad "N3" smd circle
			(at -12.5 -2.5)
			(size 0.5 0.5)
			(property pad_prop_bga)
			(layers "F.Cu" "F.Mask" "F.Paste")
			(net 78 "/FMC+ HSPC/GTX116.TX1_N")
			(pinfunction "MGTXTXN1_116")
			(pintype "bidirectional")
			(die_length 11.433)
			(solder_mask_margin 0.02)
		)
		(pad "N4" smd circle
			(at -11.5 -2.5)
			(size 0.5 0.5)
			(property pad_prop_bga)
			(layers "F.Cu" "F.Mask" "F.Paste")
			(net 73 "/FMC+ HSPC/GTX116.TX1_P")
			(pinfunction "MGTXTXP1_116")
			(pintype "bidirectional")
			(die_length 11.366)
			(solder_mask_margin 0.02)
		)
		(pad "N5" smd circle
			(at -10.5 -2.5)
			(size 0.5 0.5)
			(property pad_prop_bga)
			(layers "F.Cu" "F.Mask" "F.Paste")
			(net 8 "+1V2_MGTAVTT")
			(pinfunction "MGTAVTT")
			(pintype "passive")
			(solder_mask_margin 0.02)
		)
		(pad "N6" smd circle
			(at -9.5 -2.5)
			(size 0.5 0.5)
			(property pad_prop_bga)
			(layers "F.Cu" "F.Mask" "F.Paste")
			(net 1 "GND")
			(pinfunction "GND")
			(pintype "passive")
			(solder_mask_margin 0.02)
		)
		(pad "N7" smd circle
			(at -8.5 -2.5)
			(size 0.5 0.5)
			(property pad_prop_bga)
			(layers "F.Cu" "F.Mask" "F.Paste")
			(net 600 "/FMC+ HSPC/GTX116.REFCLK1_N")
			(pinfunction "MGTREFCLK1N_116")
			(pintype "bidirectional")
			(die_length 8.657)
			(solder_mask_margin 0.02)
		)
		(pad "N8" smd circle
			(at -7.5 -2.5)
			(size 0.5 0.5)
			(property pad_prop_bga)
			(layers "F.Cu" "F.Mask" "F.Paste")
			(net 598 "/FMC+ HSPC/GTX116.REFCLK1_P")
			(pinfunction "MGTREFCLK1P_116")
			(pintype "bidirectional")
			(die_length 8.202)
			(solder_mask_margin 0.02)
		)
		(pad "N9" smd circle
			(at -6.5 -2.5)
			(size 0.5 0.5)
			(property pad_prop_bga)
			(layers "F.Cu" "F.Mask" "F.Paste")
			(net 1 "GND")
			(pinfunction "GND")
			(pintype "passive")
			(solder_mask_margin 0.02)
		)
		(pad "N10" smd circle
			(at -5.5 -2.5)
			(size 0.5 0.5)
			(property pad_prop_bga)
			(layers "F.Cu" "F.Mask" "F.Paste")
			(net 650 "+1V0")
			(pinfunction "VCCINT")
			(pintype "passive")
			(solder_mask_margin 0.02)
		)
		(pad "N11" smd circle
			(at -4.5 -2.5)
			(size 0.5 0.5)
			(property pad_prop_bga)
			(layers "F.Cu" "F.Mask" "F.Paste")
			(net 1 "GND")
			(pinfunction "GND")
			(pintype "passive")
			(solder_mask_margin 0.02)
		)
		(pad "N12" smd circle
			(at -3.5 -2.5)
			(size 0.5 0.5)
			(property pad_prop_bga)
			(layers "F.Cu" "F.Mask" "F.Paste")
			(net 650 "+1V0")
			(pinfunction "VCCINT")
			(pintype "passive")
			(solder_mask_margin 0.02)
		)
		(pad "N13" smd circle
			(at -2.5 -2.5)
			(size 0.5 0.5)
			(property pad_prop_bga)
			(layers "F.Cu" "F.Mask" "F.Paste")
			(net 1 "GND")
			(pinfunction "GND")
			(pintype "passive")
			(solder_mask_margin 0.02)
		)
		(pad "N14" smd circle
			(at -1.5 -2.5)
			(size 0.5 0.5)
			(property pad_prop_bga)
			(layers "F.Cu" "F.Mask" "F.Paste")
			(net 650 "+1V0")
			(pinfunction "VCCINT")
			(pintype "passive")
			(solder_mask_margin 0.02)
		)
		(pad "N15" smd circle
			(at -0.5 -2.5)
			(size 0.5 0.5)
			(property pad_prop_bga)
			(layers "F.Cu" "F.Mask" "F.Paste")
			(net 1 "GND")
			(pinfunction "GND")
			(pintype "passive")
			(solder_mask_margin 0.02)
		)
		(pad "N16" smd circle
			(at 0.5 -2.5)
			(size 0.5 0.5)
			(property pad_prop_bga)
			(layers "F.Cu" "F.Mask" "F.Paste")
			(net 650 "+1V0")
			(pinfunction "VCCBRAM")
			(pintype "bidirectional")
			(solder_mask_margin 0.02)
		)
		(pad "N17" smd circle
			(at 1.5 -2.5)
			(size 0.5 0.5)
			(property pad_prop_bga)
			(layers "F.Cu" "F.Mask" "F.Paste")
			(net 1 "GND")
			(pinfunction "GND")
			(pintype "passive")
			(solder_mask_margin 0.02)
		)
		(pad "N18" smd circle
			(at 2.5 -2.5)
			(size 0.5 0.5)
			(property pad_prop_bga)
			(layers "F.Cu" "F.Mask" "F.Paste")
			(net 650 "+1V0")
			(pinfunction "VCCINT")
			(pintype "passive")
			(solder_mask_margin 0.02)
		)
		(pad "N19" smd circle
			(at 3.5 -2.5)
			(size 0.5 0.5)
			(property pad_prop_bga)
			(layers "F.Cu" "F.Mask" "F.Paste")
			(net 1243 "/USER_IO.A15")
			(pinfunction "IO_L19P_T3_A22_15")
			(pintype "bidirectional")
			(die_length 10.222)
			(solder_mask_margin 0.02)
		)
		(pad "N20" smd circle
			(at 4.5 -2.5)
			(size 0.5 0.5)
			(property pad_prop_bga)
			(layers "F.Cu" "F.Mask" "F.Paste")
			(net 1342 "unconnected-(U1B-IO_L19N_T3_A21_VREF_15-PadN20)")
			(pinfunction "IO_L19N_T3_A21_VREF_15")
			(pintype "bidirectional+no_connect")
			(die_length 9.626)
			(solder_mask_margin 0.02)
		)
		(pad "N21" smd circle
			(at 5.5 -2.5)
			(size 0.5 0.5)
			(property pad_prop_bga)
			(layers "F.Cu" "F.Mask" "F.Paste")
			(net 1343 "unconnected-(U1B-IO_L20P_T3_A20_15-PadN21)")
			(pinfunction "IO_L20P_T3_A20_15")
			(pintype "bidirectional+no_connect")
			(die_length 9.801)
			(solder_mask_margin 0.02)
		)
		(pad "N22" smd circle
			(at 6.5 -2.5)
			(size 0.5 0.5)
			(property pad_prop_bga)
			(layers "F.Cu" "F.Mask" "F.Paste")
			(net 1344 "unconnected-(U1B-IO_L20N_T3_A19_15-PadN22)")
			(pinfunction "IO_L20N_T3_A19_15")
			(pintype "bidirectional+no_connect")
			(die_length 11.991)
			(solder_mask_margin 0.02)
		)
		(pad "N23" smd circle
			(at 7.5 -2.5)
			(size 0.5 0.5)
			(property pad_prop_bga)
			(layers "F.Cu" "F.Mask" "F.Paste")
			(net 2 "VCC_USR_A")
			(pinfunction "VCCO_15")
			(pintype "passive")
			(solder_mask_margin 0.02)
		)
		(pad "N24" smd circle
			(at 8.5 -2.5)
			(size 0.5 0.5)
			(property pad_prop_bga)
			(layers "F.Cu" "F.Mask" "F.Paste")
			(net 1345 "unconnected-(U1B-IO_L21N_T3_DQS_A18_15-PadN24)")
			(pinfunction "IO_L21N_T3_DQS_A18_15")
			(pintype "bidirectional+no_connect")
			(die_length 12.575)
			(solder_mask_margin 0.02)
		)
		(pad "N25" smd circle
			(at 9.5 -2.5)
			(size 0.5 0.5)
			(property pad_prop_bga)
			(layers "F.Cu" "F.Mask" "F.Paste")
			(net 1346 "unconnected-(U1B-IO_L18P_T2_A24_15-PadN25)")
			(pinfunction "IO_L18P_T2_A24_15")
			(pintype "bidirectional+no_connect")
			(die_length 14.113)
			(solder_mask_margin 0.02)
		)
		(pad "N26" smd circle
			(at 10.5 -2.5)
			(size 0.5 0.5)
			(property pad_prop_bga)
			(layers "F.Cu" "F.Mask" "F.Paste")
			(net 1263 "/USER_IO.A38")
			(pinfunction "IO_L18N_T2_A23_15")
			(pintype "bidirectional")
			(die_length 13.64)
			(solder_mask_margin 0.02)
		)
		(pad "N27" smd circle
			(at 11.5 -2.5)
			(size 0.5 0.5)
			(property pad_prop_bga)
			(layers "F.Cu" "F.Mask" "F.Paste")
			(net 1256 "/USER_IO.A30")
			(pinfunction "IO_L16P_T2_A28_15")
			(pintype "bidirectional")
			(die_length 13.775)
			(solder_mask_margin 0.02)
		)
		(pad "N28" smd circle
			(at 12.5 -2.5)
			(size 0.5 0.5)
			(property pad_prop_bga)
			(layers "F.Cu" "F.Mask" "F.Paste")
			(net 1 "GND")
			(pinfunction "GND")
			(pintype "passive")
			(solder_mask_margin 0.02)
		)
		(pad "N29" smd circle
			(at 13.5 -2.5)
			(size 0.5 0.5)
			(property pad_prop_bga)
			(layers "F.Cu" "F.Mask" "F.Paste")
			(net 1261 "/USER_IO.A36")
			(pinfunction "IO_L17P_T2_A26_15")
			(pintype "bidirectional")
			(die_length 16.115)
			(solder_mask_margin 0.02)
		)
		(pad "N30" smd circle
			(at 14.5 -2.5)
			(size 0.5 0.5)
			(property pad_prop_bga)
			(layers "F.Cu" "F.Mask" "F.Paste")
			(net 1250 "/USER_IO.A24")
			(pinfunction "IO_L17N_T2_A25_15")
			(pintype "bidirectional")
			(die_length 16.693)
			(solder_mask_margin 0.02)
		)
		(pad "P1" smd circle
			(at -14.5 -1.5)
			(size 0.5 0.5)
			(property pad_prop_bga)
			(layers "F.Cu" "F.Mask" "F.Paste")
			(net 82 "/FMC+ HSPC/GTX116.TX0_N")
			(pinfunction "MGTXTXN0_116")
			(pintype "bidirectional")
			(die_length 13.527)
			(solder_mask_margin 0.02)
		)
		(pad "P2" smd circle
			(at -13.5 -1.5)
			(size 0.5 0.5)
			(property pad_prop_bga)
			(layers "F.Cu" "F.Mask" "F.Paste")
			(net 80 "/FMC+ HSPC/GTX116.TX0_P")
			(pinfunction "MGTXTXP0_116")
			(pintype "bidirectional")
			(die_length 13.639)
			(solder_mask_margin 0.02)
		)
		(pad "P3" smd circle
			(at -12.5 -1.5)
			(size 0.5 0.5)
			(property pad_prop_bga)
			(layers "F.Cu" "F.Mask" "F.Paste")
			(net 8 "+1V2_MGTAVTT")
			(pinfunction "MGTAVTT")
			(pintype "passive")
			(solder_mask_margin 0.02)
		)
		(pad "P4" smd circle
			(at -11.5 -1.5)
			(size 0.5 0.5)
			(property pad_prop_bga)
			(layers "F.Cu" "F.Mask" "F.Paste")
			(net 1 "GND")
			(pinfunction "GND")
			(pintype "passive")
			(solder_mask_margin 0.02)
		)
		(pad "P5" smd circle
			(at -10.5 -1.5)
			(size 0.5 0.5)
			(property pad_prop_bga)
			(layers "F.Cu" "F.Mask" "F.Paste")
			(net 307 "/FMC+ HSPC/GTX116.RX2_N")
			(pinfunction "MGTXRXN2_116")
			(pintype "bidirectional")
			(die_length 12.032)
			(solder_mask_margin 0.02)
		)
		(pad "P6" smd circle
			(at -9.5 -1.5)
			(size 0.5 0.5)
			(property pad_prop_bga)
			(layers "F.Cu" "F.Mask" "F.Paste")
			(net 312 "/FMC+ HSPC/GTX116.RX2_P")
			(pinfunction "MGTXRXP2_116")
			(pintype "bidirectional")
			(die_length 12.187)
			(solder_mask_margin 0.02)
		)
		(pad "P7" smd circle
			(at -8.5 -1.5)
			(size 0.5 0.5)
			(property pad_prop_bga)
			(layers "F.Cu" "F.Mask" "F.Paste")
			(net 6 "+1V0_MGTAVCC")
			(pinfunction "MGTAVCC")
			(pintype "passive")
			(solder_mask_margin 0.02)
		)
		(pad "P8" smd circle
			(at -7.5 -1.5)
			(size 0.5 0.5)
			(property pad_prop_bga)
			(layers "F.Cu" "F.Mask" "F.Paste")
			(net 1 "GND")
			(pinfunction "GND")
			(pintype "passive")
			(solder_mask_margin 0.02)
		)
		(pad "P9" smd circle
			(at -6.5 -1.5)
			(size 0.5 0.5)
			(property pad_prop_bga)
			(layers "F.Cu" "F.Mask" "F.Paste")
			(net 1 "GND")
			(pinfunction "GND")
			(pintype "passive")
			(solder_mask_margin 0.02)
		)
		(pad "P10" smd circle
			(at -5.5 -1.5)
			(size 0.5 0.5)
			(property pad_prop_bga)
			(layers "F.Cu" "F.Mask" "F.Paste")
			(net 1 "GND")
			(pinfunction "GND")
			(pintype "passive")
			(solder_mask_margin 0.02)
		)
		(pad "P11" smd circle
			(at -4.5 -1.5)
			(size 0.5 0.5)
			(property pad_prop_bga)
			(layers "F.Cu" "F.Mask" "F.Paste")
			(net 650 "+1V0")
			(pinfunction "VCCINT")
			(pintype "passive")
			(solder_mask_margin 0.02)
		)
		(pad "P12" smd circle
			(at -3.5 -1.5)
			(size 0.5 0.5)
			(property pad_prop_bga)
			(layers "F.Cu" "F.Mask" "F.Paste")
			(net 1 "GND")
			(pinfunction "GND")
			(pintype "passive")
			(solder_mask_margin 0.02)
		)
		(pad "P13" smd circle
			(at -2.5 -1.5)
			(size 0.5 0.5)
			(property pad_prop_bga)
			(layers "F.Cu" "F.Mask" "F.Paste")
			(net 26 "+1V8")
			(pinfunction "VCCAUX")
			(pintype "bidirectional")
			(solder_mask_margin 0.02)
		)
		(pad "P14" smd circle
			(at -1.5 -1.5)
			(size 0.5 0.5)
			(property pad_prop_bga)
			(layers "F.Cu" "F.Mask" "F.Paste")
			(net 1 "GND")
			(pinfunction "GNDADC_0")
			(pintype "bidirectional")
			(solder_mask_margin 0.02)
		)
		(pad "P15" smd circle
			(at -0.5 -1.5)
			(size 0.5 0.5)
			(property pad_prop_bga)
			(layers "F.Cu" "F.Mask" "F.Paste")
			(net 622 "+1V85_ADC")
			(pinfunction "VCCADC_0")
			(pintype "bidirectional")
			(solder_mask_margin 0.02)
		)
		(pad "P16" smd circle
			(at 0.5 -1.5)
			(size 0.5 0.5)
			(property pad_prop_bga)
			(layers "F.Cu" "F.Mask" "F.Paste")
			(net 1 "GND")
			(pinfunction "GND")
			(pintype "passive")
			(solder_mask_margin 0.02)
		)
		(pad "P17" smd circle
			(at 1.5 -1.5)
			(size 0.5 0.5)
			(property pad_prop_bga)
			(layers "F.Cu" "F.Mask" "F.Paste")
			(net 650 "+1V0")
			(pinfunction "VCCINT")
			(pintype "passive")
			(solder_mask_margin 0.02)
		)
		(pad "P18" smd circle
			(at 2.5 -1.5)
			(size 0.5 0.5)
			(property pad_prop_bga)
			(layers "F.Cu" "F.Mask" "F.Paste")
			(net 1 "GND")
			(pinfunction "GND")
			(pintype "passive")
			(solder_mask_margin 0.02)
		)
		(pad "P19" smd circle
			(at 3.5 -1.5)
			(size 0.5 0.5)
			(property pad_prop_bga)
			(layers "F.Cu" "F.Mask" "F.Paste")
			(net 1347 "unconnected-(U1B-IO_25_15-PadP19)")
			(pinfunction "IO_25_15")
			(pintype "bidirectional+no_connect")
			(die_length 8.83)
			(solder_mask_margin 0.02)
		)
		(pad "P20" smd circle
			(at 4.5 -1.5)
			(size 0.5 0.5)
			(property pad_prop_bga)
			(layers "F.Cu" "F.Mask" "F.Paste")
			(net 2 "VCC_USR_A")
			(pinfunction "VCCO_15")
			(pintype "passive")
			(solder_mask_margin 0.02)
		)
		(pad "P21" smd circle
			(at 5.5 -1.5)
			(size 0.5 0.5)
			(property pad_prop_bga)
			(layers "F.Cu" "F.Mask" "F.Paste")
			(net 1236 "/USER_IO.A5")
			(pinfunction "IO_L22P_T3_A17_15")
			(pintype "bidirectional")
			(die_length 9.84)
			(solder_mask_margin 0.02)
		)
		(pad "P22" smd circle
			(at 6.5 -1.5)
			(size 0.5 0.5)
			(property pad_prop_bga)
			(layers "F.Cu" "F.Mask" "F.Paste")
			(net 1253 "/USER_IO.A27")
			(pinfunction "IO_L22N_T3_A16_15")
			(pintype "bidirectional")
			(die_length 9.806)
			(solder_mask_margin 0.02)
		)
		(pad "P23" smd circle
			(at 7.5 -1.5)
			(size 0.5 0.5)
			(property pad_prop_bga)
			(layers "F.Cu" "F.Mask" "F.Paste")
			(net 1348 "unconnected-(U1B-IO_L21P_T3_DQS_15-PadP23)")
			(pinfunction "IO_L21P_T3_DQS_15")
			(pintype "bidirectional+no_connect")
			(die_length 12.753)
			(solder_mask_margin 0.02)
		)
		(pad "P24" smd circle
			(at 8.5 -1.5)
			(size 0.5 0.5)
			(property pad_prop_bga)
			(layers "F.Cu" "F.Mask" "F.Paste")
			(net 38 "/FPGA Bank 14 & 15/SYSTEM_FLASH.DQ0")
			(pinfunction "IO_L1P_T0_D00_MOSI_14")
			(pintype "bidirectional")
			(die_length 11.124)
			(solder_mask_margin 0.02)
		)
		(pad "P25" smd circle
			(at 9.5 -1.5)
			(size 0.5 0.5)
			(property pad_prop_bga)
			(layers "F.Cu" "F.Mask" "F.Paste")
			(net 1 "GND")
			(pinfunction "GND")
			(pintype "passive")
			(solder_mask_margin 0.02)
		)
		(pad "P26" smd circle
			(at 10.5 -1.5)
			(size 0.5 0.5)
			(property pad_prop_bga)
			(layers "F.Cu" "F.Mask" "F.Paste")
			(net 564 "/DRAM + SRAM/SRAM.~{OE}")
			(pinfunction "IO_L10P_T1_D14_14")
			(pintype "bidirectional")
			(die_length 15.193)
			(solder_mask_margin 0.02)
		)
		(pad "P27" smd circle
			(at 11.5 -1.5)
			(size 0.5 0.5)
			(property pad_prop_bga)
			(layers "F.Cu" "F.Mask" "F.Paste")
			(net 664 "/DRAM + SRAM/SRAM.A5")
			(pinfunction "IO_L8P_T1_D11_14")
			(pintype "bidirectional")
			(die_length 15.077)
			(solder_mask_margin 0.02)
		)
		(pad "P28" smd circle
			(at 12.5 -1.5)
			(size 0.5 0.5)
			(property pad_prop_bga)
			(layers "F.Cu" "F.Mask" "F.Paste")
			(net 665 "/DRAM + SRAM/SRAM.A6")
			(pinfunction "IO_L8N_T1_D12_14")
			(pintype "bidirectional")
			(die_length 14.693)
			(solder_mask_margin 0.02)
		)
		(pad "P29" smd circle
			(at 13.5 -1.5)
			(size 0.5 0.5)
			(property pad_prop_bga)
			(layers "F.Cu" "F.Mask" "F.Paste")
			(net 666 "/DRAM + SRAM/SRAM.DQ3")
			(pinfunction "IO_L7P_T1_D09_14")
			(pintype "bidirectional")
			(die_length 16.815)
			(solder_mask_margin 0.02)
		)
		(pad "P30" smd circle
			(at 14.5 -1.5)
			(size 0.5 0.5)
			(property pad_prop_bga)
			(layers "F.Cu" "F.Mask" "F.Paste")
			(net 24 "+3V3")
			(pinfunction "VCCO_14")
			(pintype "bidirectional")
			(solder_mask_margin 0.02)
		)
		(pad "R1" smd circle
			(at -14.5 -0.5)
			(size 0.5 0.5)
			(property pad_prop_bga)
			(layers "F.Cu" "F.Mask" "F.Paste")
			(net 1 "GND")
			(pinfunction "GND")
			(pintype "passive")
			(solder_mask_margin 0.02)
		)
		(pad "R2" smd circle
			(at -13.5 -0.5)
			(size 0.5 0.5)
			(property pad_prop_bga)
			(layers "F.Cu" "F.Mask" "F.Paste")
			(net 1 "GND")
			(pinfunction "GND")
			(pintype "passive")
			(solder_mask_margin 0.02)
		)
		(pad "R3" smd circle
			(at -12.5 -0.5)
			(size 0.5 0.5)
			(property pad_prop_bga)
			(layers "F.Cu" "F.Mask" "F.Paste")
			(net 282 "/FMC+ HSPC/GTX116.RX3_N")
			(pinfunction "MGTXRXN1_116")
			(pintype "bidirectional")
			(die_length 12.761)
			(solder_mask_margin 0.02)
		)
		(pad "R4" smd circle
			(at -11.5 -0.5)
			(size 0.5 0.5)
			(property pad_prop_bga)
			(layers "F.Cu" "F.Mask" "F.Paste")
			(net 287 "/FMC+ HSPC/GTX116.RX3_P")
			(pinfunction "MGTXRXP1_116")
			(pintype "bidirectional")
			(die_length 12.836)
			(solder_mask_margin 0.02)
		)
		(pad "R5" smd circle
			(at -10.5 -0.5)
			(size 0.5 0.5)
			(property pad_prop_bga)
			(layers "F.Cu" "F.Mask" "F.Paste")
			(net 8 "+1V2_MGTAVTT")
			(pinfunction "MGTAVTT")
			(pintype "passive")
			(solder_mask_margin 0.02)
		)
		(pad "R6" smd circle
			(at -9.5 -0.5)
			(size 0.5 0.5)
			(property pad_prop_bga)
			(layers "F.Cu" "F.Mask" "F.Paste")
			(net 1 "GND")
			(pinfunction "GND")
			(pintype "passive")
			(solder_mask_margin 0.02)
		)
		(pad "R7" smd circle
			(at -8.5 -0.5)
			(size 0.5 0.5)
			(property pad_prop_bga)
			(layers "F.Cu" "F.Mask" "F.Paste")
			(net 630 "/FMC+ HSPC/GTX115.REFCLK0_N")
			(pinfunction "MGTREFCLK0N_115")
			(pintype "bidirectional")
			(die_length 7.794)
			(solder_mask_margin 0.02)
		)
		(pad "R8" smd circle
			(at -7.5 -0.5)
			(size 0.5 0.5)
			(property pad_prop_bga)
			(layers "F.Cu" "F.Mask" "F.Paste")
			(net 628 "/FMC+ HSPC/GTX115.REFCLK0_P")
			(pinfunction "MGTREFCLK0P_115")
			(pintype "bidirectional")
			(die_length 7.477)
			(solder_mask_margin 0.02)
		)
		(pad "R9" smd circle
			(at -6.5 -0.5)
			(size 0.5 0.5)
			(property pad_prop_bga)
			(layers "F.Cu" "F.Mask" "F.Paste")
			(net 1 "GND")
			(pinfunction "GND")
			(pintype "passive")
			(solder_mask_margin 0.02)
		)
		(pad "R10" smd circle
			(at -5.5 -0.5)
			(size 0.5 0.5)
			(property pad_prop_bga)
			(layers "F.Cu" "F.Mask" "F.Paste")
			(net 650 "+1V0")
			(pinfunction "VCCINT")
			(pintype "passive")
			(solder_mask_margin 0.02)
		)
		(pad "R11" smd circle
			(at -4.5 -0.5)
			(size 0.5 0.5)
			(property pad_prop_bga)
			(layers "F.Cu" "F.Mask" "F.Paste")
			(net 1 "GND")
			(pinfunction "GND")
			(pintype "passive")
			(solder_mask_margin 0.02)
		)
		(pad "R12" smd circle
			(at -3.5 -0.5)
			(size 0.5 0.5)
			(property pad_prop_bga)
			(layers "F.Cu" "F.Mask" "F.Paste")
			(net 650 "+1V0")
			(pinfunction "VCCINT")
			(pintype "passive")
			(solder_mask_margin 0.02)
		)
		(pad "R13" smd circle
			(at -2.5 -0.5)
			(size 0.5 0.5)
			(property pad_prop_bga)
			(layers "F.Cu" "F.Mask" "F.Paste")
			(net 1 "GND")
			(pinfunction "GND")
			(pintype "passive")
			(solder_mask_margin 0.02)
		)
		(pad "R14" smd circle
			(at -1.5 -0.5)
			(size 0.5 0.5)
			(property pad_prop_bga)
			(layers "F.Cu" "F.Mask" "F.Paste")
			(net 1 "GND")
			(pinfunction "VREFN_0")
			(pintype "bidirectional")
			(die_length 10.643)
			(solder_mask_margin 0.02)
		)
		(pad "R15" smd circle
			(at -0.5 -0.5)
			(size 0.5 0.5)
			(property pad_prop_bga)
			(layers "F.Cu" "F.Mask" "F.Paste")
			(net 1395 "unconnected-(U1I-VP_0-PadR15)")
			(pinfunction "VP_0")
			(pintype "bidirectional+no_connect")
			(die_length 9.522)
			(solder_mask_margin 0.02)
		)
		(pad "R16" smd circle
			(at 0.5 -0.5)
			(size 0.5 0.5)
			(property pad_prop_bga)
			(layers "F.Cu" "F.Mask" "F.Paste")
			(net 650 "+1V0")
			(pinfunction "VCCBRAM")
			(pintype "passive")
			(solder_mask_margin 0.02)
		)
		(pad "R17" smd circle
			(at 1.5 -0.5)
			(size 0.5 0.5)
			(property pad_prop_bga)
			(layers "F.Cu" "F.Mask" "F.Paste")
			(net 1 "GND")
			(pinfunction "GND")
			(pintype "passive")
			(solder_mask_margin 0.02)
		)
		(pad "R18" smd circle
			(at 2.5 -0.5)
			(size 0.5 0.5)
			(property pad_prop_bga)
			(layers "F.Cu" "F.Mask" "F.Paste")
			(net 650 "+1V0")
			(pinfunction "VCCINT")
			(pintype "passive")
			(solder_mask_margin 0.02)
		)
		(pad "R19" smd circle
			(at 3.5 -0.5)
			(size 0.5 0.5)
			(property pad_prop_bga)
			(layers "F.Cu" "F.Mask" "F.Paste")
			(net 403 "/FPGA Bank 14 & 15/SYSTEM_FLASH.DQ2")
			(pinfunction "IO_0_14")
			(pintype "bidirectional")
			(die_length 7.988)
			(solder_mask_margin 0.02)
		)
		(pad "R20" smd circle
			(at 4.5 -0.5)
			(size 0.5 0.5)
			(property pad_prop_bga)
			(layers "F.Cu" "F.Mask" "F.Paste")
			(net 1386 "/SUP_MCU.SCLK1")
			(pinfunction "IO_L2P_T0_D02_14")
			(pintype "bidirectional")
			(die_length 11.33)
			(solder_mask_margin 0.02)
		)
		(pad "R21" smd circle
			(at 5.5 -0.5)
			(size 0.5 0.5)
			(property pad_prop_bga)
			(layers "F.Cu" "F.Mask" "F.Paste")
			(net 1294 "/USB_SPI.MISO")
			(pinfunction "IO_L2N_T0_D03_14")
			(pintype "bidirectional")
			(die_length 9.937)
			(solder_mask_margin 0.02)
		)
		(pad "R22" smd circle
			(at 6.5 -0.5)
			(size 0.5 0.5)
			(property pad_prop_bga)
			(layers "F.Cu" "F.Mask" "F.Paste")
			(net 1 "GND")
			(pinfunction "GND")
			(pintype "passive")
			(solder_mask_margin 0.02)
		)
		(pad "R23" smd circle
			(at 7.5 -0.5)
			(size 0.5 0.5)
			(property pad_prop_bga)
			(layers "F.Cu" "F.Mask" "F.Paste")
			(net 566 "/FPGA Bank 14 & 15/CFG_PUDC")
			(pinfunction "IO_L3P_T0_DQS_PUDC_B_14")
			(pintype "bidirectional")
			(die_length 10.245)
			(solder_mask_margin 0.02)
		)
		(pad "R24" smd circle
			(at 8.5 -0.5)
			(size 0.5 0.5)
			(property pad_prop_bga)
			(layers "F.Cu" "F.Mask" "F.Paste")
			(net 398 "/FPGA Bank 14 & 15/SYSTEM_FLASH.DQ3")
			(pinfunction "IO_L3N_T0_DQS_EMCCLK_14")
			(pintype "bidirectional")
			(die_length 10.11)
			(solder_mask_margin 0.02)
		)
		(pad "R25" smd circle
			(at 9.5 -0.5)
			(size 0.5 0.5)
			(property pad_prop_bga)
			(layers "F.Cu" "F.Mask" "F.Paste")
			(net 43 "/FPGA Bank 14 & 15/SYSTEM_FLASH.DQ1")
			(pinfunction "IO_L1N_T0_D01_DIN_14")
			(pintype "bidirectional")
			(die_length 10.823)
			(solder_mask_margin 0.02)
		)
		(pad "R26" smd circle
			(at 10.5 -0.5)
			(size 0.5 0.5)
			(property pad_prop_bga)
			(layers "F.Cu" "F.Mask" "F.Paste")
			(net 667 "/DRAM + SRAM/SRAM.A8")
			(pinfunction "IO_L10N_T1_D15_14")
			(pintype "bidirectional")
			(die_length 13.845)
			(solder_mask_margin 0.02)
		)
		(pad "R27" smd circle
			(at 11.5 -0.5)
			(size 0.5 0.5)
			(property pad_prop_bga)
			(layers "F.Cu" "F.Mask" "F.Paste")
			(net 24 "+3V3")
			(pinfunction "VCCO_14")
			(pintype "passive")
			(solder_mask_margin 0.02)
		)
		(pad "R28" smd circle
			(at 12.5 -0.5)
			(size 0.5 0.5)
			(property pad_prop_bga)
			(layers "F.Cu" "F.Mask" "F.Paste")
			(net 668 "/DRAM + SRAM/SRAM.DQ6")
			(pinfunction "IO_L11P_T1_SRCC_14")
			(pintype "bidirectional")
			(die_length 14.17)
			(solder_mask_margin 0.02)
		)
		(pad "R29" smd circle
			(at 13.5 -0.5)
			(size 0.5 0.5)
			(property pad_prop_bga)
			(layers "F.Cu" "F.Mask" "F.Paste")
			(net 669 "/DRAM + SRAM/SRAM.DQ7")
			(pinfunction "IO_L7N_T1_D10_14")
			(pintype "bidirectional")
			(die_length 16.165)
			(solder_mask_margin 0.02)
		)
		(pad "R30" smd circle
			(at 14.5 -0.5)
			(size 0.5 0.5)
			(property pad_prop_bga)
			(layers "F.Cu" "F.Mask" "F.Paste")
			(net 670 "/DRAM + SRAM/SRAM.A9")
			(pinfunction "IO_L9P_T1_DQS_14")
			(pintype "bidirectional")
			(die_length 16.981)
			(solder_mask_margin 0.02)
		)
		(pad "T1" smd circle
			(at -14.5 0.5)
			(size 0.5 0.5)
			(property pad_prop_bga)
			(layers "F.Cu" "F.Mask" "F.Paste")
			(net 124 "/FMC+ HSPC/GTX115.TX0_N")
			(pinfunction "MGTXTXN3_115")
			(pintype "bidirectional")
			(die_length 13.793)
			(solder_mask_margin 0.02)
		)
		(pad "T2" smd circle
			(at -13.5 0.5)
			(size 0.5 0.5)
			(property pad_prop_bga)
			(layers "F.Cu" "F.Mask" "F.Paste")
			(net 122 "/FMC+ HSPC/GTX115.TX0_P")
			(pinfunction "MGTXTXP3_115")
			(pintype "bidirectional")
			(die_length 13.764)
			(solder_mask_margin 0.02)
		)
		(pad "T3" smd circle
			(at -12.5 0.5)
			(size 0.5 0.5)
			(property pad_prop_bga)
			(layers "F.Cu" "F.Mask" "F.Paste")
			(net 8 "+1V2_MGTAVTT")
			(pinfunction "MGTAVTT")
			(pintype "passive")
			(solder_mask_margin 0.02)
		)
		(pad "T4" smd circle
			(at -11.5 0.5)
			(size 0.5 0.5)
			(property pad_prop_bga)
			(layers "F.Cu" "F.Mask" "F.Paste")
			(net 1 "GND")
			(pinfunction "GND")
			(pintype "passive")
			(solder_mask_margin 0.02)
		)
		(pad "T5" smd circle
			(at -10.5 0.5)
			(size 0.5 0.5)
			(property pad_prop_bga)
			(layers "F.Cu" "F.Mask" "F.Paste")
			(net 490 "/FMC+ HSPC/GTX116.RX0_N")
			(pinfunction "MGTXRXN0_116")
			(pintype "bidirectional")
			(die_length 12.339)
			(solder_mask_margin 0.02)
		)
		(pad "T6" smd circle
			(at -9.5 0.5)
			(size 0.5 0.5)
			(property pad_prop_bga)
			(layers "F.Cu" "F.Mask" "F.Paste")
			(net 249 "/FMC+ HSPC/GTX116.RX0_P")
			(pinfunction "MGTXRXP0_116")
			(pintype "bidirectional")
			(die_length 12.521)
			(solder_mask_margin 0.02)
		)
		(pad "T7" smd circle
			(at -8.5 0.5)
			(size 0.5 0.5)
			(property pad_prop_bga)
			(layers "F.Cu" "F.Mask" "F.Paste")
			(net 26 "+1V8")
			(pinfunction "MGTVCCAUX")
			(pintype "bidirectional")
			(solder_mask_margin 0.02)
		)
		(pad "T8" smd circle
			(at -7.5 0.5)
			(size 0.5 0.5)
			(property pad_prop_bga)
			(layers "F.Cu" "F.Mask" "F.Paste")
			(net 1 "GND")
			(pinfunction "GND")
			(pintype "passive")
			(solder_mask_margin 0.02)
		)
		(pad "T9" smd circle
			(at -6.5 0.5)
			(size 0.5 0.5)
			(property pad_prop_bga)
			(layers "F.Cu" "F.Mask" "F.Paste")
			(net 24 "+3V3")
			(pinfunction "VCCO_0")
			(pintype "passive")
			(solder_mask_margin 0.02)
		)
		(pad "T10" smd circle
			(at -5.5 0.5)
			(size 0.5 0.5)
			(property pad_prop_bga)
			(layers "F.Cu" "F.Mask" "F.Paste")
			(net 1 "GND")
			(pinfunction "GND")
			(pintype "passive")
			(solder_mask_margin 0.02)
		)
		(pad "T11" smd circle
			(at -4.5 0.5)
			(size 0.5 0.5)
			(property pad_prop_bga)
			(layers "F.Cu" "F.Mask" "F.Paste")
			(net 650 "+1V0")
			(pinfunction "VCCINT")
			(pintype "passive")
			(solder_mask_margin 0.02)
		)
		(pad "T12" smd circle
			(at -3.5 0.5)
			(size 0.5 0.5)
			(property pad_prop_bga)
			(layers "F.Cu" "F.Mask" "F.Paste")
			(net 1 "GND")
			(pinfunction "GND")
			(pintype "passive")
			(solder_mask_margin 0.02)
		)
		(pad "T13" smd circle
			(at -2.5 0.5)
			(size 0.5 0.5)
			(property pad_prop_bga)
			(layers "F.Cu" "F.Mask" "F.Paste")
			(net 26 "+1V8")
			(pinfunction "VCCAUX")
			(pintype "passive")
			(solder_mask_margin 0.02)
		)
		(pad "T14" smd circle
			(at -1.5 0.5)
			(size 0.5 0.5)
			(property pad_prop_bga)
			(layers "F.Cu" "F.Mask" "F.Paste")
			(net 1396 "unconnected-(U1I-VN_0-PadT14)")
			(pinfunction "VN_0")
			(pintype "bidirectional+no_connect")
			(die_length 10.582)
			(solder_mask_margin 0.02)
		)
		(pad "T15" smd circle
			(at -0.5 0.5)
			(size 0.5 0.5)
			(property pad_prop_bga)
			(layers "F.Cu" "F.Mask" "F.Paste")
			(net 649 "VREFP")
			(pinfunction "VREFP_0")
			(pintype "bidirectional")
			(die_length 10.695)
			(solder_mask_margin 0.02)
		)
		(pad "T16" smd circle
			(at 0.5 0.5)
			(size 0.5 0.5)
			(property pad_prop_bga)
			(layers "F.Cu" "F.Mask" "F.Paste")
			(net 1 "GND")
			(pinfunction "GND")
			(pintype "passive")
			(solder_mask_margin 0.02)
		)
		(pad "T17" smd circle
			(at 1.5 0.5)
			(size 0.5 0.5)
			(property pad_prop_bga)
			(layers "F.Cu" "F.Mask" "F.Paste")
			(net 650 "+1V0")
			(pinfunction "VCCINT")
			(pintype "passive")
			(solder_mask_margin 0.02)
		)
		(pad "T18" smd circle
			(at 2.5 0.5)
			(size 0.5 0.5)
			(property pad_prop_bga)
			(layers "F.Cu" "F.Mask" "F.Paste")
			(net 1 "GND")
			(pinfunction "GND")
			(pintype "passive")
			(solder_mask_margin 0.02)
		)
		(pad "T19" smd circle
			(at 3.5 0.5)
			(size 0.5 0.5)
			(property pad_prop_bga)
			(layers "F.Cu" "F.Mask" "F.Paste")
			(net 1 "GND")
			(pinfunction "GND")
			(pintype "passive")
			(solder_mask_margin 0.02)
		)
		(pad "T20" smd circle
			(at 4.5 0.5)
			(size 0.5 0.5)
			(property pad_prop_bga)
			(layers "F.Cu" "F.Mask" "F.Paste")
			(net 1385 "/SUP_MCU.SPARE3")
			(pinfunction "IO_L4P_T0_D04_14")
			(pintype "bidirectional")
			(die_length 9.515)
			(solder_mask_margin 0.02)
		)
		(pad "T21" smd circle
			(at 5.5 0.5)
			(size 0.5 0.5)
			(property pad_prop_bga)
			(layers "F.Cu" "F.Mask" "F.Paste")
			(net 1295 "/USB_SPI.MOSI")
			(pinfunction "IO_L4N_T0_D05_14")
			(pintype "bidirectional")
			(die_length 8.352)
			(solder_mask_margin 0.02)
		)
		(pad "T22" smd circle
			(at 6.5 0.5)
			(size 0.5 0.5)
			(property pad_prop_bga)
			(layers "F.Cu" "F.Mask" "F.Paste")
			(net 1296 "/USB_SPI.SCK")
			(pinfunction "IO_L5P_T0_D06_14")
			(pintype "bidirectional")
			(die_length 8.945)
			(solder_mask_margin 0.02)
		)
		(pad "T23" smd circle
			(at 7.5 0.5)
			(size 0.5 0.5)
			(property pad_prop_bga)
			(layers "F.Cu" "F.Mask" "F.Paste")
			(net 1297 "/USB_SPI.~{CS}")
			(pinfunction "IO_L5N_T0_D07_14")
			(pintype "bidirectional")
			(die_length 9.494)
			(solder_mask_margin 0.02)
		)
		(pad "T24" smd circle
			(at 8.5 0.5)
			(size 0.5 0.5)
			(property pad_prop_bga)
			(layers "F.Cu" "F.Mask" "F.Paste")
			(net 24 "+3V3")
			(pinfunction "VCCO_14")
			(pintype "passive")
			(solder_mask_margin 0.02)
		)
		(pad "T25" smd circle
			(at 9.5 0.5)
			(size 0.5 0.5)
			(property pad_prop_bga)
			(layers "F.Cu" "F.Mask" "F.Paste")
			(net 671 "/DRAM + SRAM/SRAM.A2")
			(pinfunction "IO_L14P_T2_SRCC_14")
			(pintype "bidirectional")
			(die_length 11.691)
			(solder_mask_margin 0.02)
		)
		(pad "T26" smd circle
			(at 10.5 0.5)
			(size 0.5 0.5)
			(property pad_prop_bga)
			(layers "F.Cu" "F.Mask" "F.Paste")
			(net 672 "/DRAM + SRAM/SRAM.A3")
			(pinfunction "IO_L12P_T1_MRCC_14")
			(pintype "bidirectional")
			(die_length 14.679)
			(solder_mask_margin 0.02)
		)
		(pad "T27" smd circle
			(at 11.5 0.5)
			(size 0.5 0.5)
			(property pad_prop_bga)
			(layers "F.Cu" "F.Mask" "F.Paste")
			(net 673 "/DRAM + SRAM/SRAM.A13")
			(pinfunction "IO_L12N_T1_MRCC_14")
			(pintype "bidirectional")
			(die_length 14.259)
			(solder_mask_margin 0.02)
		)
		(pad "T28" smd circle
			(at 12.5 0.5)
			(size 0.5 0.5)
			(property pad_prop_bga)
			(layers "F.Cu" "F.Mask" "F.Paste")
			(net 674 "/DRAM + SRAM/SRAM.DQ5")
			(pinfunction "IO_L11N_T1_SRCC_14")
			(pintype "bidirectional")
			(die_length 14.716)
			(solder_mask_margin 0.02)
		)
		(pad "T29" smd circle
			(at 13.5 0.5)
			(size 0.5 0.5)
			(property pad_prop_bga)
			(layers "F.Cu" "F.Mask" "F.Paste")
			(net 1 "GND")
			(pinfunction "GND")
			(pintype "passive")
			(solder_mask_margin 0.02)
		)
		(pad "T30" smd circle
			(at 14.5 0.5)
			(size 0.5 0.5)
			(property pad_prop_bga)
			(layers "F.Cu" "F.Mask" "F.Paste")
			(net 675 "/DRAM + SRAM/SRAM.A15")
			(pinfunction "IO_L9N_T1_DQS_D13_14")
			(pintype "bidirectional")
			(die_length 17.602)
			(solder_mask_margin 0.02)
		)
		(pad "U1" smd circle
			(at -14.5 1.5)
			(size 0.5 0.5)
			(property pad_prop_bga)
			(layers "F.Cu" "F.Mask" "F.Paste")
			(net 1 "GND")
			(pinfunction "GND")
			(pintype "passive")
			(solder_mask_margin 0.02)
		)
		(pad "U2" smd circle
			(at -13.5 1.5)
			(size 0.5 0.5)
			(property pad_prop_bga)
			(layers "F.Cu" "F.Mask" "F.Paste")
			(net 1 "GND")
			(pinfunction "GND")
			(pintype "passive")
			(solder_mask_margin 0.02)
		)
		(pad "U3" smd circle
			(at -12.5 1.5)
			(size 0.5 0.5)
			(property pad_prop_bga)
			(layers "F.Cu" "F.Mask" "F.Paste")
			(net 89 "/FMC+ HSPC/GTX115.TX3_N")
			(pinfunction "MGTXTXN2_115")
			(pintype "bidirectional")
			(die_length 12.101)
			(solder_mask_margin 0.02)
		)
		(pad "U4" smd circle
			(at -11.5 1.5)
			(size 0.5 0.5)
			(property pad_prop_bga)
			(layers "F.Cu" "F.Mask" "F.Paste")
			(net 87 "/FMC+ HSPC/GTX115.TX3_P")
			(pinfunction "MGTXTXP2_115")
			(pintype "bidirectional")
			(die_length 12.157)
			(solder_mask_margin 0.02)
		)
		(pad "U5" smd circle
			(at -10.5 1.5)
			(size 0.5 0.5)
			(property pad_prop_bga)
			(layers "F.Cu" "F.Mask" "F.Paste")
			(net 8 "+1V2_MGTAVTT")
			(pinfunction "MGTAVTT")
			(pintype "passive")
			(solder_mask_margin 0.02)
		)
		(pad "U6" smd circle
			(at -9.5 1.5)
			(size 0.5 0.5)
			(property pad_prop_bga)
			(layers "F.Cu" "F.Mask" "F.Paste")
			(net 1 "GND")
			(pinfunction "GND")
			(pintype "passive")
			(solder_mask_margin 0.02)
		)
		(pad "U7" smd circle
			(at -8.5 1.5)
			(size 0.5 0.5)
			(property pad_prop_bga)
			(layers "F.Cu" "F.Mask" "F.Paste")
			(net 592 "/FMC+ HSPC/GTX115.REFCLK1_N")
			(pinfunction "MGTREFCLK1N_115")
			(pintype "bidirectional")
			(die_length 8.79)
			(solder_mask_margin 0.02)
		)
		(pad "U8" smd circle
			(at -7.5 1.5)
			(size 0.5 0.5)
			(property pad_prop_bga)
			(layers "F.Cu" "F.Mask" "F.Paste")
			(net 591 "/FMC+ HSPC/GTX115.REFCLK1_P")
			(pinfunction "MGTREFCLK1P_115")
			(pintype "bidirectional")
			(die_length 8.447)
			(solder_mask_margin 0.02)
		)
		(pad "U9" smd circle
			(at -6.5 1.5)
			(size 0.5 0.5)
			(property pad_prop_bga)
			(layers "F.Cu" "F.Mask" "F.Paste")
			(net 1 "GND")
			(pinfunction "GND")
			(pintype "passive")
			(solder_mask_margin 0.02)
		)
		(pad "U10" smd circle
			(at -5.5 1.5)
			(size 0.5 0.5)
			(property pad_prop_bga)
			(layers "F.Cu" "F.Mask" "F.Paste")
			(net 650 "+1V0")
			(pinfunction "VCCINT")
			(pintype "passive")
			(solder_mask_margin 0.02)
		)
		(pad "U11" smd circle
			(at -4.5 1.5)
			(size 0.5 0.5)
			(property pad_prop_bga)
			(layers "F.Cu" "F.Mask" "F.Paste")
			(net 1 "GND")
			(pinfunction "GND")
			(pintype "passive")
			(solder_mask_margin 0.02)
		)
		(pad "U12" smd circle
			(at -3.5 1.5)
			(size 0.5 0.5)
			(property pad_prop_bga)
			(layers "F.Cu" "F.Mask" "F.Paste")
			(net 650 "+1V0")
			(pinfunction "VCCINT")
			(pintype "passive")
			(solder_mask_margin 0.02)
		)
		(pad "U13" smd circle
			(at -2.5 1.5)
			(size 0.5 0.5)
			(property pad_prop_bga)
			(layers "F.Cu" "F.Mask" "F.Paste")
			(net 1 "GND")
			(pinfunction "GND")
			(pintype "passive")
			(solder_mask_margin 0.02)
		)
		(pad "U14" smd circle
			(at -1.5 1.5)
			(size 0.5 0.5)
			(property pad_prop_bga)
			(layers "F.Cu" "F.Mask" "F.Paste")
			(net 9 "/FPGA Config/FPGA_CFG_DXN")
			(pinfunction "DXN_0")
			(pintype "bidirectional")
			(die_length 11.927)
			(solder_mask_margin 0.02)
		)
		(pad "U15" smd circle
			(at -0.5 1.5)
			(size 0.5 0.5)
			(property pad_prop_bga)
			(layers "F.Cu" "F.Mask" "F.Paste")
			(net 10 "/FPGA Config/FPGA_CFG_DXP")
			(pinfunction "DXP_0")
			(pintype "bidirectional")
			(die_length 10.856)
			(solder_mask_margin 0.02)
		)
		(pad "U16" smd circle
			(at 0.5 1.5)
			(size 0.5 0.5)
			(property pad_prop_bga)
			(layers "F.Cu" "F.Mask" "F.Paste")
			(net 650 "+1V0")
			(pinfunction "VCCBRAM")
			(pintype "passive")
			(solder_mask_margin 0.02)
		)
		(pad "U17" smd circle
			(at 1.5 1.5)
			(size 0.5 0.5)
			(property pad_prop_bga)
			(layers "F.Cu" "F.Mask" "F.Paste")
			(net 1 "GND")
			(pinfunction "GND")
			(pintype "passive")
			(solder_mask_margin 0.02)
		)
		(pad "U18" smd circle
			(at 2.5 1.5)
			(size 0.5 0.5)
			(property pad_prop_bga)
			(layers "F.Cu" "F.Mask" "F.Paste")
			(net 650 "+1V0")
			(pinfunction "VCCINT")
			(pintype "passive")
			(solder_mask_margin 0.02)
		)
		(pad "U19" smd circle
			(at 3.5 1.5)
			(size 0.5 0.5)
			(property pad_prop_bga)
			(layers "F.Cu" "F.Mask" "F.Paste")
			(net 75 "/FPGA Bank 14 & 15/SYSTEM_FLASH.~{CS}")
			(pinfunction "IO_L6P_T0_FCS_B_14")
			(pintype "bidirectional")
			(die_length 8.184)
			(solder_mask_margin 0.02)
		)
		(pad "U20" smd circle
			(at 4.5 1.5)
			(size 0.5 0.5)
			(property pad_prop_bga)
			(layers "F.Cu" "F.Mask" "F.Paste")
			(net 676 "/DRAM + SRAM/SRAM.DQ4")
			(pinfunction "IO_L6N_T0_D08_VREF_14")
			(pintype "bidirectional")
			(die_length 6.954)
			(solder_mask_margin 0.02)
		)
		(pad "U21" smd circle
			(at 5.5 1.5)
			(size 0.5 0.5)
			(property pad_prop_bga)
			(layers "F.Cu" "F.Mask" "F.Paste")
			(net 24 "+3V3")
			(pinfunction "VCCO_14")
			(pintype "passive")
			(solder_mask_margin 0.02)
		)
		(pad "U22" smd circle
			(at 6.5 1.5)
			(size 0.5 0.5)
			(property pad_prop_bga)
			(layers "F.Cu" "F.Mask" "F.Paste")
			(net 562 "/DRAM + SRAM/SRAM.CE2")
			(pinfunction "IO_L21P_T3_DQS_14")
			(pintype "bidirectional")
			(die_length 11.116)
			(solder_mask_margin 0.02)
		)
		(pad "U23" smd circle
			(at 7.5 1.5)
			(size 0.5 0.5)
			(property pad_prop_bga)
			(layers "F.Cu" "F.Mask" "F.Paste")
			(net 677 "/DRAM + SRAM/SRAM.A14")
			(pinfunction "IO_L21N_T3_DQS_A06_D22_14")
			(pintype "bidirectional")
			(die_length 11.023)
			(solder_mask_margin 0.02)
		)
		(pad "U24" smd circle
			(at 8.5 1.5)
			(size 0.5 0.5)
			(property pad_prop_bga)
			(layers "F.Cu" "F.Mask" "F.Paste")
			(net 1045 "unconnected-(U1B-IO_L23P_T3_A03_D19_14-PadU24)")
			(pinfunction "IO_L23P_T3_A03_D19_14")
			(pintype "bidirectional+no_connect")
			(die_length 10.857)
			(solder_mask_margin 0.02)
		)
		(pad "U25" smd circle
			(at 9.5 1.5)
			(size 0.5 0.5)
			(property pad_prop_bga)
			(layers "F.Cu" "F.Mask" "F.Paste")
			(net 678 "/DRAM + SRAM/SRAM.A11")
			(pinfunction "IO_L14N_T2_SRCC_14")
			(pintype "bidirectional")
			(die_length 11.788)
			(solder_mask_margin 0.02)
		)
		(pad "U26" smd circle
			(at 10.5 1.5)
			(size 0.5 0.5)
			(property pad_prop_bga)
			(layers "F.Cu" "F.Mask" "F.Paste")
			(net 1 "GND")
			(pinfunction "GND")
			(pintype "passive")
			(solder_mask_margin 0.02)
		)
		(pad "U27" smd circle
			(at 11.5 1.5)
			(size 0.5 0.5)
			(property pad_prop_bga)
			(layers "F.Cu" "F.Mask" "F.Paste")
			(net 679 "/DRAM + SRAM/SRAM.A10")
			(pinfunction "IO_L13P_T2_MRCC_14")
			(pintype "bidirectional")
			(die_length 13.108)
			(solder_mask_margin 0.02)
		)
		(pad "U28" smd circle
			(at 12.5 1.5)
			(size 0.5 0.5)
			(property pad_prop_bga)
			(layers "F.Cu" "F.Mask" "F.Paste")
			(net 680 "/DRAM + SRAM/SRAM.A0")
			(pinfunction "IO_L13N_T2_MRCC_14")
			(pintype "bidirectional")
			(die_length 13.478)
			(solder_mask_margin 0.02)
		)
		(pad "U29" smd circle
			(at 13.5 1.5)
			(size 0.5 0.5)
			(property pad_prop_bga)
			(layers "F.Cu" "F.Mask" "F.Paste")
			(net 1384 "/SUP_MCU.SPARE2")
			(pinfunction "IO_L15P_T2_DQS_RDWR_B_14")
			(pintype "bidirectional")
			(die_length 14.917)
			(solder_mask_margin 0.02)
		)
		(pad "U30" smd circle
			(at 14.5 1.5)
			(size 0.5 0.5)
			(property pad_prop_bga)
			(layers "F.Cu" "F.Mask" "F.Paste")
			(net 1046 "unconnected-(U1B-IO_L15N_T2_DQS_DOUT_CSO_B_14-PadU30)")
			(pinfunction "IO_L15N_T2_DQS_DOUT_CSO_B_14")
			(pintype "bidirectional+no_connect")
			(die_length 15.496)
			(solder_mask_margin 0.02)
		)
		(pad "V1" smd circle
			(at -14.5 2.5)
			(size 0.5 0.5)
			(property pad_prop_bga)
			(layers "F.Cu" "F.Mask" "F.Paste")
			(net 115 "/FMC+ HSPC/GTX115.TX1_N")
			(pinfunction "MGTXTXN1_115")
			(pintype "bidirectional")
			(die_length 14.451)
			(solder_mask_margin 0.02)
		)
		(pad "V2" smd circle
			(at -13.5 2.5)
			(size 0.5 0.5)
			(property pad_prop_bga)
			(layers "F.Cu" "F.Mask" "F.Paste")
			(net 107 "/FMC+ HSPC/GTX115.TX1_P")
			(pinfunction "MGTXTXP1_115")
			(pintype "bidirectional")
			(die_length 14.516)
			(solder_mask_margin 0.02)
		)
		(pad "V3" smd circle
			(at -12.5 2.5)
			(size 0.5 0.5)
			(property pad_prop_bga)
			(layers "F.Cu" "F.Mask" "F.Paste")
			(net 8 "+1V2_MGTAVTT")
			(pinfunction "MGTAVTT")
			(pintype "passive")
			(solder_mask_margin 0.02)
		)
		(pad "V4" smd circle
			(at -11.5 2.5)
			(size 0.5 0.5)
			(property pad_prop_bga)
			(layers "F.Cu" "F.Mask" "F.Paste")
			(net 1 "GND")
			(pinfunction "GND")
			(pintype "passive")
			(solder_mask_margin 0.02)
		)
		(pad "V5" smd circle
			(at -10.5 2.5)
			(size 0.5 0.5)
			(property pad_prop_bga)
			(layers "F.Cu" "F.Mask" "F.Paste")
			(net 473 "/FMC+ HSPC/GTX115.RX3_N")
			(pinfunction "MGTXRXN3_115")
			(pintype "bidirectional")
			(die_length 13.463)
			(solder_mask_margin 0.02)
		)
		(pad "V6" smd circle
			(at -9.5 2.5)
			(size 0.5 0.5)
			(property pad_prop_bga)
			(layers "F.Cu" "F.Mask" "F.Paste")
			(net 479 "/FMC+ HSPC/GTX115.RX3_P")
			(pinfunction "MGTXRXP3_115")
			(pintype "bidirectional")
			(die_length 13.634)
			(solder_mask_margin 0.02)
		)
		(pad "V7" smd circle
			(at -8.5 2.5)
			(size 0.5 0.5)
			(property pad_prop_bga)
			(layers "F.Cu" "F.Mask" "F.Paste")
			(net 26 "+1V8")
			(pinfunction "MGTVCCAUX")
			(pintype "passive")
			(solder_mask_margin 0.02)
		)
		(pad "V8" smd circle
			(at -7.5 2.5)
			(size 0.5 0.5)
			(property pad_prop_bga)
			(layers "F.Cu" "F.Mask" "F.Paste")
			(net 1 "GND")
			(pinfunction "GND")
			(pintype "passive")
			(solder_mask_margin 0.02)
		)
		(pad "V9" smd circle
			(at -6.5 2.5)
			(size 0.5 0.5)
			(property pad_prop_bga)
			(layers "F.Cu" "F.Mask" "F.Paste")
			(net 1 "GND")
			(pinfunction "GND")
			(pintype "passive")
			(solder_mask_margin 0.02)
		)
		(pad "V10" smd circle
			(at -5.5 2.5)
			(size 0.5 0.5)
			(property pad_prop_bga)
			(layers "F.Cu" "F.Mask" "F.Paste")
			(net 1 "GND")
			(pinfunction "GND")
			(pintype "passive")
			(solder_mask_margin 0.02)
		)
		(pad "V11" smd circle
			(at -4.5 2.5)
			(size 0.5 0.5)
			(property pad_prop_bga)
			(layers "F.Cu" "F.Mask" "F.Paste")
			(net 26 "+1V8")
			(pinfunction "VCCAUX_IO_G0")
			(pintype "bidirectional")
			(solder_mask_margin 0.02)
		)
		(pad "V12" smd circle
			(at -3.5 2.5)
			(size 0.5 0.5)
			(property pad_prop_bga)
			(layers "F.Cu" "F.Mask" "F.Paste")
			(net 1 "GND")
			(pinfunction "GND")
			(pintype "passive")
			(solder_mask_margin 0.02)
		)
		(pad "V13" smd circle
			(at -2.5 2.5)
			(size 0.5 0.5)
			(property pad_prop_bga)
			(layers "F.Cu" "F.Mask" "F.Paste")
			(net 26 "+1V8")
			(pinfunction "VCCAUX")
			(pintype "passive")
			(solder_mask_margin 0.02)
		)
		(pad "V14" smd circle
			(at -1.5 2.5)
			(size 0.5 0.5)
			(property pad_prop_bga)
			(layers "F.Cu" "F.Mask" "F.Paste")
			(net 1 "GND")
			(pinfunction "GND")
			(pintype "passive")
			(solder_mask_margin 0.02)
		)
		(pad "V15" smd circle
			(at -0.5 2.5)
			(size 0.5 0.5)
			(property pad_prop_bga)
			(layers "F.Cu" "F.Mask" "F.Paste")
			(net 26 "+1V8")
			(pinfunction "VCCAUX")
			(pintype "passive")
			(solder_mask_margin 0.02)
		)
		(pad "V16" smd circle
			(at 0.5 2.5)
			(size 0.5 0.5)
			(property pad_prop_bga)
			(layers "F.Cu" "F.Mask" "F.Paste")
			(net 1 "GND")
			(pinfunction "GND")
			(pintype "passive")
			(solder_mask_margin 0.02)
		)
		(pad "V17" smd circle
			(at 1.5 2.5)
			(size 0.5 0.5)
			(property pad_prop_bga)
			(layers "F.Cu" "F.Mask" "F.Paste")
			(net 650 "+1V0")
			(pinfunction "VCCINT")
			(pintype "passive")
			(solder_mask_margin 0.02)
		)
		(pad "V18" smd circle
			(at 2.5 2.5)
			(size 0.5 0.5)
			(property pad_prop_bga)
			(layers "F.Cu" "F.Mask" "F.Paste")
			(net 1 "GND")
			(pinfunction "GND")
			(pintype "passive")
			(solder_mask_margin 0.02)
		)
		(pad "V19" smd circle
			(at 3.5 2.5)
			(size 0.5 0.5)
			(property pad_prop_bga)
			(layers "F.Cu" "F.Mask" "F.Paste")
			(net 681 "/DRAM + SRAM/SRAM.A12")
			(pinfunction "IO_L19P_T3_A10_D26_14")
			(pintype "bidirectional")
			(die_length 8.087)
			(solder_mask_margin 0.02)
		)
		(pad "V20" smd circle
			(at 4.5 2.5)
			(size 0.5 0.5)
			(property pad_prop_bga)
			(layers "F.Cu" "F.Mask" "F.Paste")
			(net 682 "/DRAM + SRAM/SRAM.A4")
			(pinfunction "IO_L19N_T3_A09_D25_VREF_14")
			(pintype "bidirectional")
			(die_length 8.502)
			(solder_mask_margin 0.02)
		)
		(pad "V21" smd circle
			(at 5.5 2.5)
			(size 0.5 0.5)
			(property pad_prop_bga)
			(layers "F.Cu" "F.Mask" "F.Paste")
			(net 683 "/DRAM + SRAM/SRAM.DQ0")
			(pinfunction "IO_L22P_T3_A05_D21_14")
			(pintype "bidirectional")
			(die_length 8.935)
			(solder_mask_margin 0.02)
		)
		(pad "V22" smd circle
			(at 6.5 2.5)
			(size 0.5 0.5)
			(property pad_prop_bga)
			(layers "F.Cu" "F.Mask" "F.Paste")
			(net 1048 "unconnected-(U1B-IO_L22N_T3_A04_D20_14-PadV22)")
			(pinfunction "IO_L22N_T3_A04_D20_14")
			(pintype "bidirectional+no_connect")
			(die_length 8.194)
			(solder_mask_margin 0.02)
		)
		(pad "V23" smd circle
			(at 7.5 2.5)
			(size 0.5 0.5)
			(property pad_prop_bga)
			(layers "F.Cu" "F.Mask" "F.Paste")
			(net 1 "GND")
			(pinfunction "GND")
			(pintype "passive")
			(solder_mask_margin 0.02)
		)
		(pad "V24" smd circle
			(at 8.5 2.5)
			(size 0.5 0.5)
			(property pad_prop_bga)
			(layers "F.Cu" "F.Mask" "F.Paste")
			(net 684 "/DRAM + SRAM/SRAM.A7")
			(pinfunction "IO_L23N_T3_A02_D18_14")
			(pintype "bidirectional")
			(die_length 9.102)
			(solder_mask_margin 0.02)
		)
		(pad "V25" smd circle
			(at 9.5 2.5)
			(size 0.5 0.5)
			(property pad_prop_bga)
			(layers "F.Cu" "F.Mask" "F.Paste")
			(net 685 "/DRAM + SRAM/SRAM.A18")
			(pinfunction "IO_L18P_T2_A12_D28_14")
			(pintype "bidirectional")
			(die_length 11.952)
			(solder_mask_margin 0.02)
		)
		(pad "V26" smd circle
			(at 10.5 2.5)
			(size 0.5 0.5)
			(property pad_prop_bga)
			(layers "F.Cu" "F.Mask" "F.Paste")
			(net 1383 "/SUP_MCU.SPARE1")
			(pinfunction "IO_L16P_T2_CSI_B_14")
			(pintype "bidirectional")
			(die_length 12.076)
			(solder_mask_margin 0.02)
		)
		(pad "V27" smd circle
			(at 11.5 2.5)
			(size 0.5 0.5)
			(property pad_prop_bga)
			(layers "F.Cu" "F.Mask" "F.Paste")
			(net 556 "/DRAM + SRAM/SRAM.~{CE}")
			(pinfunction "IO_L16N_T2_A15_D31_14")
			(pintype "bidirectional")
			(die_length 12.112)
			(solder_mask_margin 0.02)
		)
		(pad "V28" smd circle
			(at 12.5 2.5)
			(size 0.5 0.5)
			(property pad_prop_bga)
			(layers "F.Cu" "F.Mask" "F.Paste")
			(net 24 "+3V3")
			(pinfunction "VCCO_14")
			(pintype "passive")
			(solder_mask_margin 0.02)
		)
		(pad "V29" smd circle
			(at 13.5 2.5)
			(size 0.5 0.5)
			(property pad_prop_bga)
			(layers "F.Cu" "F.Mask" "F.Paste")
			(net 686 "/DRAM + SRAM/SRAM.A1")
			(pinfunction "IO_L17P_T2_A14_D30_14")
			(pintype "bidirectional")
			(die_length 14.653)
			(solder_mask_margin 0.02)
		)
		(pad "V30" smd circle
			(at 14.5 2.5)
			(size 0.5 0.5)
			(property pad_prop_bga)
			(layers "F.Cu" "F.Mask" "F.Paste")
			(net 687 "/DRAM + SRAM/SRAM.DQ1")
			(pinfunction "IO_L17N_T2_A13_D29_14")
			(pintype "bidirectional")
			(die_length 15.213)
			(solder_mask_margin 0.02)
		)
		(pad "W1" smd circle
			(at -14.5 3.5)
			(size 0.5 0.5)
			(property pad_prop_bga)
			(layers "F.Cu" "F.Mask" "F.Paste")
			(net 1 "GND")
			(pinfunction "GND")
			(pintype "passive")
			(solder_mask_margin 0.02)
		)
		(pad "W2" smd circle
			(at -13.5 3.5)
			(size 0.5 0.5)
			(property pad_prop_bga)
			(layers "F.Cu" "F.Mask" "F.Paste")
			(net 1 "GND")
			(pinfunction "GND")
			(pintype "passive")
			(solder_mask_margin 0.02)
		)
		(pad "W3" smd circle
			(at -12.5 3.5)
			(size 0.5 0.5)
			(property pad_prop_bga)
			(layers "F.Cu" "F.Mask" "F.Paste")
			(net 454 "/FMC+ HSPC/GTX115.RX2_N")
			(pinfunction "MGTXRXN2_115")
			(pintype "bidirectional")
			(die_length 15.13)
			(solder_mask_margin 0.02)
		)
		(pad "W4" smd circle
			(at -11.5 3.5)
			(size 0.5 0.5)
			(property pad_prop_bga)
			(layers "F.Cu" "F.Mask" "F.Paste")
			(net 459 "/FMC+ HSPC/GTX115.RX2_P")
			(pinfunction "MGTXRXP2_115")
			(pintype "bidirectional")
			(die_length 15.15)
			(solder_mask_margin 0.02)
		)
		(pad "W5" smd circle
			(at -10.5 3.5)
			(size 0.5 0.5)
			(property pad_prop_bga)
			(layers "F.Cu" "F.Mask" "F.Paste")
			(net 8 "+1V2_MGTAVTT")
			(pinfunction "MGTAVTT")
			(pintype "passive")
			(solder_mask_margin 0.02)
		)
		(pad "W6" smd circle
			(at -9.5 3.5)
			(size 0.5 0.5)
			(property pad_prop_bga)
			(layers "F.Cu" "F.Mask" "F.Paste")
			(net 1 "GND")
			(pinfunction "GND")
			(pintype "passive")
			(solder_mask_margin 0.02)
		)
		(pad "W7" smd circle
			(at -8.5 3.5)
			(size 0.5 0.5)
			(property pad_prop_bga)
			(layers "F.Cu" "F.Mask" "F.Paste")
			(net 8 "+1V2_MGTAVTT")
			(pinfunction "MGTAVTTRCAL_115")
			(pintype "bidirectional")
			(die_length 10.818)
			(solder_mask_margin 0.02)
		)
		(pad "W8" smd circle
			(at -7.5 3.5)
			(size 0.5 0.5)
			(property pad_prop_bga)
			(layers "F.Cu" "F.Mask" "F.Paste")
			(net 494 "/FPGA supply/MGTRREF")
			(pinfunction "MGTRREF_115")
			(pintype "bidirectional")
			(die_length 9.623)
			(solder_mask_margin 0.02)
		)
		(pad "W9" smd circle
			(at -6.5 3.5)
			(size 0.5 0.5)
			(property pad_prop_bga)
			(layers "F.Cu" "F.Mask" "F.Paste")
			(net 1 "GND")
			(pinfunction "GND")
			(pintype "passive")
			(solder_mask_margin 0.02)
		)
		(pad "W10" smd circle
			(at -5.5 3.5)
			(size 0.5 0.5)
			(property pad_prop_bga)
			(layers "F.Cu" "F.Mask" "F.Paste")
			(net 26 "+1V8")
			(pinfunction "VCCAUX_IO_G0")
			(pintype "passive")
			(solder_mask_margin 0.02)
		)
		(pad "W11" smd circle
			(at -4.5 3.5)
			(size 0.5 0.5)
			(property pad_prop_bga)
			(layers "F.Cu" "F.Mask" "F.Paste")
			(net 1 "GND")
			(pinfunction "GND")
			(pintype "passive")
			(solder_mask_margin 0.02)
		)
		(pad "W12" smd circle
			(at -3.5 3.5)
			(size 0.5 0.5)
			(property pad_prop_bga)
			(layers "F.Cu" "F.Mask" "F.Paste")
			(net 26 "+1V8")
			(pinfunction "VCCAUX_IO_G0")
			(pintype "passive")
			(solder_mask_margin 0.02)
		)
		(pad "W13" smd circle
			(at -2.5 3.5)
			(size 0.5 0.5)
			(property pad_prop_bga)
			(layers "F.Cu" "F.Mask" "F.Paste")
			(net 1 "GND")
			(pinfunction "GND")
			(pintype "passive")
			(solder_mask_margin 0.02)
		)
		(pad "W14" smd circle
			(at -1.5 3.5)
			(size 0.5 0.5)
			(property pad_prop_bga)
			(layers "F.Cu" "F.Mask" "F.Paste")
			(net 26 "+1V8")
			(pinfunction "VCCAUX")
			(pintype "passive")
			(solder_mask_margin 0.02)
		)
		(pad "W15" smd circle
			(at -0.5 3.5)
			(size 0.5 0.5)
			(property pad_prop_bga)
			(layers "F.Cu" "F.Mask" "F.Paste")
			(net 1 "GND")
			(pinfunction "GND")
			(pintype "passive")
			(solder_mask_margin 0.02)
		)
		(pad "W16" smd circle
			(at 0.5 3.5)
			(size 0.5 0.5)
			(property pad_prop_bga)
			(layers "F.Cu" "F.Mask" "F.Paste")
			(net 650 "+1V0")
			(pinfunction "VCCBRAM")
			(pintype "passive")
			(solder_mask_margin 0.02)
		)
		(pad "W17" smd circle
			(at 1.5 3.5)
			(size 0.5 0.5)
			(property pad_prop_bga)
			(layers "F.Cu" "F.Mask" "F.Paste")
			(net 1 "GND")
			(pinfunction "GND")
			(pintype "passive")
			(solder_mask_margin 0.02)
		)
		(pad "W18" smd circle
			(at 2.5 3.5)
			(size 0.5 0.5)
			(property pad_prop_bga)
			(layers "F.Cu" "F.Mask" "F.Paste")
			(net 650 "+1V0")
			(pinfunction "VCCINT")
			(pintype "passive")
			(solder_mask_margin 0.02)
		)
		(pad "W19" smd circle
			(at 3.5 3.5)
			(size 0.5 0.5)
			(property pad_prop_bga)
			(layers "F.Cu" "F.Mask" "F.Paste")
			(net 1049 "unconnected-(U1B-IO_25_14-PadW19)")
			(pinfunction "IO_25_14")
			(pintype "bidirectional+no_connect")
			(die_length 6.678)
			(solder_mask_margin 0.02)
		)
		(pad "W20" smd circle
			(at 4.5 3.5)
			(size 0.5 0.5)
			(property pad_prop_bga)
			(layers "F.Cu" "F.Mask" "F.Paste")
			(net 1 "GND")
			(pinfunction "GND")
			(pintype "passive")
			(solder_mask_margin 0.02)
		)
		(pad "W21" smd circle
			(at 5.5 3.5)
			(size 0.5 0.5)
			(property pad_prop_bga)
			(layers "F.Cu" "F.Mask" "F.Paste")
			(net 688 "/DRAM + SRAM/SRAM.DQ2")
			(pinfunction "IO_L24P_T3_A01_D17_14")
			(pintype "bidirectional")
			(die_length 7.855)
			(solder_mask_margin 0.02)
		)
		(pad "W22" smd circle
			(at 6.5 3.5)
			(size 0.5 0.5)
			(property pad_prop_bga)
			(layers "F.Cu" "F.Mask" "F.Paste")
			(net 563 "/DRAM + SRAM/SRAM.~{WE}")
			(pinfunction "IO_L24N_T3_A00_D16_14")
			(pintype "bidirectional")
			(die_length 8.287)
			(solder_mask_margin 0.02)
		)
		(pad "W23" smd circle
			(at 7.5 3.5)
			(size 0.5 0.5)
			(property pad_prop_bga)
			(layers "F.Cu" "F.Mask" "F.Paste")
			(net 689 "/DRAM + SRAM/SRAM.A16")
			(pinfunction "IO_L20P_T3_A08_D24_14")
			(pintype "bidirectional")
			(die_length 8.317)
			(solder_mask_margin 0.02)
		)
		(pad "W24" smd circle
			(at 8.5 3.5)
			(size 0.5 0.5)
			(property pad_prop_bga)
			(layers "F.Cu" "F.Mask" "F.Paste")
			(net 690 "/DRAM + SRAM/SRAM.A17")
			(pinfunction "IO_L20N_T3_A07_D23_14")
			(pintype "bidirectional")
			(die_length 8.141)
			(solder_mask_margin 0.02)
		)
		(pad "W25" smd circle
			(at 9.5 3.5)
			(size 0.5 0.5)
			(property pad_prop_bga)
			(layers "F.Cu" "F.Mask" "F.Paste")
			(net 24 "+3V3")
			(pinfunction "VCCO_14")
			(pintype "passive")
			(solder_mask_margin 0.02)
		)
		(pad "W26" smd circle
			(at 10.5 3.5)
			(size 0.5 0.5)
			(property pad_prop_bga)
			(layers "F.Cu" "F.Mask" "F.Paste")
			(net 691 "/DRAM + SRAM/SRAM.A19")
			(pinfunction "IO_L18N_T2_A11_D27_14")
			(pintype "bidirectional")
			(die_length 11.963)
			(solder_mask_margin 0.02)
		)
		(pad "W27" smd circle
			(at 11.5 3.5)
			(size 0.5 0.5)
			(property pad_prop_bga)
			(layers "F.Cu" "F.Mask" "F.Paste")
			(net 457 "/FPGA Bank 12 & 13/PMOD_A.IO2")
			(pinfunction "IO_L2P_T0_13")
			(pintype "bidirectional")
			(die_length 11.615)
			(solder_mask_margin 0.02)
		)
		(pad "W28" smd circle
			(at 12.5 3.5)
			(size 0.5 0.5)
			(property pad_prop_bga)
			(layers "F.Cu" "F.Mask" "F.Paste")
			(net 472 "/FPGA Bank 12 & 13/PMOD_B.IO4")
			(pinfunction "IO_L2N_T0_13")
			(pintype "bidirectional")
			(die_length 12.971)
			(solder_mask_margin 0.02)
		)
		(pad "W29" smd circle
			(at 13.5 3.5)
			(size 0.5 0.5)
			(property pad_prop_bga)
			(layers "F.Cu" "F.Mask" "F.Paste")
			(net 434 "/FPGA Bank 12 & 13/PMOD_A.IO8")
			(pinfunction "IO_L4P_T0_13")
			(pintype "bidirectional")
			(die_length 14.012)
			(solder_mask_margin 0.02)
		)
		(pad "W30" smd circle
			(at 14.5 3.5)
			(size 0.5 0.5)
			(property pad_prop_bga)
			(layers "F.Cu" "F.Mask" "F.Paste")
			(net 1 "GND")
			(pinfunction "GND")
			(pintype "passive")
			(solder_mask_margin 0.02)
		)
		(pad "Y1" smd circle
			(at -14.5 4.5)
			(size 0.5 0.5)
			(property pad_prop_bga)
			(layers "F.Cu" "F.Mask" "F.Paste")
			(net 101 "/FMC+ HSPC/GTX115.TX2_N")
			(pinfunction "MGTXTXN0_115")
			(pintype "bidirectional")
			(die_length 15.513)
			(solder_mask_margin 0.02)
		)
		(pad "Y2" smd circle
			(at -13.5 4.5)
			(size 0.5 0.5)
			(property pad_prop_bga)
			(layers "F.Cu" "F.Mask" "F.Paste")
			(net 97 "/FMC+ HSPC/GTX115.TX2_P")
			(pinfunction "MGTXTXP0_115")
			(pintype "bidirectional")
			(die_length 15.611)
			(solder_mask_margin 0.02)
		)
		(pad "Y3" smd circle
			(at -12.5 4.5)
			(size 0.5 0.5)
			(property pad_prop_bga)
			(layers "F.Cu" "F.Mask" "F.Paste")
			(net 1 "GND")
			(pinfunction "GND")
			(pintype "passive")
			(solder_mask_margin 0.02)
		)
		(pad "Y4" smd circle
			(at -11.5 4.5)
			(size 0.5 0.5)
			(property pad_prop_bga)
			(layers "F.Cu" "F.Mask" "F.Paste")
			(net 1 "GND")
			(pinfunction "GND")
			(pintype "passive")
			(solder_mask_margin 0.02)
		)
		(pad "Y5" smd circle
			(at -10.5 4.5)
			(size 0.5 0.5)
			(property pad_prop_bga)
			(layers "F.Cu" "F.Mask" "F.Paste")
			(net 463 "/FMC+ HSPC/GTX115.RX1_N")
			(pinfunction "MGTXRXN1_115")
			(pintype "bidirectional")
			(die_length 14.381)
			(solder_mask_margin 0.02)
		)
		(pad "Y6" smd circle
			(at -9.5 4.5)
			(size 0.5 0.5)
			(property pad_prop_bga)
			(layers "F.Cu" "F.Mask" "F.Paste")
			(net 468 "/FMC+ HSPC/GTX115.RX1_P")
			(pinfunction "MGTXRXP1_115")
			(pintype "bidirectional")
			(die_length 14.366)
			(solder_mask_margin 0.02)
		)
		(pad "Y7" smd circle
			(at -8.5 4.5)
			(size 0.5 0.5)
			(property pad_prop_bga)
			(layers "F.Cu" "F.Mask" "F.Paste")
			(net 1 "GND")
			(pinfunction "GND")
			(pintype "passive")
			(solder_mask_margin 0.02)
		)
		(pad "Y8" smd circle
			(at -7.5 4.5)
			(size 0.5 0.5)
			(property pad_prop_bga)
			(layers "F.Cu" "F.Mask" "F.Paste")
			(net 1 "GND")
			(pinfunction "GND")
			(pintype "passive")
			(solder_mask_margin 0.02)
		)
		(pad "Y9" smd circle
			(at -6.5 4.5)
			(size 0.5 0.5)
			(property pad_prop_bga)
			(layers "F.Cu" "F.Mask" "F.Paste")
			(net 1 "GND")
			(pinfunction "GND")
			(pintype "passive")
			(solder_mask_margin 0.02)
		)
		(pad "Y10" smd circle
			(at -5.5 4.5)
			(size 0.5 0.5)
			(property pad_prop_bga)
			(layers "F.Cu" "F.Mask" "F.Paste")
			(net 1233 "/USER_IO.BUTTON2")
			(pinfunction "IO_L4N_T0_33")
			(pintype "bidirectional")
			(die_length 9.48)
			(solder_mask_margin 0.02)
		)
		(pad "Y11" smd circle
			(at -4.5 4.5)
			(size 0.5 0.5)
			(property pad_prop_bga)
			(layers "F.Cu" "F.Mask" "F.Paste")
			(net 1232 "/USER_IO.BUTTON3")
			(pinfunction "IO_L4P_T0_33")
			(pintype "bidirectional")
			(die_length 7.911)
			(solder_mask_margin 0.02)
		)
		(pad "Y12" smd circle
			(at -3.5 4.5)
			(size 0.5 0.5)
			(property pad_prop_bga)
			(layers "F.Cu" "F.Mask" "F.Paste")
			(net 26 "+1V8")
			(pinfunction "VCCO_33")
			(pintype "passive")
			(solder_mask_margin 0.02)
		)
		(pad "Y13" smd circle
			(at -2.5 4.5)
			(size 0.5 0.5)
			(property pad_prop_bga)
			(layers "F.Cu" "F.Mask" "F.Paste")
			(net 1311 "/USER_IO.DIP_SW0")
			(pinfunction "IO_0_VRN_33")
			(pintype "bidirectional")
			(die_length 7.67)
			(solder_mask_margin 0.02)
		)
		(pad "Y14" smd circle
			(at -1.5 4.5)
			(size 0.5 0.5)
			(property pad_prop_bga)
			(layers "F.Cu" "F.Mask" "F.Paste")
			(net 1397 "/FPGA Bank 12 & 13/USB_USER.VM")
			(pinfunction "IO_0_VRN_32")
			(pintype "bidirectional")
			(die_length 12.537)
			(solder_mask_margin 0.02)
		)
		(pad "Y15" smd circle
			(at -0.5 4.5)
			(size 0.5 0.5)
			(property pad_prop_bga)
			(layers "F.Cu" "F.Mask" "F.Paste")
			(net 1398 "unconnected-(U1D-IO_L24N_T3_32-PadY15)")
			(pinfunction "IO_L24N_T3_32")
			(pintype "bidirectional+no_connect")
			(die_length 15.861)
			(solder_mask_margin 0.02)
		)
		(pad "Y16" smd circle
			(at 0.5 4.5)
			(size 0.5 0.5)
			(property pad_prop_bga)
			(layers "F.Cu" "F.Mask" "F.Paste")
			(net 1399 "unconnected-(U1D-IO_L24P_T3_32-PadY16)")
			(pinfunction "IO_L24P_T3_32")
			(pintype "bidirectional+no_connect")
			(die_length 14.497)
			(solder_mask_margin 0.02)
		)
		(pad "Y17" smd circle
			(at 1.5 4.5)
			(size 0.5 0.5)
			(property pad_prop_bga)
			(layers "F.Cu" "F.Mask" "F.Paste")
			(net 1 "GND")
			(pinfunction "GND")
			(pintype "passive")
			(solder_mask_margin 0.02)
		)
		(pad "Y18" smd circle
			(at 2.5 4.5)
			(size 0.5 0.5)
			(property pad_prop_bga)
			(layers "F.Cu" "F.Mask" "F.Paste")
			(net 1400 "unconnected-(U1D-IO_L15N_T2_DQS_32-PadY18)")
			(pinfunction "IO_L15N_T2_DQS_32")
			(pintype "bidirectional+no_connect")
			(die_length 23.661)
			(solder_mask_margin 0.02)
		)
		(pad "Y19" smd circle
			(at 3.5 4.5)
			(size 0.5 0.5)
			(property pad_prop_bga)
			(layers "F.Cu" "F.Mask" "F.Paste")
			(net 521 "/FPGA Bank 18 & 32/ETH_RMII.RXER")
			(pinfunction "IO_L15P_T2_DQS_32")
			(pintype "bidirectional")
			(die_length 23.666)
			(solder_mask_margin 0.02)
		)
		(pad "Y20" smd circle
			(at 4.5 4.5)
			(size 0.5 0.5)
			(property pad_prop_bga)
			(layers "F.Cu" "F.Mask" "F.Paste")
			(net 1355 "/SUP_MCU.A16")
			(pinfunction "IO_0_12")
			(pintype "bidirectional")
			(die_length 8.993)
			(solder_mask_margin 0.02)
		)
		(pad "Y21" smd circle
			(at 5.5 4.5)
			(size 0.5 0.5)
			(property pad_prop_bga)
			(layers "F.Cu" "F.Mask" "F.Paste")
			(net 1352 "/SUP_MCU.A13")
			(pinfunction "IO_L2P_T0_12")
			(pintype "bidirectional")
			(die_length 9.039)
			(solder_mask_margin 0.02)
		)
		(pad "Y22" smd circle
			(at 6.5 4.5)
			(size 0.5 0.5)
			(property pad_prop_bga)
			(layers "F.Cu" "F.Mask" "F.Paste")
			(net 24 "+3V3")
			(pinfunction "VCCO_12")
			(pintype "passive")
			(solder_mask_margin 0.02)
		)
		(pad "Y23" smd circle
			(at 7.5 4.5)
			(size 0.5 0.5)
			(property pad_prop_bga)
			(layers "F.Cu" "F.Mask" "F.Paste")
			(net 1366 "/SUP_MCU.A14")
			(pinfunction "IO_L1P_T0_12")
			(pintype "bidirectional")
			(die_length 10.411)
			(solder_mask_margin 0.02)
		)
		(pad "Y24" smd circle
			(at 8.5 4.5)
			(size 0.5 0.5)
			(property pad_prop_bga)
			(layers "F.Cu" "F.Mask" "F.Paste")
			(net 1364 "/SUP_MCU.A15")
			(pinfunction "IO_L1N_T0_12")
			(pintype "bidirectional")
			(die_length 11.014)
			(solder_mask_margin 0.02)
		)
		(pad "Y25" smd circle
			(at 9.5 4.5)
			(size 0.5 0.5)
			(property pad_prop_bga)
			(layers "F.Cu" "F.Mask" "F.Paste")
			(net 1401 "unconnected-(U1A-IO_0_13-PadY25)")
			(pinfunction "IO_0_13")
			(pintype "bidirectional+no_connect")
			(die_length 9.219)
			(solder_mask_margin 0.02)
		)
		(pad "Y26" smd circle
			(at 10.5 4.5)
			(size 0.5 0.5)
			(property pad_prop_bga)
			(layers "F.Cu" "F.Mask" "F.Paste")
			(net 1304 "/USER_IO.LED_GREEN5")
			(pinfunction "IO_L1P_T0_13")
			(pintype "bidirectional")
			(die_length 11.658)
			(solder_mask_margin 0.02)
		)
		(pad "Y27" smd circle
			(at 11.5 4.5)
			(size 0.5 0.5)
			(property pad_prop_bga)
			(layers "F.Cu" "F.Mask" "F.Paste")
			(net 1 "GND")
			(pinfunction "GND")
			(pintype "passive")
			(solder_mask_margin 0.02)
		)
		(pad "Y28" smd circle
			(at 12.5 4.5)
			(size 0.5 0.5)
			(property pad_prop_bga)
			(layers "F.Cu" "F.Mask" "F.Paste")
			(net 1305 "/USER_IO.LED_RED")
			(pinfunction "IO_L3P_T0_DQS_13")
			(pintype "bidirectional")
			(die_length 14.559)
			(solder_mask_margin 0.02)
		)
		(pad "Y29" smd circle
			(at 13.5 4.5)
			(size 0.5 0.5)
			(property pad_prop_bga)
			(layers "F.Cu" "F.Mask" "F.Paste")
			(net 1053 "/DC-DC Converters/PB_CTRL.VDDR_EN")
			(pinfunction "IO_L4N_T0_13")
			(pintype "bidirectional")
			(die_length 14.587)
			(solder_mask_margin 0.02)
		)
		(pad "Y30" smd circle
			(at 14.5 4.5)
			(size 0.5 0.5)
			(property pad_prop_bga)
			(layers "F.Cu" "F.Mask" "F.Paste")
			(net 1299 "/USER_IO.LED_GREEN0")
			(pinfunction "IO_L8P_T1_13")
			(pintype "bidirectional")
			(die_length 18.627)
			(solder_mask_margin 0.02)
		)
	)
	(footprint "antmicro-footprints:R_0402_1005Metric"
		(layer "F.Cu")
		(at 235.915 117.5 180)
		(descr "Resistor SMD 0402")
		(tags "resistor SMD 0402")
		(property "Reference" "R64"
			(at -0.735 -0.35 180)
			(layer "F.SilkS")
			(effects
				(font
					(size 0.7 0.7)
					(thickness 0.15)
				)
				(justify left bottom)
			)
		)
		(property "Value" "R_10k_0402"
			(at 0 1.4 180)
			(layer "F.Fab")
			(effects
				(font
					(size 0.7 0.7)
					(thickness 0.15)
				)
				(justify left bottom)
			)
		)
		(property "Description" "SMD Chip Resistor, 10 kohm, ± 1%, 62.5 mW, 0402 [1005 Metric], Thick Film, General Purpose"
			(at 0 0 180)
			(layer "F.Fab")
			(hide yes)
			(effects
				(font
					(size 1.27 1.27)
					(thickness 0.15)
				)
			)
		)
		(property "Author" "Antmicro"
			(at 471.83 235 0)
			(layer "F.Fab")
			(hide yes)
			(effects
				(font
					(size 1 1)
					(thickness 0.15)
				)
			)
		)
		(property "License" "Apache-2.0"
			(at 471.83 235 0)
			(layer "F.Fab")
			(hide yes)
			(effects
				(font
					(size 1 1)
					(thickness 0.15)
				)
			)
		)
		(property "MPN" "CR0402-FX-1002GLF"
			(at 471.83 235 0)
			(layer "F.Fab")
			(hide yes)
			(effects
				(font
					(size 1 1)
					(thickness 0.15)
				)
			)
		)
		(property "Manufacturer" "Bourns"
			(at 471.83 235 0)
			(layer "F.Fab")
			(hide yes)
			(effects
				(font
					(size 1 1)
					(thickness 0.15)
				)
			)
		)
		(property "Tolerance" "1%"
			(at 471.83 235 0)
			(layer "F.Fab")
			(hide yes)
			(effects
				(font
					(size 1 1)
					(thickness 0.15)
				)
			)
		)
		(property "Val" "10k"
			(at 471.83 235 0)
			(layer "F.Fab")
			(hide yes)
			(effects
				(font
					(size 1 1)
					(thickness 0.15)
				)
			)
		)
		(sheetname "SPI Flash + SD Card")
		(sheetfile "spi-flash.kicad_sch")
		(attr smd)
		(fp_rect
			(start -0.925 -0.47)
			(end 0.925 0.47)
			(stroke
				(width 0.05)
				(type default)
			)
			(fill no)
			(layer "F.CrtYd")
		)
		(fp_rect
			(start -0.5 -0.25)
			(end 0.5 0.25)
			(stroke
				(width 0.15)
				(type solid)
			)
			(fill no)
			(layer "F.Fab")
		)
		(pad "1" smd roundrect
			(at -0.48 0 180)
			(size 0.59 0.64)
			(layers "F.Cu" "F.Mask" "F.Paste")
			(roundrect_rratio 0.25)
			(net 398 "/FPGA Bank 14 & 15/SYSTEM_FLASH.DQ3")
			(pintype "passive")
		)
		(pad "2" smd roundrect
			(at 0.48 0 180)
			(size 0.59 0.64)
			(layers "F.Cu" "F.Mask" "F.Paste")
			(roundrect_rratio 0.25)
			(net 24 "+3V3")
			(pintype "passive")
		)
	)
	(footprint "antmicro-footprints:R_0402_1005Metric"
		(layer "F.Cu")
		(at 264.7 133.7 -90)
		(descr "Resistor SMD 0402")
		(tags "resistor SMD 0402")
		(property "Reference" "R153"
			(at -30.3 29.85 0)
			(layer "F.SilkS")
			(effects
				(font
					(size 0.7 0.7)
					(thickness 0.15)
				)
				(justify left bottom)
			)
		)
		(property "Value" "R_330R_0402"
			(at 0 1.4 270)
			(layer "F.Fab")
			(effects
				(font
					(size 0.7 0.7)
					(thickness 0.15)
				)
				(justify left bottom)
			)
		)
		(property "Description" "SMD Chip Resistor, 330 ohm, ± 1%, 62.5 mW, 0402 [1005 Metric], Thick Film, General Purpose"
			(at 0 0 270)
			(layer "F.Fab")
			(hide yes)
			(effects
				(font
					(size 1.27 1.27)
					(thickness 0.15)
				)
			)
		)
		(property "Author" "Antmicro"
			(at 131 398.4 0)
			(layer "F.Fab")
			(hide yes)
			(effects
				(font
					(size 1 1)
					(thickness 0.15)
				)
			)
		)
		(property "License" "Apache-2.0"
			(at 131 398.4 0)
			(layer "F.Fab")
			(hide yes)
			(effects
				(font
					(size 1 1)
					(thickness 0.15)
				)
			)
		)
		(property "MPN" "CR0402-FX-3300GLF"
			(at 131 398.4 0)
			(layer "F.Fab")
			(hide yes)
			(effects
				(font
					(size 1 1)
					(thickness 0.15)
				)
			)
		)
		(property "Manufacturer" "Bourns"
			(at 131 398.4 0)
			(layer "F.Fab")
			(hide yes)
			(effects
				(font
					(size 1 1)
					(thickness 0.15)
				)
			)
		)
		(property "Tolerance" "1%"
			(at 131 398.4 0)
			(layer "F.Fab")
			(hide yes)
			(effects
				(font
					(size 1 1)
					(thickness 0.15)
				)
			)
		)
		(property "Val" "330R"
			(at 131 398.4 0)
			(layer "F.Fab")
			(hide yes)
			(effects
				(font
					(size 1 1)
					(thickness 0.15)
				)
			)
		)
		(sheetname "USB PHY")
		(sheetfile "usb-phy.kicad_sch")
		(attr smd)
		(fp_rect
			(start -0.925 -0.47)
			(end 0.925 0.47)
			(stroke
				(width 0.05)
				(type default)
			)
			(fill no)
			(layer "F.CrtYd")
		)
		(fp_rect
			(start -0.5 -0.25)
			(end 0.5 0.25)
			(stroke
				(width 0.15)
				(type solid)
			)
			(fill no)
			(layer "F.Fab")
		)
		(pad "1" smd roundrect
			(at -0.48 0 270)
			(size 0.59 0.64)
			(layers "F.Cu" "F.Mask" "F.Paste")
			(roundrect_rratio 0.25)
			(net 793 "Net-(D29-A)")
			(pintype "passive")
		)
		(pad "2" smd roundrect
			(at 0.48 0 270)
			(size 0.59 0.64)
			(layers "F.Cu" "F.Mask" "F.Paste")
			(roundrect_rratio 0.25)
			(net 915 "/USB PHY/LED_RX1")
			(pintype "passive")
		)
	)
	(footprint "antmicro-footprints:R_0402_1005Metric"
		(layer "F.Cu")
		(at 210.81 75.44 -90)
		(descr "Resistor SMD 0402")
		(tags "resistor SMD 0402")
		(property "Reference" "R10"
			(at -0.74 -0.39 270)
			(layer "F.SilkS")
			(effects
				(font
					(size 0.7 0.7)
					(thickness 0.15)
				)
				(justify left bottom)
			)
		)
		(property "Value" "R_330R_0402"
			(at 0 1.4 270)
			(layer "F.Fab")
			(effects
				(font
					(size 0.7 0.7)
					(thickness 0.15)
				)
				(justify left bottom)
			)
		)
		(property "Description" "SMD Chip Resistor, 330 ohm, ± 1%, 62.5 mW, 0402 [1005 Metric], Thick Film, General Purpose"
			(at 0 0 270)
			(layer "F.Fab")
			(hide yes)
			(effects
				(font
					(size 1.27 1.27)
					(thickness 0.15)
				)
			)
		)
		(property "Author" "Antmicro"
			(at 135.37 286.25 0)
			(layer "F.Fab")
			(hide yes)
			(effects
				(font
					(size 1 1)
					(thickness 0.15)
				)
			)
		)
		(property "License" "Apache-2.0"
			(at 135.37 286.25 0)
			(layer "F.Fab")
			(hide yes)
			(effects
				(font
					(size 1 1)
					(thickness 0.15)
				)
			)
		)
		(property "MPN" "CR0402-FX-3300GLF"
			(at 135.37 286.25 0)
			(layer "F.Fab")
			(hide yes)
			(effects
				(font
					(size 1 1)
					(thickness 0.15)
				)
			)
		)
		(property "Manufacturer" "Bourns"
			(at 135.37 286.25 0)
			(layer "F.Fab")
			(hide yes)
			(effects
				(font
					(size 1 1)
					(thickness 0.15)
				)
			)
		)
		(property "Tolerance" "1%"
			(at 135.37 286.25 0)
			(layer "F.Fab")
			(hide yes)
			(effects
				(font
					(size 1 1)
					(thickness 0.15)
				)
			)
		)
		(property "Val" "330R"
			(at 135.37 286.25 0)
			(layer "F.Fab")
			(hide yes)
			(effects
				(font
					(size 1 1)
					(thickness 0.15)
				)
			)
		)
		(sheetname "FPGA Config")
		(sheetfile "fpga-config.kicad_sch")
		(attr smd)
		(fp_rect
			(start -0.925 -0.47)
			(end 0.925 0.47)
			(stroke
				(width 0.05)
				(type default)
			)
			(fill no)
			(layer "F.CrtYd")
		)
		(fp_rect
			(start -0.5 -0.25)
			(end 0.5 0.25)
			(stroke
				(width 0.15)
				(type solid)
			)
			(fill no)
			(layer "F.Fab")
		)
		(pad "1" smd roundrect
			(at -0.48 0 270)
			(size 0.59 0.64)
			(layers "F.Cu" "F.Mask" "F.Paste")
			(roundrect_rratio 0.25)
			(net 754 "Net-(D2-C)")
			(pintype "passive")
		)
		(pad "2" smd roundrect
			(at 0.48 0 270)
			(size 0.59 0.64)
			(layers "F.Cu" "F.Mask" "F.Paste")
			(roundrect_rratio 0.25)
			(net 336 "Net-(Q2-D)")
			(pintype "passive")
		)
	)
	(footprint "antmicro-footprints:PinHeader_2x7_P2mm_SMD_Shrouded_no-locator"
		(layer "F.Cu")
		(at 189.000001 74.000001 180)
		(descr "Pin Header 2x7 SMD Shrouded no-locator")
		(property "Reference" "J1"
			(at 8.800001 -4.399999 180)
			(layer "F.SilkS")
			(effects
				(font
					(size 0.7 0.7)
					(thickness 0.15)
				)
				(justify left bottom)
			)
		)
		(property "Value" "PinHeader_2x7_P2mm_SMD_Shrouded_no-locator"
			(at 0 5.038 180)
			(layer "F.Fab")
			(effects
				(font
					(size 0.7 0.7)
					(thickness 0.15)
				)
				(justify left bottom)
			)
		)
		(property "Author" "Antmicro"
			(at 378.000002 148.000002 0)
			(layer "F.Fab")
			(hide yes)
			(effects
				(font
					(size 1 1)
					(thickness 0.15)
				)
			)
		)
		(property "License" "Apache-2.0"
			(at 378.000002 148.000002 0)
			(layer "F.Fab")
			(hide yes)
			(effects
				(font
					(size 1 1)
					(thickness 0.15)
				)
			)
		)
		(property "MPN" "878321412"
			(at 378.000002 148.000002 0)
			(layer "F.Fab")
			(hide yes)
			(effects
				(font
					(size 1 1)
					(thickness 0.15)
				)
			)
		)
		(property "Manufacturer" "Molex"
			(at 378.000002 148.000002 0)
			(layer "F.Fab")
			(hide yes)
			(effects
				(font
					(size 1 1)
					(thickness 0.15)
				)
			)
		)
		(sheetname "FPGA Config")
		(sheetfile "fpga-config.kicad_sch")
		(attr smd)
		(fp_line
			(start 8.499 3.297)
			(end 8.499 2.797)
			(stroke
				(width 0.15)
				(type solid)
			)
			(layer "F.SilkS")
		)
		(fp_line
			(start 8.499 3.297)
			(end 7.998 3.297)
			(stroke
				(width 0.15)
				(type solid)
			)
			(layer "F.SilkS")
		)
		(fp_line
			(start 8.499 -3.301)
			(end 8.499 -2.801)
			(stroke
				(width 0.15)
				(type solid)
			)
			(layer "F.SilkS")
		)
		(fp_line
			(start 8.499 -3.301)
			(end 7.998 -3.301)
			(stroke
				(width 0.15)
				(type solid)
			)
			(layer "F.SilkS")
		)
		(fp_line
			(start 1.394 2.418)
			(end 1.394 2.918)
			(stroke
				(width 0.15)
				(type solid)
			)
			(layer "F.SilkS")
		)
		(fp_line
			(start 1.394 2.418)
			(end 0.897 2.418)
			(stroke
				(width 0.15)
				(type solid)
			)
			(layer "F.SilkS")
		)
		(fp_line
			(start -1.397 2.41)
			(end -0.9 2.41)
			(stroke
				(width 0.15)
				(type solid)
			)
			(layer "F.SilkS")
		)
		(fp_line
			(start -1.397 2.41)
			(end -1.397 2.91)
			(stroke
				(width 0.15)
				(type solid)
			)
			(layer "F.SilkS")
		)
		(fp_line
			(start -8.5 3.297)
			(end -8 3.297)
			(stroke
				(width 0.15)
				(type solid)
			)
			(layer "F.SilkS")
		)
		(fp_line
			(start -8.5 3.297)
			(end -8.5 2.797)
			(stroke
				(width 0.15)
				(type solid)
			)
			(layer "F.SilkS")
		)
		(fp_line
			(start -8.5 -3.301)
			(end -8 -3.301)
			(stroke
				(width 0.15)
				(type solid)
			)
			(layer "F.SilkS")
		)
		(fp_line
			(start -8.5 -3.301)
			(end -8.5 -2.801)
			(stroke
				(width 0.15)
				(type solid)
			)
			(layer "F.SilkS")
		)
		(fp_circle
			(center -6.8 3.4)
			(end -6.748 3.4)
			(stroke
				(width 0.15)
				(type solid)
			)
			(fill yes)
			(layer "F.SilkS")
		)
		(fp_rect
			(start -8.7 -3.7)
			(end 8.7 3.7)
			(stroke
				(width 0.05)
				(type solid)
			)
			(fill no)
			(layer "F.CrtYd")
		)
		(fp_line
			(start 8.323 3.148)
			(end 8.323 -3.15)
			(stroke
				(width 0.15)
				(type solid)
			)
			(layer "F.Fab")
		)
		(fp_line
			(start 1.394 3.148)
			(end 8.323 3.148)
			(stroke
				(width 0.15)
				(type solid)
			)
			(layer "F.Fab")
		)
		(fp_line
			(start 1.394 2.41)
			(end 1.394 3.14)
			(stroke
				(width 0.15)
				(type solid)
			)
			(layer "F.Fab")
		)
		(fp_line
			(start -1.397 2.41)
			(end 1.394 2.41)
			(stroke
				(width 0.15)
				(type solid)
			)
			(layer "F.Fab")
		)
		(fp_line
			(start -1.397 2.41)
			(end -1.397 3.14)
			(stroke
				(width 0.15)
				(type solid)
			)
			(layer "F.Fab")
		)
		(fp_line
			(start -8.325 3.148)
			(end -1.397 3.148)
			(stroke
				(width 0.15)
				(type solid)
			)
			(layer "F.Fab")
		)
		(fp_line
			(start -8.325 3.148)
			(end -8.325 -3.15)
			(stroke
				(width 0.15)
				(type solid)
			)
			(layer "F.Fab")
		)
		(fp_line
			(start -8.325 -3.15)
			(end 8.323 -3.15)
			(stroke
				(width 0.15)
				(type solid)
			)
			(layer "F.Fab")
		)
		(pad "1" smd rect
			(at -6 2.128 180)
			(size 1 2.75)
			(layers "F.Cu" "F.Mask" "F.Paste")
			(net 1 "GND")
			(pintype "passive")
		)
		(pad "2" smd rect
			(at -6 -2.13 180)
			(size 1 2.75)
			(layers "F.Cu" "F.Mask" "F.Paste")
			(net 24 "+3V3")
			(pintype "passive")
		)
		(pad "3" smd rect
			(at -4 2.128 180)
			(size 1 2.75)
			(layers "F.Cu" "F.Mask" "F.Paste")
			(net 1 "GND")
			(pintype "passive")
		)
		(pad "4" smd rect
			(at -4 -2.13 180)
			(size 1 2.75)
			(layers "F.Cu" "F.Mask" "F.Paste")
			(net 161 "/FPGA Config/JTAG.TMS")
			(pintype "passive")
		)
		(pad "5" smd rect
			(at -2 2.128 180)
			(size 1 2.75)
			(layers "F.Cu" "F.Mask" "F.Paste")
			(net 1 "GND")
			(pintype "passive")
		)
		(pad "6" smd rect
			(at -2 -2.13 180)
			(size 1 2.75)
			(layers "F.Cu" "F.Mask" "F.Paste")
			(net 165 "/FPGA Config/JTAG.TCK")
			(pintype "passive")
		)
		(pad "7" smd rect
			(at 0 2.128 180)
			(size 1 2.75)
			(layers "F.Cu" "F.Mask" "F.Paste")
			(net 1 "GND")
			(pintype "passive")
		)
		(pad "8" smd rect
			(at 0 -2.13 180)
			(size 1 2.75)
			(layers "F.Cu" "F.Mask" "F.Paste")
			(net 190 "/FPGA Config/JTAG.TDO")
			(pintype "passive")
		)
		(pad "9" smd rect
			(at 1.999 2.128 180)
			(size 1 2.75)
			(layers "F.Cu" "F.Mask" "F.Paste")
			(net 1 "GND")
			(pintype "passive")
		)
		(pad "10" smd rect
			(at 1.999 -2.13 180)
			(size 1 2.75)
			(layers "F.Cu" "F.Mask" "F.Paste")
			(net 220 "/FPGA Config/JTAG.TDI")
			(pintype "passive")
		)
		(pad "11" smd rect
			(at 3.999 2.128 180)
			(size 1 2.75)
			(layers "F.Cu" "F.Mask" "F.Paste")
			(net 1 "GND")
			(pintype "passive")
		)
		(pad "12" smd rect
			(at 3.999 -2.13 180)
			(size 1 2.75)
			(layers "F.Cu" "F.Mask" "F.Paste")
			(net 431 "/FPGA Config/JTAG.RST")
			(pintype "passive")
		)
		(pad "13" smd rect
			(at 5.998 2.128 180)
			(size 1 2.75)
			(layers "F.Cu" "F.Mask" "F.Paste")
			(net 1 "GND")
			(pintype "passive")
		)
		(pad "14" smd rect
			(at 5.998 -2.13 180)
			(size 1 2.75)
			(layers "F.Cu" "F.Mask" "F.Paste")
			(net 799 "FTDI_DIS")
			(pintype "passive")
		)
	)
	(footprint "antmicro-footprints:R_0402_1005Metric"
		(layer "F.Cu")
		(at 235.9 114.575)
		(descr "Resistor SMD 0402")
		(tags "resistor SMD 0402")
		(property "Reference" "R97"
			(at 0.8 0.325 0)
			(layer "F.SilkS")
			(effects
				(font
					(size 0.7 0.7)
					(thickness 0.15)
				)
				(justify left bottom)
			)
		)
		(property "Value" "R_100R_0402"
			(at 0 1.4 0)
			(layer "F.Fab")
			(effects
				(font
					(size 0.7 0.7)
					(thickness 0.15)
				)
				(justify left bottom)
			)
		)
		(property "Description" "SMD Chip Resistor, 100 ohm, ± 1%, 62.5 mW, 0402 [1005 Metric], Thick Film, General Purpose"
			(at 0 0 0)
			(layer "F.Fab")
			(hide yes)
			(effects
				(font
					(size 1.27 1.27)
					(thickness 0.15)
				)
			)
		)
		(property "Author" "Antmicro"
			(at 0 0 0)
			(layer "F.Fab")
			(hide yes)
			(effects
				(font
					(size 1 1)
					(thickness 0.15)
				)
			)
		)
		(property "DNP" "DNP"
			(at 0 0 0)
			(layer "F.Fab")
			(hide yes)
			(effects
				(font
					(size 1 1)
					(thickness 0.15)
				)
			)
		)
		(property "License" "Apache-2.0"
			(at 0 0 0)
			(layer "F.Fab")
			(hide yes)
			(effects
				(font
					(size 1 1)
					(thickness 0.15)
				)
			)
		)
		(property "MPN" "CR0402-FX-1000GLF"
			(at 0 0 0)
			(layer "F.Fab")
			(hide yes)
			(effects
				(font
					(size 1 1)
					(thickness 0.15)
				)
			)
		)
		(property "Manufacturer" "Bourns"
			(at 0 0 0)
			(layer "F.Fab")
			(hide yes)
			(effects
				(font
					(size 1 1)
					(thickness 0.15)
				)
			)
		)
		(property "Tolerance" "1%"
			(at 0 0 0)
			(layer "F.Fab")
			(hide yes)
			(effects
				(font
					(size 1 1)
					(thickness 0.15)
				)
			)
		)
		(property "Val" "100R"
			(at 0 0 0)
			(layer "F.Fab")
			(hide yes)
			(effects
				(font
					(size 1 1)
					(thickness 0.15)
				)
			)
		)
		(property "dnp" ""
			(at 0 0 0)
			(layer "F.Fab")
			(hide yes)
			(effects
				(font
					(size 1 1)
					(thickness 0.15)
				)
			)
		)
		(property "exclude_from_bom" ""
			(at 0 0 0)
			(layer "F.Fab")
			(hide yes)
			(effects
				(font
					(size 1 1)
					(thickness 0.15)
				)
			)
		)
		(sheetname "SPI Flash + SD Card")
		(sheetfile "spi-flash.kicad_sch")
		(attr smd exclude_from_bom)
		(fp_rect
			(start -0.925 -0.47)
			(end 0.925 0.47)
			(stroke
				(width 0.05)
				(type default)
			)
			(fill no)
			(layer "F.CrtYd")
		)
		(fp_rect
			(start -0.5 -0.25)
			(end 0.5 0.25)
			(stroke
				(width 0.15)
				(type solid)
			)
			(fill no)
			(layer "F.Fab")
		)
		(pad "1" smd roundrect
			(at -0.48 0)
			(size 0.59 0.64)
			(layers "F.Cu" "F.Mask" "F.Paste")
			(roundrect_rratio 0.25)
			(net 1 "GND")
			(pintype "passive")
		)
		(pad "2" smd roundrect
			(at 0.48 0)
			(size 0.59 0.64)
			(layers "F.Cu" "F.Mask" "F.Paste")
			(roundrect_rratio 0.25)
			(net 427 "/FPGA Bank 16 & 17/USR_FLASH_1.CLK")
			(pintype "passive")
		)
	)
	(footprint "antmicro-footprints:C_0402_1005Metric"
		(layer "F.Cu")
		(at 209.35 157.09 90)
		(descr "Capacitor SMD 0402")
		(tags "capacitor SMD 0402")
		(property "Reference" "C210"
			(at -1.41 -0.5 90)
			(layer "F.SilkS")
			(effects
				(font
					(size 0.7 0.7)
					(thickness 0.15)
				)
				(justify left bottom)
			)
		)
		(property "Value" "C_100n_0402"
			(at 0 1.4 90)
			(layer "F.Fab")
			(effects
				(font
					(size 0.7 0.7)
					(thickness 0.15)
				)
				(justify left bottom)
			)
		)
		(property "Description" "SMD Multilayer Ceramic Capacitor, 0.1 µF, 50 V, 0402 [1005 Metric], ± 10%, X5R, GRM Series"
			(at 0 0 90)
			(layer "F.Fab")
			(hide yes)
			(effects
				(font
					(size 1.27 1.27)
					(thickness 0.15)
				)
			)
		)
		(property "Author" "Antmicro"
			(at 366.44 -52.26 0)
			(layer "F.Fab")
			(hide yes)
			(effects
				(font
					(size 1 1)
					(thickness 0.15)
				)
			)
		)
		(property "Dielectric" "X5R"
			(at 366.44 -52.26 0)
			(layer "F.Fab")
			(hide yes)
			(effects
				(font
					(size 1 1)
					(thickness 0.15)
				)
			)
		)
		(property "License" "Apache-2.0"
			(at 366.44 -52.26 0)
			(layer "F.Fab")
			(hide yes)
			(effects
				(font
					(size 1 1)
					(thickness 0.15)
				)
			)
		)
		(property "MPN" "GRM155R61H104KE14D"
			(at 366.44 -52.26 0)
			(layer "F.Fab")
			(hide yes)
			(effects
				(font
					(size 1 1)
					(thickness 0.15)
				)
			)
		)
		(property "Manufacturer" "Murata"
			(at 366.44 -52.26 0)
			(layer "F.Fab")
			(hide yes)
			(effects
				(font
					(size 1 1)
					(thickness 0.15)
				)
			)
		)
		(property "Val" "100n"
			(at 366.44 -52.26 0)
			(layer "F.Fab")
			(hide yes)
			(effects
				(font
					(size 1 1)
					(thickness 0.15)
				)
			)
		)
		(property "Voltage" "50V"
			(at 366.44 -52.26 0)
			(layer "F.Fab")
			(hide yes)
			(effects
				(font
					(size 1 1)
					(thickness 0.15)
				)
			)
		)
		(sheetname "SPI Flash + SD Card")
		(sheetfile "spi-flash.kicad_sch")
		(attr smd)
		(fp_rect
			(start -0.925 -0.47)
			(end 0.925 0.47)
			(stroke
				(width 0.05)
				(type default)
			)
			(fill no)
			(layer "F.CrtYd")
		)
		(fp_line
			(start 0.504 -0.25)
			(end 0.504 0.248)
			(stroke
				(width 0.15)
				(type solid)
			)
			(layer "F.Fab")
		)
		(fp_line
			(start -0.494 -0.25)
			(end 0.504 -0.25)
			(stroke
				(width 0.15)
				(type solid)
			)
			(layer "F.Fab")
		)
		(fp_line
			(start 0.504 0.248)
			(end -0.494 0.248)
			(stroke
				(width 0.15)
				(type solid)
			)
			(layer "F.Fab")
		)
		(fp_line
			(start -0.494 0.248)
			(end -0.494 -0.25)
			(stroke
				(width 0.15)
				(type solid)
			)
			(layer "F.Fab")
		)
		(pad "1" smd roundrect
			(at -0.48 0 90)
			(size 0.59 0.64)
			(layers "F.Cu" "F.Mask" "F.Paste")
			(roundrect_rratio 0.25)
			(net 1 "GND")
			(pintype "passive")
		)
		(pad "2" smd roundrect
			(at 0.48 0 90)
			(size 0.59 0.64)
			(layers "F.Cu" "F.Mask" "F.Paste")
			(roundrect_rratio 0.25)
			(net 26 "+1V8")
			(pintype "passive")
		)
	)
	(footprint "antmicro-footprints:SC70-3"
		(layer "F.Cu")
		(at 207.4 78.79 90)
		(property "Reference" "Q1"
			(at -2.31 -1.8 180)
			(layer "F.SilkS")
			(effects
				(font
					(size 0.7 0.7)
					(thickness 0.15)
				)
				(justify left bottom)
			)
		)
		(property "Value" "BSS138PW"
			(at 0 2.3 90)
			(layer "F.Fab")
			(effects
				(font
					(size 0.7 0.7)
					(thickness 0.15)
				)
				(justify left bottom)
			)
		)
		(property "Description" "Power MOSFET, N Channel, 60 V, 320 mA, 0.9 ohm, SOT-323, Surface Mount"
			(at 0 0 90)
			(layer "F.Fab")
			(hide yes)
			(effects
				(font
					(size 1.27 1.27)
					(thickness 0.15)
				)
			)
		)
		(property "Author" "Antmicro"
			(at 286.19 -128.61 0)
			(layer "F.Fab")
			(hide yes)
			(effects
				(font
					(size 1 1)
					(thickness 0.15)
				)
			)
		)
		(property "License" "Apache-2.0"
			(at 286.19 -128.61 0)
			(layer "F.Fab")
			(hide yes)
			(effects
				(font
					(size 1 1)
					(thickness 0.15)
				)
			)
		)
		(property "MPN" "BSS138PW"
			(at 286.19 -128.61 0)
			(layer "F.Fab")
			(hide yes)
			(effects
				(font
					(size 1 1)
					(thickness 0.15)
				)
			)
		)
		(property "Manufacturer" "Nexperia"
			(at 286.19 -128.61 0)
			(layer "F.Fab")
			(hide yes)
			(effects
				(font
					(size 1 1)
					(thickness 0.15)
				)
			)
		)
		(sheetname "FPGA Config")
		(sheetfile "fpga-config.kicad_sch")
		(attr smd)
		(fp_line
			(start -0.3 -1)
			(end 0.627 -0.999)
			(stroke
				(width 0.15)
				(type solid)
			)
			(layer "F.SilkS")
		)
		(fp_line
			(start 0.627 -0.6)
			(end 0.627 -0.999)
			(stroke
				(width 0.15)
				(type solid)
			)
			(layer "F.SilkS")
		)
		(fp_line
			(start 0.627 0.6)
			(end 0.627 1.001)
			(stroke
				(width 0.15)
				(type solid)
			)
			(layer "F.SilkS")
		)
		(fp_line
			(start -0.3 1)
			(end 0.627 1.001)
			(stroke
				(width 0.15)
				(type solid)
			)
			(layer "F.SilkS")
		)
		(fp_line
			(start 0.9 -1.3)
			(end 0.9 -0.4)
			(stroke
				(width 0.05)
				(type solid)
			)
			(layer "F.CrtYd")
		)
		(fp_line
			(start -0.9 -1.3)
			(end 0.9 -1.3)
			(stroke
				(width 0.05)
				(type solid)
			)
			(layer "F.CrtYd")
		)
		(fp_line
			(start -0.9 -1.3)
			(end -0.9 -1)
			(stroke
				(width 0.05)
				(type solid)
			)
			(layer "F.CrtYd")
		)
		(fp_line
			(start -0.9 -1)
			(end -1.4 -1)
			(stroke
				(width 0.05)
				(type solid)
			)
			(layer "F.CrtYd")
		)
		(fp_line
			(start 1.4 -0.4)
			(end 1.4 0.4)
			(stroke
				(width 0.05)
				(type solid)
			)
			(layer "F.CrtYd")
		)
		(fp_line
			(start 0.9 -0.4)
			(end 1.4 -0.4)
			(stroke
				(width 0.05)
				(type solid)
			)
			(layer "F.CrtYd")
		)
		(fp_line
			(start 1.4 0.4)
			(end 0.9 0.4)
			(stroke
				(width 0.05)
				(type solid)
			)
			(layer "F.CrtYd")
		)
		(fp_line
			(start 0.9 0.4)
			(end 0.9 1.3)
			(stroke
				(width 0.05)
				(type solid)
			)
			(layer "F.CrtYd")
		)
		(fp_line
			(start -0.9 1)
			(end -1.4 1)
			(stroke
				(width 0.05)
				(type solid)
			)
			(layer "F.CrtYd")
		)
		(fp_line
			(start -1.4 1)
			(end -1.4 -1)
			(stroke
				(width 0.05)
				(type solid)
			)
			(layer "F.CrtYd")
		)
		(fp_line
			(start 0.9 1.3)
			(end -0.9 1.3)
			(stroke
				(width 0.05)
				(type solid)
			)
			(layer "F.CrtYd")
		)
		(fp_line
			(start -0.9 1.3)
			(end -0.9 1)
			(stroke
				(width 0.05)
				(type solid)
			)
			(layer "F.CrtYd")
		)
		(fp_rect
			(start -0.623 -0.999)
			(end 0.627 1.001)
			(stroke
				(width 0.15)
				(type solid)
			)
			(fill no)
			(layer "F.Fab")
		)
		(pad "1" smd rect
			(at -1.051 -0.65 180)
			(size 0.6 0.6)
			(layers "F.Cu" "F.Mask" "F.Paste")
			(net 246 "/FPGA Config/DONE")
			(pinfunction "G")
			(pintype "bidirectional")
		)
		(pad "2" smd rect
			(at -1.051 0.65 180)
			(size 0.6 0.6)
			(layers "F.Cu" "F.Mask" "F.Paste")
			(net 1 "GND")
			(pinfunction "S")
			(pintype "bidirectional")
		)
		(pad "3" smd rect
			(at 1.05 0 180)
			(size 0.6 0.6)
			(layers "F.Cu" "F.Mask" "F.Paste")
			(net 333 "Net-(Q1-D)")
			(pinfunction "D")
			(pintype "bidirectional")
		)
	)
	(footprint "antmicro-footprints:C_0805_2012Metric"
		(layer "F.Cu")
		(at 159.0125 176.2)
		(descr "Capacitor SMD 0805")
		(tags "capacitor SMD 0805")
		(property "Reference" "C315"
			(at 2.4875 1.8 0)
			(layer "F.SilkS")
			(effects
				(font
					(size 0.7 0.7)
					(thickness 0.15)
				)
				(justify left bottom)
			)
		)
		(property "Value" "C_22u_25V_0805"
			(at 0 1.947 0)
			(layer "F.Fab")
			(effects
				(font
					(size 0.7 0.7)
					(thickness 0.15)
				)
				(justify left bottom)
			)
		)
		(property "Description" "SMT Multilayer Ceramic Capacitor, 22uF, +/-20%, 25V, X5R, 0805 [2012 Metric]"
			(at 0 0 0)
			(layer "F.Fab")
			(hide yes)
			(effects
				(font
					(size 1.27 1.27)
					(thickness 0.15)
				)
			)
		)
		(property "Author" "Antmicro"
			(at 0 0 0)
			(layer "F.Fab")
			(hide yes)
			(effects
				(font
					(size 1 1)
					(thickness 0.15)
				)
			)
		)
		(property "Dielectric" "X5R"
			(at 0 0 0)
			(layer "F.Fab")
			(hide yes)
			(effects
				(font
					(size 1 1)
					(thickness 0.15)
				)
			)
		)
		(property "License" "Apache-2.0"
			(at 0 0 0)
			(layer "F.Fab")
			(hide yes)
			(effects
				(font
					(size 1 1)
					(thickness 0.15)
				)
			)
		)
		(property "MPN" "CL21A226MAYNNNE"
			(at 0 0 0)
			(layer "F.Fab")
			(hide yes)
			(effects
				(font
					(size 1 1)
					(thickness 0.15)
				)
			)
		)
		(property "Manufacturer" "Samsung Electro-Mechanics"
			(at 0 0 0)
			(layer "F.Fab")
			(hide yes)
			(effects
				(font
					(size 1 1)
					(thickness 0.15)
				)
			)
		)
		(property "Val" "22u"
			(at 0 0 0)
			(layer "F.Fab")
			(hide yes)
			(effects
				(font
					(size 1 1)
					(thickness 0.15)
				)
			)
		)
		(property "Voltage" "25V"
			(at 0 0 0)
			(layer "F.Fab")
			(hide yes)
			(effects
				(font
					(size 1 1)
					(thickness 0.15)
				)
			)
		)
		(sheetname "DC-DC Converters")
		(sheetfile "dc-dc.kicad_sch")
		(attr smd)
		(fp_line
			(start -0.3 -0.7)
			(end 0.3 -0.7)
			(stroke
				(width 0.15)
				(type solid)
			)
			(layer "F.SilkS")
		)
		(fp_line
			(start -0.3 0.7)
			(end 0.3 0.7)
			(stroke
				(width 0.15)
				(type solid)
			)
			(layer "F.SilkS")
		)
		(fp_rect
			(start 1.95 -0.9)
			(end -1.95 0.9)
			(stroke
				(width 0.05)
				(type default)
			)
			(fill no)
			(layer "F.CrtYd")
		)
		(fp_rect
			(start -0.95 -0.675)
			(end 0.95 0.675)
			(stroke
				(width 0.15)
				(type solid)
			)
			(fill no)
			(layer "F.Fab")
		)
		(pad "1" smd roundrect
			(at -1.1 0)
			(size 1.2 1.3)
			(layers "F.Cu" "F.Mask" "F.Paste")
			(roundrect_rratio 0.25)
			(net 1 "GND")
			(pintype "passive")
		)
		(pad "2" smd roundrect
			(at 1.1 0)
			(size 1.2 1.3)
			(layers "F.Cu" "F.Mask" "F.Paste")
			(roundrect_rratio 0.25)
			(net 702 "VDC")
			(pintype "passive")
		)
	)
	(footprint "antmicro-footprints:R_0402_1005Metric"
		(layer "F.Cu")
		(at 242.15 109.5)
		(descr "Resistor SMD 0402")
		(tags "resistor SMD 0402")
		(property "Reference" "R260"
			(at -3.65 0.35 0)
			(layer "F.SilkS")
			(effects
				(font
					(size 0.7 0.7)
					(thickness 0.15)
				)
				(justify left bottom)
			)
		)
		(property "Value" "R_0R_0402"
			(at 0 1.4 0)
			(layer "F.Fab")
			(effects
				(font
					(size 0.7 0.7)
					(thickness 0.15)
				)
				(justify left bottom)
			)
		)
		(property "Description" "SMD Chip Resistor, Jumper, 0 ohm, 100 mW, 0402 [1005 Metric], Thick Film, General Purpose"
			(at 0 0 0)
			(layer "F.Fab")
			(hide yes)
			(effects
				(font
					(size 1.27 1.27)
					(thickness 0.15)
				)
			)
		)
		(property "Author" "Antmicro"
			(at 0 0 0)
			(layer "F.Fab")
			(hide yes)
			(effects
				(font
					(size 1 1)
					(thickness 0.15)
				)
			)
		)
		(property "Current" "1A"
			(at 0 0 0)
			(layer "F.Fab")
			(hide yes)
			(effects
				(font
					(size 1 1)
					(thickness 0.15)
				)
			)
		)
		(property "License" "Apache-2.0"
			(at 0 0 0)
			(layer "F.Fab")
			(hide yes)
			(effects
				(font
					(size 1 1)
					(thickness 0.15)
				)
			)
		)
		(property "MPN" "ERJ2GE0R00X"
			(at 0 0 0)
			(layer "F.Fab")
			(hide yes)
			(effects
				(font
					(size 1 1)
					(thickness 0.15)
				)
			)
		)
		(property "Manufacturer" "Panasonic"
			(at 0 0 0)
			(layer "F.Fab")
			(hide yes)
			(effects
				(font
					(size 1 1)
					(thickness 0.15)
				)
			)
		)
		(property "Tolerance" ""
			(at 0 0 0)
			(layer "F.Fab")
			(hide yes)
			(effects
				(font
					(size 1 1)
					(thickness 0.15)
				)
			)
		)
		(property "Val" "0R"
			(at 0 0 0)
			(layer "F.Fab")
			(hide yes)
			(effects
				(font
					(size 1 1)
					(thickness 0.15)
				)
			)
		)
		(sheetname "HDMI + Ethernet")
		(sheetfile "hdmi-ethernet.kicad_sch")
		(attr smd)
		(fp_rect
			(start -0.925 -0.47)
			(end 0.925 0.47)
			(stroke
				(width 0.05)
				(type default)
			)
			(fill no)
			(layer "F.CrtYd")
		)
		(fp_rect
			(start -0.5 -0.25)
			(end 0.5 0.25)
			(stroke
				(width 0.15)
				(type solid)
			)
			(fill no)
			(layer "F.Fab")
		)
		(pad "1" smd roundrect
			(at -0.48 0)
			(size 0.59 0.64)
			(layers "F.Cu" "F.Mask" "F.Paste")
			(roundrect_rratio 0.25)
			(net 530 "/FPGA Bank 16 & 17/HDMI.CLK_P")
			(pintype "passive")
		)
		(pad "2" smd roundrect
			(at 0.48 0)
			(size 0.59 0.64)
			(layers "F.Cu" "F.Mask" "F.Paste")
			(roundrect_rratio 0.25)
			(net 861 "/HDMI + Ethernet/HDMI_CONN_CLK_P")
			(pintype "passive")
		)
	)
	(footprint "antmicro-footprints:R_0402_1005Metric"
		(layer "F.Cu")
		(at 224.8 163.4 180)
		(descr "Resistor SMD 0402")
		(tags "resistor SMD 0402")
		(property "Reference" "R51"
			(at 1.1 -1.25 180)
			(layer "F.SilkS")
			(effects
				(font
					(size 0.7 0.7)
					(thickness 0.15)
				)
				(justify left bottom)
			)
		)
		(property "Value" "R_22k_0402"
			(at 0 1.4 180)
			(layer "F.Fab")
			(effects
				(font
					(size 0.7 0.7)
					(thickness 0.15)
				)
				(justify left bottom)
			)
		)
		(property "Description" "SMD Chip Resistor, 22 kohm, ± 1%, 62.5 mW, 0402 [1005 Metric], Thick Film, General Purpose"
			(at 0 0 180)
			(layer "F.Fab")
			(hide yes)
			(effects
				(font
					(size 1.27 1.27)
					(thickness 0.15)
				)
			)
		)
		(property "Author" "Antmicro"
			(at 449.6 326.8 0)
			(layer "F.Fab")
			(hide yes)
			(effects
				(font
					(size 1 1)
					(thickness 0.15)
				)
			)
		)
		(property "License" "Apache-2.0"
			(at 449.6 326.8 0)
			(layer "F.Fab")
			(hide yes)
			(effects
				(font
					(size 1 1)
					(thickness 0.15)
				)
			)
		)
		(property "MPN" "CR0402-FX-2202GLF"
			(at 449.6 326.8 0)
			(layer "F.Fab")
			(hide yes)
			(effects
				(font
					(size 1 1)
					(thickness 0.15)
				)
			)
		)
		(property "Manufacturer" "Bourns"
			(at 449.6 326.8 0)
			(layer "F.Fab")
			(hide yes)
			(effects
				(font
					(size 1 1)
					(thickness 0.15)
				)
			)
		)
		(property "Tolerance" "1%"
			(at 449.6 326.8 0)
			(layer "F.Fab")
			(hide yes)
			(effects
				(font
					(size 1 1)
					(thickness 0.15)
				)
			)
		)
		(property "Val" "22k"
			(at 449.6 326.8 0)
			(layer "F.Fab")
			(hide yes)
			(effects
				(font
					(size 1 1)
					(thickness 0.15)
				)
			)
		)
		(sheetname "Power supply")
		(sheetfile "power-supply.kicad_sch")
		(attr smd)
		(fp_rect
			(start -0.925 -0.47)
			(end 0.925 0.47)
			(stroke
				(width 0.05)
				(type default)
			)
			(fill no)
			(layer "F.CrtYd")
		)
		(fp_rect
			(start -0.5 -0.25)
			(end 0.5 0.25)
			(stroke
				(width 0.15)
				(type solid)
			)
			(fill no)
			(layer "F.Fab")
		)
		(pad "1" smd roundrect
			(at -0.48 0 180)
			(size 0.59 0.64)
			(layers "F.Cu" "F.Mask" "F.Paste")
			(roundrect_rratio 0.25)
			(net 362 "Net-(U6-VBUS_EN_SNK)")
			(pintype "passive")
		)
		(pad "2" smd roundrect
			(at 0.48 0 180)
			(size 0.59 0.64)
			(layers "F.Cu" "F.Mask" "F.Paste")
			(roundrect_rratio 0.25)
			(net 872 "/Power supply/SINK_EN")
			(pintype "passive")
		)
	)
	(footprint "antmicro-footprints:C_0402_1005Metric"
		(layer "F.Cu")
		(at 195.8375 97.0865)
		(descr "Capacitor SMD 0402")
		(tags "capacitor SMD 0402")
		(property "Reference" "C254"
			(at -1.4875 1.2635 0)
			(layer "F.SilkS")
			(effects
				(font
					(size 0.7 0.7)
					(thickness 0.15)
				)
				(justify left bottom)
			)
		)
		(property "Value" "C_10u_0402"
			(at 0 1.4 0)
			(layer "F.Fab")
			(effects
				(font
					(size 0.7 0.7)
					(thickness 0.15)
				)
				(justify left bottom)
			)
		)
		(property "Description" "SMD Multilayer Ceramic Capacitor, 10 µF, 6.3 V, 0402 [1005 Metric], ± 20%, X5R, CC Series"
			(at 0 0 0)
			(layer "F.Fab")
			(hide yes)
			(effects
				(font
					(size 1.27 1.27)
					(thickness 0.15)
				)
			)
		)
		(property "Author" "Antmicro"
			(at 0 0 0)
			(layer "F.Fab")
			(hide yes)
			(effects
				(font
					(size 1 1)
					(thickness 0.15)
				)
			)
		)
		(property "Dielectric" ""
			(at 0 0 0)
			(layer "F.Fab")
			(hide yes)
			(effects
				(font
					(size 1 1)
					(thickness 0.15)
				)
			)
		)
		(property "License" "Apache-2.0"
			(at 0 0 0)
			(layer "F.Fab")
			(hide yes)
			(effects
				(font
					(size 1 1)
					(thickness 0.15)
				)
			)
		)
		(property "MPN" "CC0402MRX5R5BB106"
			(at 0 0 0)
			(layer "F.Fab")
			(hide yes)
			(effects
				(font
					(size 1 1)
					(thickness 0.15)
				)
			)
		)
		(property "Manufacturer" "YAGEO"
			(at 0 0 0)
			(layer "F.Fab")
			(hide yes)
			(effects
				(font
					(size 1 1)
					(thickness 0.15)
				)
			)
		)
		(property "Val" "10u"
			(at 0 0 0)
			(layer "F.Fab")
			(hide yes)
			(effects
				(font
					(size 1 1)
					(thickness 0.15)
				)
			)
		)
		(property "Voltage" ""
			(at 0 0 0)
			(layer "F.Fab")
			(hide yes)
			(effects
				(font
					(size 1 1)
					(thickness 0.15)
				)
			)
		)
		(sheetname "HDMI + Ethernet")
		(sheetfile "hdmi-ethernet.kicad_sch")
		(attr smd)
		(fp_rect
			(start -0.925 -0.47)
			(end 0.925 0.47)
			(stroke
				(width 0.05)
				(type default)
			)
			(fill no)
			(layer "F.CrtYd")
		)
		(fp_line
			(start -0.494 -0.25)
			(end 0.504 -0.25)
			(stroke
				(width 0.15)
				(type solid)
			)
			(layer "F.Fab")
		)
		(fp_line
			(start -0.494 0.248)
			(end -0.494 -0.25)
			(stroke
				(width 0.15)
				(type solid)
			)
			(layer "F.Fab")
		)
		(fp_line
			(start 0.504 -0.25)
			(end 0.504 0.248)
			(stroke
				(width 0.15)
				(type solid)
			)
			(layer "F.Fab")
		)
		(fp_line
			(start 0.504 0.248)
			(end -0.494 0.248)
			(stroke
				(width 0.15)
				(type solid)
			)
			(layer "F.Fab")
		)
		(pad "1" smd roundrect
			(at -0.48 0)
			(size 0.59 0.64)
			(layers "F.Cu" "F.Mask" "F.Paste")
			(roundrect_rratio 0.25)
			(net 1 "GND")
			(pintype "passive")
		)
		(pad "2" smd roundrect
			(at 0.48 0)
			(size 0.59 0.64)
			(layers "F.Cu" "F.Mask" "F.Paste")
			(roundrect_rratio 0.25)
			(net 24 "+3V3")
			(pintype "passive")
		)
	)
	(footprint "antmicro-footprints:C_0402_1005Metric"
		(layer "F.Cu")
		(at 207.403752 92.6615 180)
		(descr "Capacitor SMD 0402")
		(tags "capacitor SMD 0402")
		(property "Reference" "C287"
			(at 1.753752 5.1115 180)
			(layer "F.SilkS")
			(effects
				(font
					(size 0.7 0.7)
					(thickness 0.15)
				)
				(justify left bottom)
			)
		)
		(property "Value" "C_100n_0402"
			(at 0 1.169 180)
			(layer "F.Fab")
			(effects
				(font
					(size 0.7 0.7)
					(thickness 0.15)
				)
				(justify left bottom)
			)
		)
		(property "Description" "SMD Multilayer Ceramic Capacitor, 0.1 µF, 50 V, 0402 [1005 Metric], ± 10%, X5R, GRM Series"
			(at 0 0 180)
			(layer "F.Fab")
			(hide yes)
			(effects
				(font
					(size 1.27 1.27)
					(thickness 0.15)
				)
			)
		)
		(property "Author" "Antmicro"
			(at 414.807504 185.323 0)
			(layer "F.Fab")
			(hide yes)
			(effects
				(font
					(size 1 1)
					(thickness 0.15)
				)
			)
		)
		(property "Dielectric" "X5R"
			(at 414.807504 185.323 0)
			(layer "F.Fab")
			(hide yes)
			(effects
				(font
					(size 1 1)
					(thickness 0.15)
				)
			)
		)
		(property "License" "Apache-2.0"
			(at 414.807504 185.323 0)
			(layer "F.Fab")
			(hide yes)
			(effects
				(font
					(size 1 1)
					(thickness 0.15)
				)
			)
		)
		(property "MPN" "GRM155R61H104KE14D"
			(at 414.807504 185.323 0)
			(layer "F.Fab")
			(hide yes)
			(effects
				(font
					(size 1 1)
					(thickness 0.15)
				)
			)
		)
		(property "Manufacturer" "Murata"
			(at 414.807504 185.323 0)
			(layer "F.Fab")
			(hide yes)
			(effects
				(font
					(size 1 1)
					(thickness 0.15)
				)
			)
		)
		(property "Val" "100n"
			(at 414.807504 185.323 0)
			(layer "F.Fab")
			(hide yes)
			(effects
				(font
					(size 1 1)
					(thickness 0.15)
				)
			)
		)
		(property "Voltage" "50V"
			(at 414.807504 185.323 0)
			(layer "F.Fab")
			(hide yes)
			(effects
				(font
					(size 1 1)
					(thickness 0.15)
				)
			)
		)
		(sheetname "HDMI + Ethernet")
		(sheetfile "hdmi-ethernet.kicad_sch")
		(attr smd)
		(fp_rect
			(start -0.925 -0.47)
			(end 0.925 0.47)
			(stroke
				(width 0.05)
				(type default)
			)
			(fill no)
			(layer "F.CrtYd")
		)
		(fp_line
			(start 0.504 0.248)
			(end -0.494 0.248)
			(stroke
				(width 0.15)
				(type solid)
			)
			(layer "F.Fab")
		)
		(fp_line
			(start 0.504 -0.25)
			(end 0.504 0.248)
			(stroke
				(width 0.15)
				(type solid)
			)
			(layer "F.Fab")
		)
		(fp_line
			(start -0.494 0.248)
			(end -0.494 -0.25)
			(stroke
				(width 0.15)
				(type solid)
			)
			(layer "F.Fab")
		)
		(fp_line
			(start -0.494 -0.25)
			(end 0.504 -0.25)
			(stroke
				(width 0.15)
				(type solid)
			)
			(layer "F.Fab")
		)
		(pad "1" smd roundrect
			(at -0.48 0 180)
			(size 0.59 0.64)
			(layers "F.Cu" "F.Mask" "F.Paste")
			(roundrect_rratio 0.25)
			(net 1 "GND")
			(pintype "passive")
		)
		(pad "2" smd roundrect
			(at 0.48 0 180)
			(size 0.59 0.64)
			(layers "F.Cu" "F.Mask" "F.Paste")
			(roundrect_rratio 0.25)
			(net 728 "/HDMI + Ethernet/GBE_AVDDL{slash}PLL")
			(pintype "passive")
		)
	)
	(footprint "antmicro-footprints:C_0402_1005Metric"
		(layer "F.Cu")
		(at 248.7 141.6 90)
		(descr "Capacitor SMD 0402")
		(tags "capacitor SMD 0402")
		(property "Reference" "C230"
			(at -1.55 -0.45 90)
			(layer "F.SilkS")
			(effects
				(font
					(size 0.7 0.7)
					(thickness 0.15)
				)
				(justify left bottom)
			)
		)
		(property "Value" "C_100n_0402"
			(at 0 1.169 90)
			(layer "F.Fab")
			(effects
				(font
					(size 0.7 0.7)
					(thickness 0.15)
				)
				(justify left bottom)
			)
		)
		(property "Description" "SMD Multilayer Ceramic Capacitor, 0.1 µF, 50 V, 0402 [1005 Metric], ± 10%, X5R, GRM Series"
			(at 0 0 90)
			(layer "F.Fab")
			(hide yes)
			(effects
				(font
					(size 1.27 1.27)
					(thickness 0.15)
				)
			)
		)
		(property "Author" "Antmicro"
			(at 390.3 -107.1 0)
			(layer "F.Fab")
			(hide yes)
			(effects
				(font
					(size 1 1)
					(thickness 0.15)
				)
			)
		)
		(property "Dielectric" "X5R"
			(at 390.3 -107.1 0)
			(layer "F.Fab")
			(hide yes)
			(effects
				(font
					(size 1 1)
					(thickness 0.15)
				)
			)
		)
		(property "License" "Apache-2.0"
			(at 390.3 -107.1 0)
			(layer "F.Fab")
			(hide yes)
			(effects
				(font
					(size 1 1)
					(thickness 0.15)
				)
			)
		)
		(property "MPN" "GRM155R61H104KE14D"
			(at 390.3 -107.1 0)
			(layer "F.Fab")
			(hide yes)
			(effects
				(font
					(size 1 1)
					(thickness 0.15)
				)
			)
		)
		(property "Manufacturer" "Murata"
			(at 390.3 -107.1 0)
			(layer "F.Fab")
			(hide yes)
			(effects
				(font
					(size 1 1)
					(thickness 0.15)
				)
			)
		)
		(property "Val" "100n"
			(at 390.3 -107.1 0)
			(layer "F.Fab")
			(hide yes)
			(effects
				(font
					(size 1 1)
					(thickness 0.15)
				)
			)
		)
		(property "Voltage" "50V"
			(at 390.3 -107.1 0)
			(layer "F.Fab")
			(hide yes)
			(effects
				(font
					(size 1 1)
					(thickness 0.15)
				)
			)
		)
		(sheetname "USB PHY")
		(sheetfile "usb-phy.kicad_sch")
		(attr smd)
		(fp_rect
			(start -0.925 -0.47)
			(end 0.925 0.47)
			(stroke
				(width 0.05)
				(type default)
			)
			(fill no)
			(layer "F.CrtYd")
		)
		(fp_line
			(start 0.504 -0.25)
			(end 0.504 0.248)
			(stroke
				(width 0.15)
				(type solid)
			)
			(layer "F.Fab")
		)
		(fp_line
			(start -0.494 -0.25)
			(end 0.504 -0.25)
			(stroke
				(width 0.15)
				(type solid)
			)
			(layer "F.Fab")
		)
		(fp_line
			(start 0.504 0.248)
			(end -0.494 0.248)
			(stroke
				(width 0.15)
				(type solid)
			)
			(layer "F.Fab")
		)
		(fp_line
			(start -0.494 0.248)
			(end -0.494 -0.25)
			(stroke
				(width 0.15)
				(type solid)
			)
			(layer "F.Fab")
		)
		(pad "1" smd roundrect
			(at -0.48 0 90)
			(size 0.59 0.64)
			(layers "F.Cu" "F.Mask" "F.Paste")
			(roundrect_rratio 0.25)
			(net 1 "GND")
			(pintype "passive")
		)
		(pad "2" smd roundrect
			(at 0.48 0 90)
			(size 0.59 0.64)
			(layers "F.Cu" "F.Mask" "F.Paste")
			(roundrect_rratio 0.25)
			(net 707 "/USB PHY/FTDI_3V3")
			(pintype "passive")
		)
	)
	(footprint "antmicro-footprints:R_0402_1005Metric"
		(layer "F.Cu")
		(at 236 135.4 180)
		(descr "Resistor SMD 0402")
		(tags "resistor SMD 0402")
		(property "Reference" "R196"
			(at 1.6 1.35 180)
			(layer "F.SilkS")
			(effects
				(font
					(size 0.7 0.7)
					(thickness 0.15)
				)
				(justify left bottom)
			)
		)
		(property "Value" "R_4k7_0402"
			(at 0 1.4 180)
			(layer "F.Fab")
			(effects
				(font
					(size 0.7 0.7)
					(thickness 0.15)
				)
				(justify left bottom)
			)
		)
		(property "Description" "SMD Chip Resistor, 4.7 kohm, ± 1%, 62.5 mW, 0402 [1005 Metric], Thick Film, General Purpose"
			(at 0 0 180)
			(layer "F.Fab")
			(hide yes)
			(effects
				(font
					(size 1.27 1.27)
					(thickness 0.15)
				)
			)
		)
		(property "Author" "Antmicro"
			(at 472 270.8 0)
			(layer "F.Fab")
			(hide yes)
			(effects
				(font
					(size 1 1)
					(thickness 0.15)
				)
			)
		)
		(property "License" "Apache-2.0"
			(at 472 270.8 0)
			(layer "F.Fab")
			(hide yes)
			(effects
				(font
					(size 1 1)
					(thickness 0.15)
				)
			)
		)
		(property "MPN" "CR0402-FX-4701GLF"
			(at 472 270.8 0)
			(layer "F.Fab")
			(hide yes)
			(effects
				(font
					(size 1 1)
					(thickness 0.15)
				)
			)
		)
		(property "Manufacturer" "Bourns"
			(at 472 270.8 0)
			(layer "F.Fab")
			(hide yes)
			(effects
				(font
					(size 1 1)
					(thickness 0.15)
				)
			)
		)
		(property "Tolerance" "1%"
			(at 472 270.8 0)
			(layer "F.Fab")
			(hide yes)
			(effects
				(font
					(size 1 1)
					(thickness 0.15)
				)
			)
		)
		(property "Val" "4k7"
			(at 472 270.8 0)
			(layer "F.Fab")
			(hide yes)
			(effects
				(font
					(size 1 1)
					(thickness 0.15)
				)
			)
		)
		(sheetname "USB PHY")
		(sheetfile "usb-phy.kicad_sch")
		(attr smd)
		(fp_rect
			(start -0.925 -0.47)
			(end 0.925 0.47)
			(stroke
				(width 0.05)
				(type default)
			)
			(fill no)
			(layer "F.CrtYd")
		)
		(fp_rect
			(start -0.5 -0.25)
			(end 0.5 0.25)
			(stroke
				(width 0.15)
				(type solid)
			)
			(fill no)
			(layer "F.Fab")
		)
		(pad "1" smd roundrect
			(at -0.48 0 180)
			(size 0.59 0.64)
			(layers "F.Cu" "F.Mask" "F.Paste")
			(roundrect_rratio 0.25)
			(net 1205 "Net-(D38-Pad1)")
			(pintype "passive")
		)
		(pad "2" smd roundrect
			(at 0.48 0 180)
			(size 0.59 0.64)
			(layers "F.Cu" "F.Mask" "F.Paste")
			(roundrect_rratio 0.25)
			(net 1336 "/I2C.SDA")
			(pintype "passive")
		)
	)
	(footprint "antmicro-footprints:LED_0603_1608Metric_R"
		(layer "F.Cu")
		(at 257.06 185.95 180)
		(descr "LED SMD 0603 Red")
		(tags "LED SMD 0603 Red")
		(property "Reference" "D9"
			(at -1.24 0.7 0)
			(layer "F.SilkS")
			(effects
				(font
					(size 0.7 0.7)
					(thickness 0.15)
				)
				(justify right bottom)
			)
		)
		(property "Value" "LED_R_0603_KP-1608EC"
			(at 0 1.6 0)
			(layer "F.Fab")
			(effects
				(font
					(size 0.7 0.7)
					(thickness 0.15)
				)
				(justify right bottom)
			)
		)
		(property "Description" "LED, Red, SMD, 0603, 30 mA, 2 V, 617 nm"
			(at 0 0 180)
			(layer "F.Fab")
			(hide yes)
			(effects
				(font
					(size 1.27 1.27)
					(thickness 0.15)
				)
			)
		)
		(property "Author" "Antmicro"
			(at 514.12 371.9 0)
			(layer "F.Fab")
			(hide yes)
			(effects
				(font
					(size 1 1)
					(thickness 0.15)
				)
			)
		)
		(property "Color" "Red"
			(at 514.12 371.9 0)
			(layer "F.Fab")
			(hide yes)
			(effects
				(font
					(size 1 1)
					(thickness 0.15)
				)
			)
		)
		(property "License" "Apache-2.0"
			(at 514.12 371.9 0)
			(layer "F.Fab")
			(hide yes)
			(effects
				(font
					(size 1 1)
					(thickness 0.15)
				)
			)
		)
		(property "MPN" "KP-1608EC"
			(at 514.12 371.9 0)
			(layer "F.Fab")
			(hide yes)
			(effects
				(font
					(size 1 1)
					(thickness 0.15)
				)
			)
		)
		(property "Manufacturer" "Kingbright"
			(at 514.12 371.9 0)
			(layer "F.Fab")
			(hide yes)
			(effects
				(font
					(size 1 1)
					(thickness 0.15)
				)
			)
		)
		(property "Public" "False"
			(at 514.12 371.9 0)
			(layer "F.Fab")
			(hide yes)
			(effects
				(font
					(size 1 1)
					(thickness 0.15)
				)
			)
		)
		(sheetname "Power supply")
		(sheetfile "power-supply.kicad_sch")
		(attr smd)
		(fp_line
			(start 0.22 0.35)
			(end -0.22 0.35)
			(stroke
				(width 0.15)
				(type solid)
			)
			(layer "F.SilkS")
		)
		(fp_line
			(start 0.22 -0.35)
			(end -0.22 -0.35)
			(stroke
				(width 0.15)
				(type solid)
			)
			(layer "F.SilkS")
		)
		(fp_line
			(start 0.105328 0.201008)
			(end 0.105328 -0.198992)
			(stroke
				(width 0.1)
				(type solid)
			)
			(layer "F.SilkS")
		)
		(fp_line
			(start 0.105328 0.201008)
			(end -0.094672 0.001008)
			(stroke
				(width 0.1)
				(type solid)
			)
			(layer "F.SilkS")
		)
		(fp_line
			(start 0.105328 0.001008)
			(end 0.24 0.001)
			(stroke
				(width 0.1)
				(type solid)
			)
			(layer "F.SilkS")
		)
		(fp_line
			(start -0.094672 0.201008)
			(end -0.094672 -0.198992)
			(stroke
				(width 0.1)
				(type solid)
			)
			(layer "F.SilkS")
		)
		(fp_line
			(start -0.094672 0.001008)
			(end 0.105328 -0.198992)
			(stroke
				(width 0.1)
				(type solid)
			)
			(layer "F.SilkS")
		)
		(fp_line
			(start -0.094672 0.001008)
			(end -0.24 0.001008)
			(stroke
				(width 0.1)
				(type solid)
			)
			(layer "F.SilkS")
		)
		(fp_line
			(start -1.18 -0.319)
			(end -1.18 0.321)
			(stroke
				(width 0.15)
				(type solid)
			)
			(layer "F.SilkS")
		)
		(fp_rect
			(start 1.25 0.65)
			(end -1.25 -0.65)
			(stroke
				(width 0.05)
				(type solid)
			)
			(fill no)
			(layer "F.CrtYd")
		)
		(fp_line
			(start 0.599 0)
			(end 0.201 0)
			(stroke
				(width 0.15)
				(type solid)
			)
			(layer "F.Fab")
		)
		(fp_line
			(start 0.201 0.2)
			(end 0.201 0)
			(stroke
				(width 0.15)
				(type solid)
			)
			(layer "F.Fab")
		)
		(fp_line
			(start 0.201 0)
			(end 0.201 -0.202)
			(stroke
				(width 0.15)
				(type solid)
			)
			(layer "F.Fab")
		)
		(fp_line
			(start 0.201 -0.202)
			(end -0.101 0)
			(stroke
				(width 0.15)
				(type solid)
			)
			(layer "F.Fab")
		)
		(fp_line
			(start -0.101 0)
			(end 0.201 0.2)
			(stroke
				(width 0.15)
				(type solid)
			)
			(layer "F.Fab")
		)
		(fp_line
			(start -0.199 0.2)
			(end -0.199 0.1)
			(stroke
				(width 0.15)
				(type solid)
			)
			(layer "F.Fab")
		)
		(fp_line
			(start -0.199 0)
			(end -0.597 0)
			(stroke
				(width 0.15)
				(type solid)
			)
			(layer "F.Fab")
		)
		(fp_line
			(start -0.199 -0.202)
			(end -0.199 0.1)
			(stroke
				(width 0.15)
				(type solid)
			)
			(layer "F.Fab")
		)
		(fp_rect
			(start 0.848 0.4)
			(end -0.85 -0.402)
			(stroke
				(width 0.15)
				(type solid)
			)
			(fill no)
			(layer "F.Fab")
		)
		(pad "1" smd roundrect
			(at -0.7 0)
			(size 0.8 1)
			(layers "F.Cu" "F.Mask" "F.Paste")
			(roundrect_rratio 0.2)
			(net 699 "GNDD")
			(pinfunction "C")
			(pintype "passive")
		)
		(pad "2" smd roundrect
			(at 0.7 0)
			(size 0.8 1)
			(layers "F.Cu" "F.Mask" "F.Paste")
			(roundrect_rratio 0.2)
			(net 18 "Net-(D9-A)")
			(pinfunction "A")
			(pintype "passive")
		)
	)
	(footprint "antmicro-footprints:SW_KMR211NGLFS_SMD"
		(layer "F.Cu")
		(at 266.8 84 180)
		(property "Reference" "S3"
			(at 0.7 -2.6 180)
			(layer "F.SilkS")
			(effects
				(font
					(size 0.7 0.7)
					(thickness 0.15)
				)
				(justify left bottom)
			)
		)
		(property "Value" "SW_KMR211NGLFS_SMD"
			(at -3 3 180)
			(layer "F.Fab")
			(effects
				(font
					(size 0.7 0.7)
					(thickness 0.15)
				)
				(justify left bottom)
			)
		)
		(property "Description" "Tactile Switch, KMR 2 Series, Top Actuated, Surface Mount, Oval Button, 120 gf, 50mA at 32VDC"
			(at 0 0 180)
			(layer "F.Fab")
			(hide yes)
			(effects
				(font
					(size 1.27 1.27)
					(thickness 0.15)
				)
			)
		)
		(property "Author" "Antmicro"
			(at 533.6 168 0)
			(layer "F.Fab")
			(hide yes)
			(effects
				(font
					(size 1 1)
					(thickness 0.15)
				)
			)
		)
		(property "License" "Apache-2.0"
			(at 533.6 168 0)
			(layer "F.Fab")
			(hide yes)
			(effects
				(font
					(size 1 1)
					(thickness 0.15)
				)
			)
		)
		(property "MPN" "KMR211NGLFS"
			(at 533.6 168 0)
			(layer "F.Fab")
			(hide yes)
			(effects
				(font
					(size 1 1)
					(thickness 0.15)
				)
			)
		)
		(property "Manufacturer" "C&K"
			(at 533.6 168 0)
			(layer "F.Fab")
			(hide yes)
			(effects
				(font
					(size 1 1)
					(thickness 0.15)
				)
			)
		)
		(sheetname "User GPIO + LED + button + DIP switch")
		(sheetfile "user-gpio.kicad_sch")
		(attr smd)
		(fp_line
			(start 2.101 1.601)
			(end 2.101 1.48)
			(stroke
				(width 0.15)
				(type solid)
			)
			(layer "F.SilkS")
		)
		(fp_line
			(start 2.101 1.601)
			(end -2.1 1.601)
			(stroke
				(width 0.15)
				(type solid)
			)
			(layer "F.SilkS")
		)
		(fp_line
			(start 2.101 -1.58)
			(end 2.101 -1.459)
			(stroke
				(width 0.15)
				(type solid)
			)
			(layer "F.SilkS")
		)
		(fp_line
			(start 2.101 -1.6)
			(end -2.1 -1.6)
			(stroke
				(width 0.15)
				(type solid)
			)
			(layer "F.SilkS")
		)
		(fp_line
			(start -2.1 1.601)
			(end -2.1 1.48)
			(stroke
				(width 0.15)
				(type solid)
			)
			(layer "F.SilkS")
		)
		(fp_line
			(start -2.1 -1.6)
			(end -2.1 -1.499)
			(stroke
				(width 0.15)
				(type solid)
			)
			(layer "F.SilkS")
		)
		(fp_rect
			(start 2.751 1.75)
			(end -2.748 -1.749)
			(stroke
				(width 0.05)
				(type solid)
			)
			(fill no)
			(layer "F.CrtYd")
		)
		(fp_line
			(start 2.101 1.601)
			(end 2.101 -1.6)
			(stroke
				(width 0.15)
				(type solid)
			)
			(layer "F.Fab")
		)
		(fp_line
			(start 2.101 -1.6)
			(end -2.1 -1.6)
			(stroke
				(width 0.15)
				(type solid)
			)
			(layer "F.Fab")
		)
		(fp_line
			(start 0.25 0.802)
			(end -0.248 0.802)
			(stroke
				(width 0.15)
				(type solid)
			)
			(layer "F.Fab")
		)
		(fp_line
			(start -0.248 -0.8)
			(end 0.25 -0.8)
			(stroke
				(width 0.15)
				(type solid)
			)
			(layer "F.Fab")
		)
		(fp_line
			(start -2.1 1.601)
			(end 2.101 1.601)
			(stroke
				(width 0.15)
				(type solid)
			)
			(layer "F.Fab")
		)
		(fp_line
			(start -2.1 -1.6)
			(end -2.1 1.601)
			(stroke
				(width 0.15)
				(type solid)
			)
			(layer "F.Fab")
		)
		(fp_arc
			(start 0.25 -0.8)
			(mid 1.051001 0.001)
			(end 0.25 0.802)
			(stroke
				(width 0.15)
				(type solid)
			)
			(layer "F.Fab")
		)
		(fp_arc
			(start -0.248 0.802)
			(mid -1.050001 0.001)
			(end -0.248 -0.8)
			(stroke
				(width 0.15)
				(type solid)
			)
			(layer "F.Fab")
		)
		(pad "1" smd rect
			(at -2.048 -0.8)
			(size 0.9 1)
			(layers "F.Cu" "F.Mask" "F.Paste")
			(net 13 "/USER_IO.BUTTON1")
			(pinfunction "1")
			(pintype "passive")
		)
		(pad "2" smd rect
			(at 2.05 -0.8)
			(size 0.9 1)
			(layers "F.Cu" "F.Mask" "F.Paste")
			(net 13 "/USER_IO.BUTTON1")
			(pinfunction "2")
			(pintype "passive")
		)
		(pad "3" smd rect
			(at -2.048 0.802)
			(size 0.9 1)
			(layers "F.Cu" "F.Mask" "F.Paste")
			(net 1 "GND")
			(pinfunction "3")
			(pintype "passive")
		)
		(pad "4" smd rect
			(at 2.05 0.802)
			(size 0.9 1)
			(layers "F.Cu" "F.Mask" "F.Paste")
			(net 1 "GND")
			(pinfunction "4")
			(pintype "passive")
		)
	)
	(footprint "antmicro-footprints:R_0402_1005Metric"
		(layer "F.Cu")
		(at 224.8 162.35 180)
		(descr "Resistor SMD 0402")
		(tags "resistor SMD 0402")
		(property "Reference" "R54"
			(at 1.15 0.3 180)
			(layer "F.SilkS")
			(effects
				(font
					(size 0.7 0.7)
					(thickness 0.15)
				)
				(justify left bottom)
			)
		)
		(property "Value" "R_100R_0402"
			(at 0 1.4 180)
			(layer "F.Fab")
			(effects
				(font
					(size 0.7 0.7)
					(thickness 0.15)
				)
				(justify left bottom)
			)
		)
		(property "Description" "SMD Chip Resistor, 100 ohm, ± 1%, 62.5 mW, 0402 [1005 Metric], Thick Film, General Purpose"
			(at 0 0 180)
			(layer "F.Fab")
			(hide yes)
			(effects
				(font
					(size 1.27 1.27)
					(thickness 0.15)
				)
			)
		)
		(property "Author" "Antmicro"
			(at 449.6 324.7 0)
			(layer "F.Fab")
			(hide yes)
			(effects
				(font
					(size 1 1)
					(thickness 0.15)
				)
			)
		)
		(property "License" "Apache-2.0"
			(at 449.6 324.7 0)
			(layer "F.Fab")
			(hide yes)
			(effects
				(font
					(size 1 1)
					(thickness 0.15)
				)
			)
		)
		(property "MPN" "CR0402-FX-1000GLF"
			(at 449.6 324.7 0)
			(layer "F.Fab")
			(hide yes)
			(effects
				(font
					(size 1 1)
					(thickness 0.15)
				)
			)
		)
		(property "Manufacturer" "Bourns"
			(at 449.6 324.7 0)
			(layer "F.Fab")
			(hide yes)
			(effects
				(font
					(size 1 1)
					(thickness 0.15)
				)
			)
		)
		(property "Tolerance" "1%"
			(at 449.6 324.7 0)
			(layer "F.Fab")
			(hide yes)
			(effects
				(font
					(size 1 1)
					(thickness 0.15)
				)
			)
		)
		(property "Val" "100R"
			(at 449.6 324.7 0)
			(layer "F.Fab")
			(hide yes)
			(effects
				(font
					(size 1 1)
					(thickness 0.15)
				)
			)
		)
		(sheetname "Power supply")
		(sheetfile "power-supply.kicad_sch")
		(attr smd)
		(fp_rect
			(start -0.925 -0.47)
			(end 0.925 0.47)
			(stroke
				(width 0.05)
				(type default)
			)
			(fill no)
			(layer "F.CrtYd")
		)
		(fp_rect
			(start -0.5 -0.25)
			(end 0.5 0.25)
			(stroke
				(width 0.15)
				(type solid)
			)
			(fill no)
			(layer "F.Fab")
		)
		(pad "1" smd roundrect
			(at -0.48 0 180)
			(size 0.59 0.64)
			(layers "F.Cu" "F.Mask" "F.Paste")
			(roundrect_rratio 0.25)
			(net 872 "/Power supply/SINK_EN")
			(pintype "passive")
		)
		(pad "2" smd roundrect
			(at 0.48 0 180)
			(size 0.59 0.64)
			(layers "F.Cu" "F.Mask" "F.Paste")
			(roundrect_rratio 0.25)
			(net 1227 "Net-(C198-Pad2)")
			(pintype "passive")
		)
	)
	(footprint "antmicro-footprints:C_0402_1005Metric"
		(layer "F.Cu")
		(at 154.225 152.4 180)
		(descr "Capacitor SMD 0402")
		(tags "capacitor SMD 0402")
		(property "Reference" "C356"
			(at 0.875 -0.4 0)
			(layer "F.SilkS")
			(effects
				(font
					(size 0.7 0.7)
					(thickness 0.15)
				)
				(justify right bottom)
			)
		)
		(property "Value" "C_100n_0402"
			(at 0 1.4 0)
			(layer "F.Fab")
			(effects
				(font
					(size 0.7 0.7)
					(thickness 0.15)
				)
				(justify right bottom)
			)
		)
		(property "Description" "SMD Multilayer Ceramic Capacitor, 0.1 µF, 50 V, 0402 [1005 Metric], ± 10%, X5R, GRM Series"
			(at 0 0 180)
			(layer "F.Fab")
			(hide yes)
			(effects
				(font
					(size 1.27 1.27)
					(thickness 0.15)
				)
			)
		)
		(property "Author" "Antmicro"
			(at 308.45 304.8 0)
			(layer "F.Fab")
			(hide yes)
			(effects
				(font
					(size 1 1)
					(thickness 0.15)
				)
			)
		)
		(property "Dielectric" "X5R"
			(at 308.45 304.8 0)
			(layer "F.Fab")
			(hide yes)
			(effects
				(font
					(size 1 1)
					(thickness 0.15)
				)
			)
		)
		(property "License" "Apache-2.0"
			(at 308.45 304.8 0)
			(layer "F.Fab")
			(hide yes)
			(effects
				(font
					(size 1 1)
					(thickness 0.15)
				)
			)
		)
		(property "MPN" "GRM155R61H104KE14D"
			(at 308.45 304.8 0)
			(layer "F.Fab")
			(hide yes)
			(effects
				(font
					(size 1 1)
					(thickness 0.15)
				)
			)
		)
		(property "Manufacturer" "Murata"
			(at 308.45 304.8 0)
			(layer "F.Fab")
			(hide yes)
			(effects
				(font
					(size 1 1)
					(thickness 0.15)
				)
			)
		)
		(property "Val" "100n"
			(at 308.45 304.8 0)
			(layer "F.Fab")
			(hide yes)
			(effects
				(font
					(size 1 1)
					(thickness 0.15)
				)
			)
		)
		(property "Voltage" "50V"
			(at 308.45 304.8 0)
			(layer "F.Fab")
			(hide yes)
			(effects
				(font
					(size 1 1)
					(thickness 0.15)
				)
			)
		)
		(sheetname "DC-DC Converters")
		(sheetfile "dc-dc.kicad_sch")
		(attr smd)
		(fp_rect
			(start -0.925 -0.47)
			(end 0.925 0.47)
			(stroke
				(width 0.05)
				(type default)
			)
			(fill no)
			(layer "F.CrtYd")
		)
		(fp_line
			(start 0.504 0.248)
			(end -0.494 0.248)
			(stroke
				(width 0.15)
				(type solid)
			)
			(layer "F.Fab")
		)
		(fp_line
			(start 0.504 -0.25)
			(end 0.504 0.248)
			(stroke
				(width 0.15)
				(type solid)
			)
			(layer "F.Fab")
		)
		(fp_line
			(start -0.494 0.248)
			(end -0.494 -0.25)
			(stroke
				(width 0.15)
				(type solid)
			)
			(layer "F.Fab")
		)
		(fp_line
			(start -0.494 -0.25)
			(end 0.504 -0.25)
			(stroke
				(width 0.15)
				(type solid)
			)
			(layer "F.Fab")
		)
		(pad "1" smd roundrect
			(at -0.48 0 180)
			(size 0.59 0.64)
			(layers "F.Cu" "F.Mask" "F.Paste")
			(roundrect_rratio 0.25)
			(net 1 "GND")
			(pintype "passive")
		)
		(pad "2" smd roundrect
			(at 0.48 0 180)
			(size 0.59 0.64)
			(layers "F.Cu" "F.Mask" "F.Paste")
			(roundrect_rratio 0.25)
			(net 11 "+0V675_VREF")
			(pintype "passive")
		)
	)
	(footprint "antmicro-footprints:NetTie-2_SMD_Pad0.127mm"
		(layer "F.Cu")
		(at 189.1 146.59 180)
		(descr "Net tie, 2 pin, 0.127mm  SMD pads")
		(tags "net tie")
		(property "Reference" "NT27"
			(at -0.128 -1.345 180)
			(layer "F.SilkS")
			(hide yes)
			(effects
				(font
					(size 0.7 0.7)
					(thickness 0.15)
				)
				(justify left bottom)
			)
		)
		(property "Value" "Net-Tie_2"
			(at 0 1.199 180)
			(layer "F.Fab")
			(effects
				(font
					(size 0.7 0.7)
					(thickness 0.15)
				)
				(justify left bottom)
			)
		)
		(property "Description" "Net tie, 2 pins"
			(at 0 0 180)
			(layer "F.Fab")
			(hide yes)
			(effects
				(font
					(size 1.27 1.27)
					(thickness 0.15)
				)
			)
		)
		(property "Author" "Antmicro"
			(at 378.2 293.18 0)
			(layer "F.Fab")
			(hide yes)
			(effects
				(font
					(size 1 1)
					(thickness 0.15)
				)
			)
		)
		(property "License" "Apache-2.0"
			(at 378.2 293.18 0)
			(layer "F.Fab")
			(hide yes)
			(effects
				(font
					(size 1 1)
					(thickness 0.15)
				)
			)
		)
		(property "MPN" ""
			(at 378.2 293.18 0)
			(layer "F.Fab")
			(hide yes)
			(effects
				(font
					(size 1 1)
					(thickness 0.15)
				)
			)
		)
		(property "Manufacturer" ""
			(at 378.2 293.18 0)
			(layer "F.Fab")
			(hide yes)
			(effects
				(font
					(size 1 1)
					(thickness 0.15)
				)
			)
		)
		(sheetname "DC-DC Converters")
		(sheetfile "dc-dc.kicad_sch")
		(attr exclude_from_pos_files)
		(net_tie_pad_groups "1, 2")
		(fp_poly
			(pts
				(xy -0.0635 -0.0635) (xy 0.0625 -0.0635) (xy 0.0625 0.0635) (xy -0.0635 0.0635)
			)
			(stroke
				(width 0)
				(type solid)
			)
			(fill yes)
			(layer "F.Cu")
		)
		(pad "1" smd roundrect
			(at -0.127 0)
			(size 0.127 0.127)
			(layers "F.Cu")
			(roundrect_rratio 0.5)
			(chamfer_ratio 0)
			(chamfer top_left bottom_left)
			(net 1 "GND")
			(pinfunction "1")
			(pintype "passive")
		)
		(pad "2" smd roundrect
			(at 0.126 0 180)
			(size 0.127 0.127)
			(layers "F.Cu")
			(roundrect_rratio 0.5)
			(chamfer_ratio 0)
			(chamfer top_left bottom_left)
			(net 1215 "/DC-DC Converters/SENSE_1V35_N")
			(pinfunction "2")
			(pintype "passive")
		)
	)
	(footprint "antmicro-footprints:C_0603_1608Metric"
		(layer "F.Cu")
		(at 164.4 172.8 -90)
		(descr "Capacitor SMD 0603")
		(tags "capacitor 0603")
		(property "Reference" "C328"
			(at -1.36 -1.37 90)
			(layer "F.SilkS")
			(effects
				(font
					(size 0.7 0.7)
					(thickness 0.15)
				)
				(justify right bottom)
			)
		)
		(property "Value" "C_22u_0603"
			(at 0 1.6 90)
			(layer "F.Fab")
			(effects
				(font
					(size 0.7 0.7)
					(thickness 0.15)
				)
				(justify right bottom)
			)
		)
		(property "Description" "SMD Multilayer Ceramic Capacitor, 22 µF, 6.3 V, 0603 [1608 Metric], ± 20%, X5R, GRM Series"
			(at 0 0 270)
			(layer "F.Fab")
			(hide yes)
			(effects
				(font
					(size 1.27 1.27)
					(thickness 0.15)
				)
			)
		)
		(property "Author" "Antmicro"
			(at -8.4 337.2 0)
			(layer "F.Fab")
			(hide yes)
			(effects
				(font
					(size 1 1)
					(thickness 0.15)
				)
			)
		)
		(property "Dielectric" ""
			(at -8.4 337.2 0)
			(layer "F.Fab")
			(hide yes)
			(effects
				(font
					(size 1 1)
					(thickness 0.15)
				)
			)
		)
		(property "License" "Apache-2.0"
			(at -8.4 337.2 0)
			(layer "F.Fab")
			(hide yes)
			(effects
				(font
					(size 1 1)
					(thickness 0.15)
				)
			)
		)
		(property "MPN" "GRM188R60J226MEA0D"
			(at -8.4 337.2 0)
			(layer "F.Fab")
			(hide yes)
			(effects
				(font
					(size 1 1)
					(thickness 0.15)
				)
			)
		)
		(property "Manufacturer" "Murata"
			(at -8.4 337.2 0)
			(layer "F.Fab")
			(hide yes)
			(effects
				(font
					(size 1 1)
					(thickness 0.15)
				)
			)
		)
		(property "Val" "22u"
			(at -8.4 337.2 0)
			(layer "F.Fab")
			(hide yes)
			(effects
				(font
					(size 1 1)
					(thickness 0.15)
				)
			)
		)
		(property "Voltage" ""
			(at -8.4 337.2 0)
			(layer "F.Fab")
			(hide yes)
			(effects
				(font
					(size 1 1)
					(thickness 0.15)
				)
			)
		)
		(sheetname "DC-DC Converters")
		(sheetfile "dc-dc.kicad_sch")
		(attr smd)
		(fp_line
			(start -0.15 0.4)
			(end 0.15 0.4)
			(stroke
				(width 0.15)
				(type solid)
			)
			(layer "F.SilkS")
		)
		(fp_line
			(start -0.15 -0.4)
			(end 0.15 -0.4)
			(stroke
				(width 0.15)
				(type solid)
			)
			(layer "F.SilkS")
		)
		(fp_rect
			(start -1.25 -0.65)
			(end 1.25 0.65)
			(stroke
				(width 0.05)
				(type solid)
			)
			(fill no)
			(layer "F.CrtYd")
		)
		(fp_rect
			(start -0.8 -0.4)
			(end 0.8 0.4)
			(stroke
				(width 0.15)
				(type solid)
			)
			(fill no)
			(layer "F.Fab")
		)
		(pad "1" smd roundrect
			(at -0.7 0 270)
			(size 0.8 1)
			(layers "F.Cu" "F.Mask" "F.Paste")
			(roundrect_rratio 0.2)
			(net 1 "GND")
			(pintype "passive")
		)
		(pad "2" smd roundrect
			(at 0.7 0 270)
			(size 0.8 1)
			(layers "F.Cu" "F.Mask" "F.Paste")
			(roundrect_rratio 0.2)
			(net 737 "/DC-DC Converters/1V2_local")
			(pintype "passive")
		)
	)
	(footprint "antmicro-footprints:MPS_QFN-14_MP8869S"
		(layer "F.Cu")
		(at 194.598001 161.898999 180)
		(property "Reference" "U37"
			(at 3.898001 1.948999 180)
			(layer "F.SilkS")
			(effects
				(font
					(size 0.7 0.7)
					(thickness 0.15)
				)
				(justify left bottom)
			)
		)
		(property "Value" "MP8869S"
			(at -5.5 3.43 180)
			(layer "F.Fab")
			(effects
				(font
					(size 0.7 0.7)
					(thickness 0.15)
				)
				(justify left bottom)
			)
		)
		(property "Description" "DC-DC Switching Synchronous Buck Regulator, 2.85V-18V in, 600mV to 5.5V out, 12A, 500kHz, QFN-14"
			(at 0 0 180)
			(layer "F.Fab")
			(hide yes)
			(effects
				(font
					(size 1.27 1.27)
					(thickness 0.15)
				)
			)
		)
		(property "Author" "Antmicro"
			(at 389.196002 323.797998 0)
			(layer "F.Fab")
			(hide yes)
			(effects
				(font
					(size 1 1)
					(thickness 0.15)
				)
			)
		)
		(property "License" "Apache-2.0"
			(at 389.196002 323.797998 0)
			(layer "F.Fab")
			(hide yes)
			(effects
				(font
					(size 1 1)
					(thickness 0.15)
				)
			)
		)
		(property "MPN" "MP8869SGL-P"
			(at 389.196002 323.797998 0)
			(layer "F.Fab")
			(hide yes)
			(effects
				(font
					(size 1 1)
					(thickness 0.15)
				)
			)
		)
		(property "Manufacturer" "Monolithic Power Systems"
			(at 389.196002 323.797998 0)
			(layer "F.Fab")
			(hide yes)
			(effects
				(font
					(size 1 1)
					(thickness 0.15)
				)
			)
		)
		(sheetname "DC-DC Converters")
		(sheetfile "dc-dc.kicad_sch")
		(attr smd)
		(fp_line
			(start 1.675 0.981)
			(end 1.675 2.171)
			(stroke
				(width 0.15)
				(type solid)
			)
			(layer "F.SilkS")
		)
		(fp_line
			(start 1.675 -2.173)
			(end 1.675 -0.983)
			(stroke
				(width 0.15)
				(type solid)
			)
			(layer "F.SilkS")
		)
		(fp_line
			(start -1.678 2.171)
			(end -1.678 0.481)
			(stroke
				(width 0.15)
				(type solid)
			)
			(layer "F.SilkS")
		)
		(fp_line
			(start -1.678 -0.959)
			(end -1.678 -2.173)
			(stroke
				(width 0.15)
				(type solid)
			)
			(layer "F.SilkS")
		)
		(fp_circle
			(center -2.361 -0.5)
			(end -2.311 -0.5)
			(stroke
				(width 0.15)
				(type solid)
			)
			(fill yes)
			(layer "F.SilkS")
		)
		(fp_rect
			(start -2.061 -2.55)
			(end 2.06 2.548)
			(stroke
				(width 0.05)
				(type solid)
			)
			(fill no)
			(layer "F.CrtYd")
		)
		(fp_line
			(start 1.548 2.043)
			(end 1.548 -2.045)
			(stroke
				(width 0.15)
				(type solid)
			)
			(layer "F.Fab")
		)
		(fp_line
			(start 1.548 -2.045)
			(end -1.551 -2.045)
			(stroke
				(width 0.15)
				(type solid)
			)
			(layer "F.Fab")
		)
		(fp_line
			(start -1.541 -1.841)
			(end -1.341 -2.04)
			(stroke
				(width 0.15)
				(type solid)
			)
			(layer "F.Fab")
		)
		(fp_line
			(start -1.551 2.043)
			(end 1.548 2.043)
			(stroke
				(width 0.15)
				(type solid)
			)
			(layer "F.Fab")
		)
		(fp_line
			(start -1.551 -2.045)
			(end -1.551 2.043)
			(stroke
				(width 0.15)
				(type solid)
			)
			(layer "F.Fab")
		)
		(pad "1" smd custom
			(at -1.401 -0.5 180)
			(size 0.799998 0.249998)
			(layers "F.Cu" "F.Mask" "F.Paste")
			(net 745 "/DC-DC Converters/1V0_BS")
			(pinfunction "BST")
			(pintype "unspecified")
			(options
				(clearance outline)
				(anchor rect)
			)
			(primitives
				(gr_poly
					(pts
						(xy -0.400002 -0.125001) (xy -0.400002 0.124999) (xy 0.499998 0.124999) (xy 0.499998 -0.000001)
						(xy 0.374998 -0.125001)
					)
					(width 0.1)
					(fill yes)
				)
			)
		)
		(pad "2" smd rect
			(at -0.851 0 180)
			(size 1.9 0.3)
			(layers "F.Cu" "F.Mask" "F.Paste")
			(net 746 "/DC-DC Converters/1V0_SW")
			(pinfunction "SW")
			(pintype "output")
		)
		(pad "3" smd rect
			(at -1.002 1.848 270)
			(size 0.9 0.25)
			(layers "F.Cu" "F.Mask" "F.Paste")
			(net 1338 "/I2C.SCL")
			(pinfunction "SCL")
			(pintype "unspecified")
		)
		(pad "4" smd rect
			(at -0.5 1.848 270)
			(size 0.9 0.25)
			(layers "F.Cu" "F.Mask" "F.Paste")
			(net 1336 "/I2C.SDA")
			(pinfunction "SDA")
			(pintype "unspecified")
		)
		(pad "5" smd rect
			(at 0 1.848 270)
			(size 0.9 0.25)
			(layers "F.Cu" "F.Mask" "F.Paste")
			(net 966 "/DC-DC Converters/EN1")
			(pinfunction "EN")
			(pintype "unspecified")
		)
		(pad "6" smd rect
			(at 0.498 1.848 270)
			(size 0.9 0.25)
			(layers "F.Cu" "F.Mask" "F.Paste")
			(net 1 "GND")
			(pinfunction "A0")
			(pintype "unspecified")
		)
		(pad "7" smd rect
			(at 0.999 1.848 270)
			(size 0.9 0.25)
			(layers "F.Cu" "F.Mask" "F.Paste")
			(net 1389 "/SUP_MCU.PG_VCCINT")
			(pinfunction "PG")
			(pintype "unspecified")
		)
		(pad "8" smd custom
			(at 0.849 0.498 180)
			(size 0.127 0.127)
			(layers "F.Cu" "F.Mask" "F.Paste")
			(net 1 "GND")
			(pinfunction "PGND")
			(pintype "power_in")
			(options
				(clearance outline)
				(anchor rect)
			)
			(primitives
				(gr_poly
					(pts
						(xy 0.95 0.15) (xy 0.95 -0.15) (xy -0.55 -0.15) (xy -0.65 -0.05) (xy -0.95 -0.05) (xy -0.95 0.15)
					)
					(width 0.1)
					(fill yes)
				)
			)
		)
		(pad "9" smd custom
			(at 0.849 -0.5 180)
			(size 0.127 0.127)
			(layers "F.Cu" "F.Mask" "F.Paste")
			(net 702 "VDC")
			(pinfunction "VIN")
			(pintype "power_in")
			(options
				(clearance outline)
				(anchor rect)
			)
			(primitives
				(gr_poly
					(pts
						(xy 0.95 -0.15) (xy 0.95 0.15) (xy -0.55 0.15) (xy -0.65 0.05) (xy -0.95 0.05) (xy -0.95 -0.15)
					)
					(width 0.1)
					(fill yes)
				)
			)
		)
		(pad "10" smd rect
			(at 0.999 -1.851 270)
			(size 0.9 0.25)
			(layers "F.Cu" "F.Mask" "F.Paste")
			(net 751 "/DC-DC Converters/1V0_REG")
			(pinfunction "VOUT")
			(pintype "unspecified")
		)
		(pad "11" smd rect
			(at 0.498 -1.851 270)
			(size 0.9 0.25)
			(layers "F.Cu" "F.Mask" "F.Paste")
			(net 970 "/DC-DC Converters/1V0_FB")
			(pinfunction "FB")
			(pintype "unspecified")
		)
		(pad "12" smd rect
			(at 0 -1.851 270)
			(size 0.9 0.25)
			(layers "F.Cu" "F.Mask" "F.Paste")
			(net 749 "/DC-DC Converters/1V0_SS")
			(pinfunction "SS")
			(pintype "unspecified")
		)
		(pad "13" smd rect
			(at -0.5 -1.851 270)
			(size 0.9 0.25)
			(layers "F.Cu" "F.Mask" "F.Paste")
			(net 741 "/DC-DC Converters/1V0_VCC")
			(pinfunction "VCC")
			(pintype "power_out")
		)
		(pad "14" smd rect
			(at -1.002 -1.851 270)
			(size 0.9 0.25)
			(layers "F.Cu" "F.Mask" "F.Paste")
			(net 1 "GND")
			(pinfunction "AGND")
			(pintype "power_in")
		)
	)
	(footprint "antmicro-footprints:SC70-3"
		(layer "F.Cu")
		(at 210.1 78.78 90)
		(property "Reference" "Q2"
			(at -2.32 0.2 180)
			(layer "F.SilkS")
			(effects
				(font
					(size 0.7 0.7)
					(thickness 0.15)
				)
				(justify left bottom)
			)
		)
		(property "Value" "BSS138PW"
			(at 0 2.3 90)
			(layer "F.Fab")
			(effects
				(font
					(size 0.7 0.7)
					(thickness 0.15)
				)
				(justify left bottom)
			)
		)
		(property "Description" "Power MOSFET, N Channel, 60 V, 320 mA, 0.9 ohm, SOT-323, Surface Mount"
			(at 0 0 90)
			(layer "F.Fab")
			(hide yes)
			(effects
				(font
					(size 1.27 1.27)
					(thickness 0.15)
				)
			)
		)
		(property "Author" "Antmicro"
			(at 288.88 -131.32 0)
			(layer "F.Fab")
			(hide yes)
			(effects
				(font
					(size 1 1)
					(thickness 0.15)
				)
			)
		)
		(property "License" "Apache-2.0"
			(at 288.88 -131.32 0)
			(layer "F.Fab")
			(hide yes)
			(effects
				(font
					(size 1 1)
					(thickness 0.15)
				)
			)
		)
		(property "MPN" "BSS138PW"
			(at 288.88 -131.32 0)
			(layer "F.Fab")
			(hide yes)
			(effects
				(font
					(size 1 1)
					(thickness 0.15)
				)
			)
		)
		(property "Manufacturer" "Nexperia"
			(at 288.88 -131.32 0)
			(layer "F.Fab")
			(hide yes)
			(effects
				(font
					(size 1 1)
					(thickness 0.15)
				)
			)
		)
		(sheetname "FPGA Config")
		(sheetfile "fpga-config.kicad_sch")
		(attr smd)
		(fp_line
			(start -0.3 -1)
			(end 0.627 -0.999)
			(stroke
				(width 0.15)
				(type solid)
			)
			(layer "F.SilkS")
		)
		(fp_line
			(start 0.627 -0.6)
			(end 0.627 -0.999)
			(stroke
				(width 0.15)
				(type solid)
			)
			(layer "F.SilkS")
		)
		(fp_line
			(start 0.627 0.6)
			(end 0.627 1.001)
			(stroke
				(width 0.15)
				(type solid)
			)
			(layer "F.SilkS")
		)
		(fp_line
			(start -0.3 1)
			(end 0.627 1.001)
			(stroke
				(width 0.15)
				(type solid)
			)
			(layer "F.SilkS")
		)
		(fp_line
			(start 0.9 -1.3)
			(end 0.9 -0.4)
			(stroke
				(width 0.05)
				(type solid)
			)
			(layer "F.CrtYd")
		)
		(fp_line
			(start -0.9 -1.3)
			(end 0.9 -1.3)
			(stroke
				(width 0.05)
				(type solid)
			)
			(layer "F.CrtYd")
		)
		(fp_line
			(start -0.9 -1.3)
			(end -0.9 -1)
			(stroke
				(width 0.05)
				(type solid)
			)
			(layer "F.CrtYd")
		)
		(fp_line
			(start -0.9 -1)
			(end -1.4 -1)
			(stroke
				(width 0.05)
				(type solid)
			)
			(layer "F.CrtYd")
		)
		(fp_line
			(start 1.4 -0.4)
			(end 1.4 0.4)
			(stroke
				(width 0.05)
				(type solid)
			)
			(layer "F.CrtYd")
		)
		(fp_line
			(start 0.9 -0.4)
			(end 1.4 -0.4)
			(stroke
				(width 0.05)
				(type solid)
			)
			(layer "F.CrtYd")
		)
		(fp_line
			(start 1.4 0.4)
			(end 0.9 0.4)
			(stroke
				(width 0.05)
				(type solid)
			)
			(layer "F.CrtYd")
		)
		(fp_line
			(start 0.9 0.4)
			(end 0.9 1.3)
			(stroke
				(width 0.05)
				(type solid)
			)
			(layer "F.CrtYd")
		)
		(fp_line
			(start -0.9 1)
			(end -1.4 1)
			(stroke
				(width 0.05)
				(type solid)
			)
			(layer "F.CrtYd")
		)
		(fp_line
			(start -1.4 1)
			(end -1.4 -1)
			(stroke
				(width 0.05)
				(type solid)
			)
			(layer "F.CrtYd")
		)
		(fp_line
			(start 0.9 1.3)
			(end -0.9 1.3)
			(stroke
				(width 0.05)
				(type solid)
			)
			(layer "F.CrtYd")
		)
		(fp_line
			(start -0.9 1.3)
			(end -0.9 1)
			(stroke
				(width 0.05)
				(type solid)
			)
			(layer "F.CrtYd")
		)
		(fp_rect
			(start -0.623 -0.999)
			(end 0.627 1.001)
			(stroke
				(width 0.15)
				(type solid)
			)
			(fill no)
			(layer "F.Fab")
		)
		(pad "1" smd rect
			(at -1.051 -0.65 180)
			(size 0.6 0.6)
			(layers "F.Cu" "F.Mask" "F.Paste")
			(net 257 "/FPGA Config/INIT_B")
			(pinfunction "G")
			(pintype "bidirectional")
		)
		(pad "2" smd rect
			(at -1.051 0.65 180)
			(size 0.6 0.6)
			(layers "F.Cu" "F.Mask" "F.Paste")
			(net 1 "GND")
			(pinfunction "S")
			(pintype "bidirectional")
		)
		(pad "3" smd rect
			(at 1.05 0 180)
			(size 0.6 0.6)
			(layers "F.Cu" "F.Mask" "F.Paste")
			(net 336 "Net-(Q2-D)")
			(pinfunction "D")
			(pintype "bidirectional")
		)
	)
	(footprint "antmicro-footprints:R_0402_1005Metric"
		(layer "F.Cu")
		(at 260.3 133.7 -90)
		(descr "Resistor SMD 0402")
		(tags "resistor SMD 0402")
		(property "Reference" "R158"
			(at 0.9 0.5 270)
			(layer "F.SilkS")
			(effects
				(font
					(size 0.7 0.7)
					(thickness 0.15)
				)
				(justify left bottom)
			)
		)
		(property "Value" "R_10k_0402"
			(at 0 1.4 270)
			(layer "F.Fab")
			(effects
				(font
					(size 0.7 0.7)
					(thickness 0.15)
				)
				(justify left bottom)
			)
		)
		(property "Description" "SMD Chip Resistor, 10 kohm, ± 1%, 62.5 mW, 0402 [1005 Metric], Thick Film, General Purpose"
			(at 0 0 270)
			(layer "F.Fab")
			(hide yes)
			(effects
				(font
					(size 1.27 1.27)
					(thickness 0.15)
				)
			)
		)
		(property "Author" "Antmicro"
			(at 126.6 394 0)
			(layer "F.Fab")
			(hide yes)
			(effects
				(font
					(size 1 1)
					(thickness 0.15)
				)
			)
		)
		(property "License" "Apache-2.0"
			(at 126.6 394 0)
			(layer "F.Fab")
			(hide yes)
			(effects
				(font
					(size 1 1)
					(thickness 0.15)
				)
			)
		)
		(property "MPN" "CR0402-FX-1002GLF"
			(at 126.6 394 0)
			(layer "F.Fab")
			(hide yes)
			(effects
				(font
					(size 1 1)
					(thickness 0.15)
				)
			)
		)
		(property "Manufacturer" "Bourns"
			(at 126.6 394 0)
			(layer "F.Fab")
			(hide yes)
			(effects
				(font
					(size 1 1)
					(thickness 0.15)
				)
			)
		)
		(property "Tolerance" "1%"
			(at 126.6 394 0)
			(layer "F.Fab")
			(hide yes)
			(effects
				(font
					(size 1 1)
					(thickness 0.15)
				)
			)
		)
		(property "Val" "10k"
			(at 126.6 394 0)
			(layer "F.Fab")
			(hide yes)
			(effects
				(font
					(size 1 1)
					(thickness 0.15)
				)
			)
		)
		(sheetname "USB PHY")
		(sheetfile "usb-phy.kicad_sch")
		(attr smd)
		(fp_rect
			(start -0.925 -0.47)
			(end 0.925 0.47)
			(stroke
				(width 0.05)
				(type default)
			)
			(fill no)
			(layer "F.CrtYd")
		)
		(fp_rect
			(start -0.5 -0.25)
			(end 0.5 0.25)
			(stroke
				(width 0.15)
				(type solid)
			)
			(fill no)
			(layer "F.Fab")
		)
		(pad "1" smd roundrect
			(at -0.48 0 270)
			(size 0.59 0.64)
			(layers "F.Cu" "F.Mask" "F.Paste")
			(roundrect_rratio 0.25)
			(net 707 "/USB PHY/FTDI_3V3")
			(pintype "passive")
		)
		(pad "2" smd roundrect
			(at 0.48 0 270)
			(size 0.59 0.64)
			(layers "F.Cu" "F.Mask" "F.Paste")
			(roundrect_rratio 0.25)
			(net 918 "/USB PHY/FTDI_PWREN")
			(pintype "passive")
		)
	)
	(footprint "antmicro-footprints:SC70-3"
		(layer "F.Cu")
		(at 258.4 81.4)
		(property "Reference" "Q16"
			(at -1.6 1.1 90)
			(layer "F.SilkS")
			(effects
				(font
					(size 0.7 0.7)
					(thickness 0.15)
				)
				(justify left bottom)
			)
		)
		(property "Value" "BSS138PW"
			(at 0 2.3 0)
			(layer "F.Fab")
			(effects
				(font
					(size 0.7 0.7)
					(thickness 0.15)
				)
				(justify left bottom)
			)
		)
		(property "Description" "Power MOSFET, N Channel, 60 V, 320 mA, 0.9 ohm, SOT-323, Surface Mount"
			(at 0 0 0)
			(layer "F.Fab")
			(hide yes)
			(effects
				(font
					(size 1.27 1.27)
					(thickness 0.15)
				)
			)
		)
		(property "Author" "Antmicro"
			(at 0 0 0)
			(layer "F.Fab")
			(hide yes)
			(effects
				(font
					(size 1 1)
					(thickness 0.15)
				)
			)
		)
		(property "License" "Apache-2.0"
			(at 0 0 0)
			(layer "F.Fab")
			(hide yes)
			(effects
				(font
					(size 1 1)
					(thickness 0.15)
				)
			)
		)
		(property "MPN" "BSS138PW"
			(at 0 0 0)
			(layer "F.Fab")
			(hide yes)
			(effects
				(font
					(size 1 1)
					(thickness 0.15)
				)
			)
		)
		(property "Manufacturer" "Nexperia"
			(at 0 0 0)
			(layer "F.Fab")
			(hide yes)
			(effects
				(font
					(size 1 1)
					(thickness 0.15)
				)
			)
		)
		(sheetname "User GPIO + LED + button + DIP switch")
		(sheetfile "user-gpio.kicad_sch")
		(attr smd)
		(fp_line
			(start -0.3 -1)
			(end 0.627 -0.999)
			(stroke
				(width 0.15)
				(type solid)
			)
			(layer "F.SilkS")
		)
		(fp_line
			(start -0.3 1)
			(end 0.627 1.001)
			(stroke
				(width 0.15)
				(type solid)
			)
			(layer "F.SilkS")
		)
		(fp_line
			(start 0.627 -0.6)
			(end 0.627 -0.999)
			(stroke
				(width 0.15)
				(type solid)
			)
			(layer "F.SilkS")
		)
		(fp_line
			(start 0.627 0.6)
			(end 0.627 1.001)
			(stroke
				(width 0.15)
				(type solid)
			)
			(layer "F.SilkS")
		)
		(fp_line
			(start -1.4 1)
			(end -1.4 -1)
			(stroke
				(width 0.05)
				(type solid)
			)
			(layer "F.CrtYd")
		)
		(fp_line
			(start -0.9 -1.3)
			(end -0.9 -1)
			(stroke
				(width 0.05)
				(type solid)
			)
			(layer "F.CrtYd")
		)
		(fp_line
			(start -0.9 -1.3)
			(end 0.9 -1.3)
			(stroke
				(width 0.05)
				(type solid)
			)
			(layer "F.CrtYd")
		)
		(fp_line
			(start -0.9 -1)
			(end -1.4 -1)
			(stroke
				(width 0.05)
				(type solid)
			)
			(layer "F.CrtYd")
		)
		(fp_line
			(start -0.9 1)
			(end -1.4 1)
			(stroke
				(width 0.05)
				(type solid)
			)
			(layer "F.CrtYd")
		)
		(fp_line
			(start -0.9 1.3)
			(end -0.9 1)
			(stroke
				(width 0.05)
				(type solid)
			)
			(layer "F.CrtYd")
		)
		(fp_line
			(start 0.9 -1.3)
			(end 0.9 -0.4)
			(stroke
				(width 0.05)
				(type solid)
			)
			(layer "F.CrtYd")
		)
		(fp_line
			(start 0.9 -0.4)
			(end 1.4 -0.4)
			(stroke
				(width 0.05)
				(type solid)
			)
			(layer "F.CrtYd")
		)
		(fp_line
			(start 0.9 0.4)
			(end 0.9 1.3)
			(stroke
				(width 0.05)
				(type solid)
			)
			(layer "F.CrtYd")
		)
		(fp_line
			(start 0.9 1.3)
			(end -0.9 1.3)
			(stroke
				(width 0.05)
				(type solid)
			)
			(layer "F.CrtYd")
		)
		(fp_line
			(start 1.4 -0.4)
			(end 1.4 0.4)
			(stroke
				(width 0.05)
				(type solid)
			)
			(layer "F.CrtYd")
		)
		(fp_line
			(start 1.4 0.4)
			(end 0.9 0.4)
			(stroke
				(width 0.05)
				(type solid)
			)
			(layer "F.CrtYd")
		)
		(fp_rect
			(start -0.623 -0.999)
			(end 0.627 1.001)
			(stroke
				(width 0.15)
				(type solid)
			)
			(fill no)
			(layer "F.Fab")
		)
		(pad "1" smd rect
			(at -1.051 -0.65 90)
			(size 0.6 0.6)
			(layers "F.Cu" "F.Mask" "F.Paste")
			(net 1307 "/USER_IO.LED_BLUE")
			(pinfunction "G")
			(pintype "passive")
		)
		(pad "2" smd rect
			(at -1.051 0.65 90)
			(size 0.6 0.6)
			(layers "F.Cu" "F.Mask" "F.Paste")
			(net 1 "GND")
			(pinfunction "S")
			(pintype "passive")
		)
		(pad "3" smd rect
			(at 1.05 0 90)
			(size 0.6 0.6)
			(layers "F.Cu" "F.Mask" "F.Paste")
			(net 787 "Net-(D25-C)")
			(pinfunction "D")
			(pintype "passive")
		)
	)
	(footprint "antmicro-footprints:SOT-23-6"
		(layer "F.Cu")
		(at 159.95 187.1)
		(property "Reference" "U33"
			(at -1.02 2.79 0)
			(layer "F.SilkS")
			(effects
				(font
					(size 0.7 0.7)
					(thickness 0.15)
				)
				(justify left bottom)
			)
		)
		(property "Value" "MAX16150A_SOT"
			(at -1.75 2.75 0)
			(layer "F.Fab")
			(effects
				(font
					(size 0.7 0.7)
					(thickness 0.15)
				)
				(justify left bottom)
			)
		)
		(property "Description" "Push Button On/Off Controller, Latched Output, 1.3 to 5.5 V Supply, 50 ms Debounce Time, SOT-23-6"
			(at 0 0 0)
			(layer "F.Fab")
			(hide yes)
			(effects
				(font
					(size 1.27 1.27)
					(thickness 0.15)
				)
			)
		)
		(property "Author" "Antmicro"
			(at 0 0 0)
			(layer "F.Fab")
			(hide yes)
			(effects
				(font
					(size 1 1)
					(thickness 0.15)
				)
			)
		)
		(property "License" "Apache-2.0"
			(at 0 0 0)
			(layer "F.Fab")
			(hide yes)
			(effects
				(font
					(size 1 1)
					(thickness 0.15)
				)
			)
		)
		(property "MPN" "MAX16150AUT+T"
			(at 0 0 0)
			(layer "F.Fab")
			(hide yes)
			(effects
				(font
					(size 1 1)
					(thickness 0.15)
				)
			)
		)
		(property "Manufacturer" "Maxim Integrated Products"
			(at 0 0 0)
			(layer "F.Fab")
			(hide yes)
			(effects
				(font
					(size 1 1)
					(thickness 0.15)
				)
			)
		)
		(sheetname "DC-DC Converters")
		(sheetfile "dc-dc.kicad_sch")
		(attr smd)
		(fp_line
			(start -1.45 -0.7)
			(end -1.45 -0.4)
			(stroke
				(width 0.12)
				(type solid)
			)
			(layer "F.SilkS")
		)
		(fp_line
			(start -1.45 0.7)
			(end -1.45 0.4)
			(stroke
				(width 0.12)
				(type solid)
			)
			(layer "F.SilkS")
		)
		(fp_line
			(start -1.3 -0.7)
			(end -1.45 -0.7)
			(stroke
				(width 0.12)
				(type solid)
			)
			(layer "F.SilkS")
		)
		(fp_line
			(start 1.3 -0.7)
			(end 1.45 -0.7)
			(stroke
				(width 0.12)
				(type solid)
			)
			(layer "F.SilkS")
		)
		(fp_line
			(start 1.3 0.7)
			(end 1.45 0.7)
			(stroke
				(width 0.12)
				(type solid)
			)
			(layer "F.SilkS")
		)
		(fp_line
			(start 1.45 -0.7)
			(end 1.45 -0.4)
			(stroke
				(width 0.12)
				(type solid)
			)
			(layer "F.SilkS")
		)
		(fp_line
			(start 1.45 0.7)
			(end 1.45 0.4)
			(stroke
				(width 0.12)
				(type solid)
			)
			(layer "F.SilkS")
		)
		(fp_rect
			(start -1.55 -1.85)
			(end 1.55 1.75)
			(stroke
				(width 0.05)
				(type solid)
			)
			(fill no)
			(layer "F.CrtYd")
		)
		(fp_line
			(start -1.5 -0.7)
			(end 1.5 -0.7)
			(stroke
				(width 0.1)
				(type solid)
			)
			(layer "F.Fab")
		)
		(fp_line
			(start -1.5 0.7)
			(end -1.5 -0.7)
			(stroke
				(width 0.1)
				(type solid)
			)
			(layer "F.Fab")
		)
		(fp_line
			(start 1.5 -0.7)
			(end 1.5 0.7)
			(stroke
				(width 0.1)
				(type solid)
			)
			(layer "F.Fab")
		)
		(fp_line
			(start 1.5 0.7)
			(end -1.5 0.7)
			(stroke
				(width 0.1)
				(type solid)
			)
			(layer "F.Fab")
		)
		(fp_text user "."
			(at -1.4 1.2 180)
			(layer "F.SilkS")
			(effects
				(font
					(size 1 1)
					(thickness 0.15)
				)
			)
		)
		(pad "1" smd roundrect
			(at -0.954 1.1)
			(size 0.55 1)
			(layers "F.Cu" "F.Mask" "F.Paste")
			(roundrect_rratio 0.15)
			(net 974 "/DC-DC Converters/~{PB_CTRL_IN}")
			(pinfunction "~{PB_IN}")
			(pintype "input")
		)
		(pad "2" smd roundrect
			(at -0.003 1.1)
			(size 0.55 1)
			(layers "F.Cu" "F.Mask" "F.Paste")
			(roundrect_rratio 0.15)
			(net 1 "GND")
			(pinfunction "GND")
			(pintype "power_in")
		)
		(pad "3" smd roundrect
			(at 0.947 1.1)
			(size 0.55 1)
			(layers "F.Cu" "F.Mask" "F.Paste")
			(roundrect_rratio 0.15)
			(net 37 "+3V3_AON")
			(pinfunction "VCC")
			(pintype "power_in")
		)
		(pad "4" smd roundrect
			(at 0.947 -1.214)
			(size 0.55 1)
			(layers "F.Cu" "F.Mask" "F.Paste")
			(roundrect_rratio 0.15)
			(net 701 "/DC-DC Converters/PB_CTRL_OUT")
			(pinfunction "OUT")
			(pintype "output")
		)
		(pad "5" smd roundrect
			(at -0.003 -1.214)
			(size 0.55 1)
			(layers "F.Cu" "F.Mask" "F.Paste")
			(roundrect_rratio 0.15)
			(net 577 "/DC-DC Converters/PB_CTRL.~{PB_CTRL_INT}")
			(pinfunction "~{INT}")
			(pintype "output")
		)
		(pad "6" smd roundrect
			(at -0.954 -1.214)
			(size 0.55 1)
			(layers "F.Cu" "F.Mask" "F.Paste")
			(roundrect_rratio 0.15)
			(net 1340 "/SUP_MCU.SW_STATE")
			(pinfunction "~{CLR}")
			(pintype "input")
		)
	)
	(footprint "antmicro-footprints:R_0603_1608Metric"
		(layer "F.Cu")
		(at 152.3 172.7 90)
		(descr "Resistor SMD 0603")
		(tags "resistor SMD 0603")
		(property "Reference" "R288"
			(at 2.975 -1.575 315)
			(unlocked yes)
			(layer "F.SilkS")
			(effects
				(font
					(size 0.7 0.7)
					(thickness 0.15)
				)
				(justify left bottom)
			)
		)
		(property "Value" "R_0R_22.4A_0603"
			(at 0 1.6 90)
			(layer "F.Fab")
			(effects
				(font
					(size 0.7 0.7)
					(thickness 0.15)
				)
				(justify left bottom)
			)
		)
		(property "Description" "SMD Chip Resistor"
			(at 0 0 90)
			(layer "F.Fab")
			(hide yes)
			(effects
				(font
					(size 1.27 1.27)
					(thickness 0.15)
				)
			)
		)
		(property "Author" "Antmicro"
			(at 325 20.4 0)
			(layer "F.Fab")
			(hide yes)
			(effects
				(font
					(size 1 1)
					(thickness 0.15)
				)
			)
		)
		(property "License" "Apache-2.0"
			(at 325 20.4 0)
			(layer "F.Fab")
			(hide yes)
			(effects
				(font
					(size 1 1)
					(thickness 0.15)
				)
			)
		)
		(property "MPN" "PMR03EZPJ000"
			(at 325 20.4 0)
			(layer "F.Fab")
			(hide yes)
			(effects
				(font
					(size 1 1)
					(thickness 0.15)
				)
			)
		)
		(property "Manufacturer" "ROHM Semiconductor"
			(at 325 20.4 0)
			(layer "F.Fab")
			(hide yes)
			(effects
				(font
					(size 1 1)
					(thickness 0.15)
				)
			)
		)
		(property "Max. Curr." "22.4A"
			(at 325 20.4 0)
			(layer "F.Fab")
			(hide yes)
			(effects
				(font
					(size 1 1)
					(thickness 0.15)
				)
			)
		)
		(property "Tolerance" "template_tolerance"
			(at 325 20.4 0)
			(layer "F.Fab")
			(hide yes)
			(effects
				(font
					(size 1 1)
					(thickness 0.15)
				)
			)
		)
		(property "Val" "0R"
			(at 325 20.4 0)
			(layer "F.Fab")
			(hide yes)
			(effects
				(font
					(size 1 1)
					(thickness 0.15)
				)
			)
		)
		(sheetname "DC-DC Converters")
		(sheetfile "dc-dc.kicad_sch")
		(attr smd)
		(fp_line
			(start -0.15 -0.4)
			(end 0.15 -0.4)
			(stroke
				(width 0.15)
				(type solid)
			)
			(layer "F.SilkS")
		)
		(fp_line
			(start -0.15 0.4)
			(end 0.15 0.4)
			(stroke
				(width 0.15)
				(type solid)
			)
			(layer "F.SilkS")
		)
		(fp_rect
			(start -1.25 -0.65)
			(end 1.25 0.65)
			(stroke
				(width 0.05)
				(type solid)
			)
			(fill no)
			(layer "F.CrtYd")
		)
		(fp_rect
			(start -0.8 -0.4)
			(end 0.8 0.4)
			(stroke
				(width 0.15)
				(type solid)
			)
			(fill no)
			(layer "F.Fab")
		)
		(pad "1" smd roundrect
			(at -0.7 0 90)
			(size 0.8 1)
			(layers "F.Cu" "F.Mask" "F.Paste")
			(roundrect_rratio 0.2)
			(net 738 "/DC-DC Converters/1V7_local")
			(pintype "passive")
		)
		(pad "2" smd roundrect
			(at 0.7 0 90)
			(size 0.8 1)
			(layers "F.Cu" "F.Mask" "F.Paste")
			(roundrect_rratio 0.2)
			(net 743 "/DC-DC Converters/1V7")
			(pintype "passive")
		)
	)
	(footprint "antmicro-footprints:R_0402_1005Metric"
		(layer "F.Cu")
		(at 225.025 121.5)
		(descr "Resistor SMD 0402")
		(tags "resistor SMD 0402")
		(property "Reference" "R78"
			(at -2.975 0.4 0)
			(layer "F.SilkS")
			(effects
				(font
					(size 0.7 0.7)
					(thickness 0.15)
				)
				(justify left bottom)
			)
		)
		(property "Value" "R_0R_0402"
			(at 0 1.4 0)
			(layer "F.Fab")
			(effects
				(font
					(size 0.7 0.7)
					(thickness 0.15)
				)
				(justify left bottom)
			)
		)
		(property "Description" "SMD Chip Resistor, Jumper, 0 ohm, 100 mW, 0402 [1005 Metric], Thick Film, General Purpose"
			(at 0 0 0)
			(layer "F.Fab")
			(hide yes)
			(effects
				(font
					(size 1.27 1.27)
					(thickness 0.15)
				)
			)
		)
		(property "Author" "Antmicro"
			(at 0 0 0)
			(layer "F.Fab")
			(hide yes)
			(effects
				(font
					(size 1 1)
					(thickness 0.15)
				)
			)
		)
		(property "Current" "1A"
			(at 0 0 0)
			(layer "F.Fab")
			(hide yes)
			(effects
				(font
					(size 1 1)
					(thickness 0.15)
				)
			)
		)
		(property "License" "Apache-2.0"
			(at 0 0 0)
			(layer "F.Fab")
			(hide yes)
			(effects
				(font
					(size 1 1)
					(thickness 0.15)
				)
			)
		)
		(property "MPN" "ERJ2GE0R00X"
			(at 0 0 0)
			(layer "F.Fab")
			(hide yes)
			(effects
				(font
					(size 1 1)
					(thickness 0.15)
				)
			)
		)
		(property "Manufacturer" "Panasonic"
			(at 0 0 0)
			(layer "F.Fab")
			(hide yes)
			(effects
				(font
					(size 1 1)
					(thickness 0.15)
				)
			)
		)
		(property "Tolerance" ""
			(at 0 0 0)
			(layer "F.Fab")
			(hide yes)
			(effects
				(font
					(size 1 1)
					(thickness 0.15)
				)
			)
		)
		(property "Val" "0R"
			(at 0 0 0)
			(layer "F.Fab")
			(hide yes)
			(effects
				(font
					(size 1 1)
					(thickness 0.15)
				)
			)
		)
		(sheetname "SPI Flash + SD Card")
		(sheetfile "spi-flash.kicad_sch")
		(attr smd)
		(fp_rect
			(start -0.925 -0.47)
			(end 0.925 0.47)
			(stroke
				(width 0.05)
				(type default)
			)
			(fill no)
			(layer "F.CrtYd")
		)
		(fp_rect
			(start -0.5 -0.25)
			(end 0.5 0.25)
			(stroke
				(width 0.15)
				(type solid)
			)
			(fill no)
			(layer "F.Fab")
		)
		(pad "1" smd roundrect
			(at -0.48 0)
			(size 0.59 0.64)
			(layers "F.Cu" "F.Mask" "F.Paste")
			(roundrect_rratio 0.25)
			(net 403 "/FPGA Bank 14 & 15/SYSTEM_FLASH.DQ2")
			(pintype "passive")
		)
		(pad "2" smd roundrect
			(at 0.48 0)
			(size 0.59 0.64)
			(layers "F.Cu" "F.Mask" "F.Paste")
			(roundrect_rratio 0.25)
			(net 898 "/SPI Flash + SD Card/SYSTEM_FLASH_DQ2")
			(pintype "passive")
		)
	)
	(footprint "antmicro-footprints:R_0402_1005Metric"
		(layer "F.Cu")
		(at 235.915 119.5 180)
		(descr "Resistor SMD 0402")
		(tags "resistor SMD 0402")
		(property "Reference" "R70"
			(at -0.735 -0.35 180)
			(layer "F.SilkS")
			(effects
				(font
					(size 0.7 0.7)
					(thickness 0.15)
				)
				(justify left bottom)
			)
		)
		(property "Value" "R_100R_0402"
			(at 0 1.4 180)
			(layer "F.Fab")
			(effects
				(font
					(size 0.7 0.7)
					(thickness 0.15)
				)
				(justify left bottom)
			)
		)
		(property "Description" "SMD Chip Resistor, 100 ohm, ± 1%, 62.5 mW, 0402 [1005 Metric], Thick Film, General Purpose"
			(at 0 0 180)
			(layer "F.Fab")
			(hide yes)
			(effects
				(font
					(size 1.27 1.27)
					(thickness 0.15)
				)
			)
		)
		(property "Author" "Antmicro"
			(at 471.83 239 0)
			(layer "F.Fab")
			(hide yes)
			(effects
				(font
					(size 1 1)
					(thickness 0.15)
				)
			)
		)
		(property "DNP" "DNP"
			(at 471.83 239 0)
			(layer "F.Fab")
			(hide yes)
			(effects
				(font
					(size 1 1)
					(thickness 0.15)
				)
			)
		)
		(property "License" "Apache-2.0"
			(at 471.83 239 0)
			(layer "F.Fab")
			(hide yes)
			(effects
				(font
					(size 1 1)
					(thickness 0.15)
				)
			)
		)
		(property "MPN" "CR0402-FX-1000GLF"
			(at 471.83 239 0)
			(layer "F.Fab")
			(hide yes)
			(effects
				(font
					(size 1 1)
					(thickness 0.15)
				)
			)
		)
		(property "Manufacturer" "Bourns"
			(at 471.83 239 0)
			(layer "F.Fab")
			(hide yes)
			(effects
				(font
					(size 1 1)
					(thickness 0.15)
				)
			)
		)
		(property "Tolerance" "1%"
			(at 471.83 239 0)
			(layer "F.Fab")
			(hide yes)
			(effects
				(font
					(size 1 1)
					(thickness 0.15)
				)
			)
		)
		(property "Val" "100R"
			(at 471.83 239 0)
			(layer "F.Fab")
			(hide yes)
			(effects
				(font
					(size 1 1)
					(thickness 0.15)
				)
			)
		)
		(property "dnp" ""
			(at 471.83 239 0)
			(layer "F.Fab")
			(hide yes)
			(effects
				(font
					(size 1 1)
					(thickness 0.15)
				)
			)
		)
		(property "exclude_from_bom" ""
			(at 471.83 239 0)
			(layer "F.Fab")
			(hide yes)
			(effects
				(font
					(size 1 1)
					(thickness 0.15)
				)
			)
		)
		(sheetname "SPI Flash + SD Card")
		(sheetfile "spi-flash.kicad_sch")
		(attr smd exclude_from_bom)
		(fp_rect
			(start -0.925 -0.47)
			(end 0.925 0.47)
			(stroke
				(width 0.05)
				(type default)
			)
			(fill no)
			(layer "F.CrtYd")
		)
		(fp_rect
			(start -0.5 -0.25)
			(end 0.5 0.25)
			(stroke
				(width 0.15)
				(type solid)
			)
			(fill no)
			(layer "F.Fab")
		)
		(pad "1" smd roundrect
			(at -0.48 0 180)
			(size 0.59 0.64)
			(layers "F.Cu" "F.Mask" "F.Paste")
			(roundrect_rratio 0.25)
			(net 56 "/FPGA Bank 14 & 15/SYSTEM_FLASH.CLK")
			(pintype "passive")
		)
		(pad "2" smd roundrect
			(at 0.48 0 180)
			(size 0.59 0.64)
			(layers "F.Cu" "F.Mask" "F.Paste")
			(roundrect_rratio 0.25)
			(net 24 "+3V3")
			(pintype "passive")
		)
	)
	(footprint "antmicro-footprints:MP_Pad6mm_Drill3mm"
		(locked yes)
		(layer "F.Cu")
		(at 266.5 186.5)
		(property "Reference" "MH2"
			(at -0.178 4.025 0)
			(layer "F.SilkS")
			(hide yes)
			(effects
				(font
					(size 0.7 0.7)
					(thickness 0.15)
				)
				(justify left bottom)
			)
		)
		(property "Value" "MP_Pad6mm_Drill3mm"
			(at -0.153 -4.153 0)
			(layer "F.Fab")
			(effects
				(font
					(size 0.7 0.7)
					(thickness 0.15)
				)
				(justify left bottom)
			)
		)
		(property "Description" "Mechanical part"
			(at 0 0 0)
			(layer "F.Fab")
			(hide yes)
			(effects
				(font
					(size 1.27 1.27)
					(thickness 0.15)
				)
			)
		)
		(property "Author" "Antmicro"
			(at 0 0 0)
			(layer "F.Fab")
			(hide yes)
			(effects
				(font
					(size 1 1)
					(thickness 0.15)
				)
			)
		)
		(property "License" "Apache-2.0"
			(at 0 0 0)
			(layer "F.Fab")
			(hide yes)
			(effects
				(font
					(size 1 1)
					(thickness 0.15)
				)
			)
		)
		(property "MPN" ""
			(at 0 0 0)
			(layer "F.Fab")
			(hide yes)
			(effects
				(font
					(size 1 1)
					(thickness 0.15)
				)
			)
		)
		(property "Manufacturer" ""
			(at 0 0 0)
			(layer "F.Fab")
			(hide yes)
			(effects
				(font
					(size 1 1)
					(thickness 0.15)
				)
			)
		)
		(property "exclude_from_bom" ""
			(at 0 0 0)
			(layer "F.Fab")
			(hide yes)
			(effects
				(font
					(size 1 1)
					(thickness 0.15)
				)
			)
		)
		(sheetfile "k410t-devboard.kicad_sch")
		(attr exclude_from_pos_files exclude_from_bom)
		(pad "1" thru_hole circle
			(at 0 0)
			(size 6 6)
			(drill 3)
			(layers "*.Cu" "*.Mask")
			(remove_unused_layers no)
			(net 1 "GND")
			(pintype "passive")
		)
	)
	(footprint "antmicro-footprints:SW_DIP_SPSTx08_Slide_Copal_CVS-08xB_W5.9mm_P1mm"
		(layer "F.Cu")
		(at 179.27 185.69 -90)
		(descr "SMD 8x-dip-switch SPST Copal_CVS-08xB, Slide, row spacing 5.9 mm (232 mils), body size  (see http://www.nidec-copal-electronics.com/e/catalog/switch/cvs.pdf)")
		(tags "SMD DIP Switch SPST Slide 5.9mm 232mil")
		(property "Reference" "SW3"
			(at -3.74 1.17 180)
			(layer "F.SilkS")
			(effects
				(font
					(size 0.7 0.7)
					(thickness 0.15)
				)
				(justify left bottom)
			)
		)
		(property "Value" "SW_CVS-08TB"
			(at -14.59 6.29 270)
			(layer "F.Fab")
			(effects
				(font
					(size 0.7 0.7)
					(thickness 0.15)
				)
				(justify left bottom)
			)
		)
		(property "Description" "DIP / SIP Switch, 8 Circuits, Slide, Surface Mount, SPST, 6 V, 100 mA"
			(at 0 0 270)
			(layer "F.Fab")
			(hide yes)
			(effects
				(font
					(size 1.27 1.27)
					(thickness 0.15)
				)
			)
		)
		(property "Author" "Antmicro"
			(at -6.42 364.96 0)
			(layer "F.Fab")
			(hide yes)
			(effects
				(font
					(size 1 1)
					(thickness 0.15)
				)
			)
		)
		(property "License" "Apache-2.0"
			(at -6.42 364.96 0)
			(layer "F.Fab")
			(hide yes)
			(effects
				(font
					(size 1 1)
					(thickness 0.15)
				)
			)
		)
		(property "MPN" "CVS-08TB"
			(at -6.42 364.96 0)
			(layer "F.Fab")
			(hide yes)
			(effects
				(font
					(size 1 1)
					(thickness 0.15)
				)
			)
		)
		(property "Manufacturer" "Nidec Components"
			(at -6.42 364.96 0)
			(layer "F.Fab")
			(hide yes)
			(effects
				(font
					(size 1 1)
					(thickness 0.15)
				)
			)
		)
		(sheetname "USB PHY")
		(sheetfile "usb-phy.kicad_sch")
		(attr smd)
		(fp_line
			(start -1.561 4.91)
			(end 1.56 4.91)
			(stroke
				(width 0.15)
				(type solid)
			)
			(layer "F.SilkS")
		)
		(fp_line
			(start -1.561 -4.912)
			(end 1.56 -4.912)
			(stroke
				(width 0.15)
				(type solid)
			)
			(layer "F.SilkS")
		)
		(fp_circle
			(center -3.31 -4.2)
			(end -3.261 -4.2)
			(stroke
				(width 0.15)
				(type solid)
			)
			(fill yes)
			(layer "F.SilkS")
		)
		(fp_rect
			(start -3.601 -5)
			(end 3.598 4.998)
			(stroke
				(width 0.05)
				(type solid)
			)
			(fill no)
			(layer "F.CrtYd")
		)
		(fp_line
			(start -2.351 4.498)
			(end -2.351 -3.5)
			(stroke
				(width 0.15)
				(type solid)
			)
			(layer "F.Fab")
		)
		(fp_line
			(start 2.35 4.498)
			(end -2.351 4.498)
			(stroke
				(width 0.15)
				(type solid)
			)
			(layer "F.Fab")
		)
		(fp_line
			(start -1 3.749)
			(end -0.335 3.749)
			(stroke
				(width 0.15)
				(type solid)
			)
			(layer "F.Fab")
		)
		(fp_line
			(start -1 3.749)
			(end 0.998 3.749)
			(stroke
				(width 0.15)
				(type solid)
			)
			(layer "F.Fab")
		)
		(fp_line
			(start 0.998 3.749)
			(end 0.998 3.249)
			(stroke
				(width 0.15)
				(type solid)
			)
			(layer "F.Fab")
		)
		(fp_line
			(start -1 3.648)
			(end -0.335 3.648)
			(stroke
				(width 0.15)
				(type solid)
			)
			(layer "F.Fab")
		)
		(fp_line
			(start -1 3.548)
			(end -0.335 3.548)
			(stroke
				(width 0.15)
				(type solid)
			)
			(layer "F.Fab")
		)
		(fp_line
			(start -1 3.45)
			(end -0.335 3.45)
			(stroke
				(width 0.15)
				(type solid)
			)
			(layer "F.Fab")
		)
		(fp_line
			(start -1 3.35)
			(end -0.335 3.35)
			(stroke
				(width 0.15)
				(type solid)
			)
			(layer "F.Fab")
		)
		(fp_line
			(start -1 3.249)
			(end -1 3.749)
			(stroke
				(width 0.15)
				(type solid)
			)
			(layer "F.Fab")
		)
		(fp_line
			(start -0.335 3.249)
			(end -0.335 3.749)
			(stroke
				(width 0.15)
				(type solid)
			)
			(layer "F.Fab")
		)
		(fp_line
			(start 0.998 3.249)
			(end -1 3.249)
			(stroke
				(width 0.15)
				(type solid)
			)
			(layer "F.Fab")
		)
		(fp_line
			(start -1 2.749)
			(end -0.335 2.749)
			(stroke
				(width 0.15)
				(type solid)
			)
			(layer "F.Fab")
		)
		(fp_line
			(start -1 2.749)
			(end 0.998 2.749)
			(stroke
				(width 0.15)
				(type solid)
			)
			(layer "F.Fab")
		)
		(fp_line
			(start 0.998 2.749)
			(end 0.998 2.249)
			(stroke
				(width 0.15)
				(type solid)
			)
			(layer "F.Fab")
		)
		(fp_line
			(start -1 2.648)
			(end -0.335 2.648)
			(stroke
				(width 0.15)
				(type solid)
			)
			(layer "F.Fab")
		)
		(fp_line
			(start -1 2.548)
			(end -0.335 2.548)
			(stroke
				(width 0.15)
				(type solid)
			)
			(layer "F.Fab")
		)
		(fp_line
			(start -1 2.45)
			(end -0.335 2.45)
			(stroke
				(width 0.15)
				(type solid)
			)
			(layer "F.Fab")
		)
		(fp_line
			(start -1 2.35)
			(end -0.335 2.35)
			(stroke
				(width 0.15)
				(type solid)
			)
			(layer "F.Fab")
		)
		(fp_line
			(start -1 2.249)
			(end -1 2.749)
			(stroke
				(width 0.15)
				(type solid)
			)
			(layer "F.Fab")
		)
		(fp_line
			(start -0.335 2.249)
			(end -0.335 2.749)
			(stroke
				(width 0.15)
				(type solid)
			)
			(layer "F.Fab")
		)
		(fp_line
			(start 0.998 2.249)
			(end -1 2.249)
			(stroke
				(width 0.15)
				(type solid)
			)
			(layer "F.Fab")
		)
		(fp_line
			(start -1 1.749)
			(end -0.335 1.749)
			(stroke
				(width 0.15)
				(type solid)
			)
			(layer "F.Fab")
		)
		(fp_line
			(start -1 1.749)
			(end 0.998 1.749)
			(stroke
				(width 0.15)
				(type solid)
			)
			(layer "F.Fab")
		)
		(fp_line
			(start 0.998 1.749)
			(end 0.998 1.249)
			(stroke
				(width 0.15)
				(type solid)
			)
			(layer "F.Fab")
		)
		(fp_line
			(start -1 1.648)
			(end -0.335 1.648)
			(stroke
				(width 0.15)
				(type solid)
			)
			(layer "F.Fab")
		)
		(fp_line
			(start -1 1.55)
			(end -0.335 1.55)
			(stroke
				(width 0.15)
				(type solid)
			)
			(layer "F.Fab")
		)
		(fp_line
			(start -1 1.449)
			(end -0.335 1.449)
			(stroke
				(width 0.15)
				(type solid)
			)
			(layer "F.Fab")
		)
		(fp_line
			(start -1 1.35)
			(end -0.335 1.35)
			(stroke
				(width 0.15)
				(type solid)
			)
			(layer "F.Fab")
		)
		(fp_line
			(start -1 1.249)
			(end -1 1.749)
			(stroke
				(width 0.15)
				(type solid)
			)
			(layer "F.Fab")
		)
		(fp_line
			(start -0.335 1.249)
			(end -0.335 1.749)
			(stroke
				(width 0.15)
				(type solid)
			)
			(layer "F.Fab")
		)
		(fp_line
			(start 0.998 1.249)
			(end -1 1.249)
			(stroke
				(width 0.15)
				(type solid)
			)
			(layer "F.Fab")
		)
		(fp_line
			(start -1 0.748)
			(end -0.335 0.748)
			(stroke
				(width 0.15)
				(type solid)
			)
			(layer "F.Fab")
		)
		(fp_line
			(start -1 0.748)
			(end 0.998 0.748)
			(stroke
				(width 0.15)
				(type solid)
			)
			(layer "F.Fab")
		)
		(fp_line
			(start 0.998 0.748)
			(end 0.998 0.248)
			(stroke
				(width 0.15)
				(type solid)
			)
			(layer "F.Fab")
		)
		(fp_line
			(start -1 0.65)
			(end -0.335 0.65)
			(stroke
				(width 0.15)
				(type solid)
			)
			(layer "F.Fab")
		)
		(fp_line
			(start -1 0.55)
			(end -0.335 0.55)
			(stroke
				(width 0.15)
				(type solid)
			)
			(layer "F.Fab")
		)
		(fp_line
			(start -1 0.45)
			(end -0.335 0.45)
			(stroke
				(width 0.15)
				(type solid)
			)
			(layer "F.Fab")
		)
		(fp_line
			(start -1 0.349)
			(end -0.335 0.349)
			(stroke
				(width 0.15)
				(type solid)
			)
			(layer "F.Fab")
		)
		(fp_line
			(start -1 0.248)
			(end -1 0.748)
			(stroke
				(width 0.15)
				(type solid)
			)
			(layer "F.Fab")
		)
		(fp_line
			(start -0.335 0.248)
			(end -0.335 0.748)
			(stroke
				(width 0.15)
				(type solid)
			)
			(layer "F.Fab")
		)
		(fp_line
			(start 0.998 0.248)
			(end -1 0.248)
			(stroke
				(width 0.15)
				(type solid)
			)
			(layer "F.Fab")
		)
		(fp_line
			(start -1 -0.25)
			(end 0.998 -0.25)
			(stroke
				(width 0.15)
				(type solid)
			)
			(layer "F.Fab")
		)
		(fp_line
			(start 0.998 -0.25)
			(end 0.998 -0.75)
			(stroke
				(width 0.15)
				(type solid)
			)
			(layer "F.Fab")
		)
		(fp_line
			(start -1 -0.351)
			(end -0.335 -0.351)
			(stroke
				(width 0.15)
				(type solid)
			)
			(layer "F.Fab")
		)
		(fp_line
			(start -1 -0.452)
			(end -0.335 -0.452)
			(stroke
				(width 0.15)
				(type solid)
			)
			(layer "F.Fab")
		)
		(fp_line
			(start -1 -0.552)
			(end -0.335 -0.552)
			(stroke
				(width 0.15)
				(type solid)
			)
			(layer "F.Fab")
		)
		(fp_line
			(start -1 -0.652)
			(end -0.335 -0.652)
			(stroke
				(width 0.15)
				(type solid)
			)
			(layer "F.Fab")
		)
		(fp_line
			(start -1 -0.75)
			(end -1 -0.25)
			(stroke
				(width 0.15)
				(type solid)
			)
			(layer "F.Fab")
		)
		(fp_line
			(start -0.335 -0.75)
			(end -0.335 -0.25)
			(stroke
				(width 0.15)
				(type solid)
			)
			(layer "F.Fab")
		)
		(fp_line
			(start 0.998 -0.75)
			(end -1 -0.75)
			(stroke
				(width 0.15)
				(type solid)
			)
			(layer "F.Fab")
		)
		(fp_line
			(start -1 -1.25)
			(end 0.998 -1.25)
			(stroke
				(width 0.15)
				(type solid)
			)
			(layer "F.Fab")
		)
		(fp_line
			(start 0.998 -1.25)
			(end 0.998 -1.75)
			(stroke
				(width 0.15)
				(type solid)
			)
			(layer "F.Fab")
		)
		(fp_line
			(start -1 -1.351)
			(end -0.335 -1.351)
			(stroke
				(width 0.15)
				(type solid)
			)
			(layer "F.Fab")
		)
		(fp_line
			(start -1 -1.45)
			(end -0.335 -1.45)
			(stroke
				(width 0.15)
				(type solid)
			)
			(layer "F.Fab")
		)
		(fp_line
			(start -1 -1.551)
			(end -0.335 -1.551)
			(stroke
				(width 0.15)
				(type solid)
			)
			(layer "F.Fab")
		)
		(fp_line
			(start -1 -1.651)
			(end -0.335 -1.651)
			(stroke
				(width 0.15)
				(type solid)
			)
			(layer "F.Fab")
		)
		(fp_line
			(start -1 -1.75)
			(end -1 -1.25)
			(stroke
				(width 0.15)
				(type solid)
			)
			(layer "F.Fab")
		)
		(fp_line
			(start -0.335 -1.75)
			(end -0.335 -1.25)
			(stroke
				(width 0.15)
				(type solid)
			)
			(layer "F.Fab")
		)
		(fp_line
			(start 0.998 -1.75)
			(end -1 -1.75)
			(stroke
				(width 0.15)
				(type solid)
			)
			(layer "F.Fab")
		)
		(fp_line
			(start -1 -2.25)
			(end 0.998 -2.25)
			(stroke
				(width 0.15)
				(type solid)
			)
			(layer "F.Fab")
		)
		(fp_line
			(start 0.998 -2.25)
			(end 0.998 -2.75)
			(stroke
				(width 0.15)
				(type solid)
			)
			(layer "F.Fab")
		)
		(fp_line
			(start -1 -2.351)
			(end -0.335 -2.351)
			(stroke
				(width 0.15)
				(type solid)
			)
			(layer "F.Fab")
		)
		(fp_line
			(start -1 -2.452)
			(end -0.335 -2.452)
			(stroke
				(width 0.15)
				(type solid)
			)
			(layer "F.Fab")
		)
		(fp_line
			(start -1 -2.551)
			(end -0.335 -2.551)
			(stroke
				(width 0.15)
				(type solid)
			)
			(layer "F.Fab")
		)
		(fp_line
			(start -1 -2.65)
			(end -0.335 -2.65)
			(stroke
				(width 0.15)
				(type solid)
			)
			(layer "F.Fab")
		)
		(fp_line
			(start -1 -2.75)
			(end -1 -2.25)
			(stroke
				(width 0.15)
				(type solid)
			)
			(layer "F.Fab")
		)
		(fp_line
			(start -0.335 -2.75)
			(end -0.335 -2.25)
			(stroke
				(width 0.15)
				(type solid)
			)
			(layer "F.Fab")
		)
		(fp_line
			(start 0.998 -2.75)
			(end -1 -2.75)
			(stroke
				(width 0.15)
				(type solid)
			)
			(layer "F.Fab")
		)
		(fp_line
			(start -1 -3.25)
			(end 0.998 -3.25)
			(stroke
				(width 0.15)
				(type solid)
			)
			(layer "F.Fab")
		)
		(fp_line
			(start 0.998 -3.25)
			(end 0.998 -3.75)
			(stroke
				(width 0.15)
				(type solid)
			)
			(layer "F.Fab")
		)
		(fp_line
			(start -1 -3.351)
			(end -0.335 -3.351)
			(stroke
				(width 0.15)
				(type solid)
			)
			(layer "F.Fab")
		)
		(fp_line
			(start -1 -3.451)
			(end -0.335 -3.451)
			(stroke
				(width 0.15)
				(type solid)
			)
			(layer "F.Fab")
		)
		(fp_line
			(start -2.351 -3.5)
			(end -1.351 -4.5)
			(stroke
				(width 0.15)
				(type solid)
			)
			(layer "F.Fab")
		)
		(fp_line
			(start -1 -3.551)
			(end -0.335 -3.551)
			(stroke
				(width 0.15)
				(type solid)
			)
			(layer "F.Fab")
		)
		(fp_line
			(start -1 -3.65)
			(end -0.335 -3.65)
			(stroke
				(width 0.15)
				(type solid)
			)
			(layer "F.Fab")
		)
		(fp_line
			(start -1 -3.75)
			(end -1 -3.25)
			(stroke
				(width 0.15)
				(type solid)
			)
			(layer "F.Fab")
		)
		(fp_line
			(start -0.335 -3.75)
			(end -0.335 -3.25)
			(stroke
				(width 0.15)
				(type solid)
			)
			(layer "F.Fab")
		)
		(fp_line
			(start 0.998 -3.75)
			(end -1 -3.75)
			(stroke
				(width 0.15)
				(type solid)
			)
			(layer "F.Fab")
		)
		(fp_line
			(start -1.351 -4.5)
			(end 2.35 -4.5)
			(stroke
				(width 0.15)
				(type solid)
			)
			(layer "F.Fab")
		)
		(fp_line
			(start 2.35 -4.5)
			(end 2.35 4.498)
			(stroke
				(width 0.15)
				(type solid)
			)
			(layer "F.Fab")
		)
		(fp_text user "on"
			(at -1.56 0.69 0)
			(layer "F.Fab")
			(effects
				(font
					(size 0.7 0.7)
					(thickness 0.15)
				)
				(justify left bottom)
			)
		)
		(pad "1" smd rect
			(at -2.952 -3.5 270)
			(size 1.2 0.5)
			(layers "F.Cu" "F.Mask" "F.Paste")
			(net 1209 "unconnected-(SW3-Pad1)")
			(pinfunction "1")
			(pintype "passive+no_connect")
		)
		(pad "2" smd rect
			(at -2.952 -2.5 270)
			(size 1.2 0.5)
			(layers "F.Cu" "F.Mask" "F.Paste")
			(net 1210 "unconnected-(SW3-Pad2)")
			(pinfunction "2")
			(pintype "passive+no_connect")
		)
		(pad "3" smd rect
			(at -2.952 -1.5 270)
			(size 1.2 0.5)
			(layers "F.Cu" "F.Mask" "F.Paste")
			(net 1393 "/I2C.QDCDC2_SCL")
			(pinfunction "3")
			(pintype "passive")
		)
		(pad "4" smd rect
			(at -2.952 -0.5 270)
			(size 1.2 0.5)
			(layers "F.Cu" "F.Mask" "F.Paste")
			(net 1394 "/I2C.QDCDC1_SCL")
			(pinfunction "4")
			(pintype "passive")
		)
		(pad "5" smd rect
			(at -2.952 0.498 270)
			(size 1.2 0.5)
			(layers "F.Cu" "F.Mask" "F.Paste")
			(net 1023 "/USB PHY/BDBUS0")
			(pinfunction "5")
			(pintype "passive")
		)
		(pad "6" smd rect
			(at -2.952 1.499 270)
			(size 1.2 0.5)
			(layers "F.Cu" "F.Mask" "F.Paste")
			(net 1024 "/USB PHY/BDBUS1")
			(pinfunction "6")
			(pintype "passive")
		)
		(pad "7" smd rect
			(at -2.952 2.499 270)
			(size 1.2 0.5)
			(layers "F.Cu" "F.Mask" "F.Paste")
			(net 1025 "/USB PHY/BDBUS2")
			(pinfunction "7")
			(pintype "passive")
		)
		(pad "8" smd rect
			(at -2.952 3.499 270)
			(size 1.2 0.5)
			(layers "F.Cu" "F.Mask" "F.Paste")
			(net 799 "FTDI_DIS")
			(pinfunction "8")
			(pintype "passive")
		)
		(pad "9" smd rect
			(at 2.95 3.499 270)
			(size 1.2 0.5)
			(layers "F.Cu" "F.Mask" "F.Paste")
			(net 1 "GND")
			(pinfunction "9")
			(pintype "passive")
		)
		(pad "10" smd rect
			(at 2.95 2.499 270)
			(size 1.2 0.5)
			(layers "F.Cu" "F.Mask" "F.Paste")
			(net 942 "/USB PHY/FTDI_SDA_IN")
			(pinfunction "10")
			(pintype "passive")
		)
		(pad "11" smd rect
			(at 2.95 1.499 270)
			(size 1.2 0.5)
			(layers "F.Cu" "F.Mask" "F.Paste")
			(net 1047 "/USB PHY/FTDI_SDA_OUT")
			(pinfunction "11")
			(pintype "passive")
		)
		(pad "12" smd rect
			(at 2.95 0.498 270)
			(size 1.2 0.5)
			(layers "F.Cu" "F.Mask" "F.Paste")
			(net 941 "/USB PHY/FTDI_SCL")
			(pinfunction "12")
			(pintype "passive")
		)
		(pad "13" smd rect
			(at 2.95 -0.5 270)
			(size 1.2 0.5)
			(layers "F.Cu" "F.Mask" "F.Paste")
			(net 1338 "/I2C.SCL")
			(pinfunction "13")
			(pintype "passive")
		)
		(pad "14" smd rect
			(at 2.95 -1.5 270)
			(size 1.2 0.5)
			(layers "F.Cu" "F.Mask" "F.Paste")
			(net 1338 "/I2C.SCL")
			(pinfunction "14")
			(pintype "passive")
		)
		(pad "15" smd rect
			(at 2.95 -2.5 270)
			(size 1.2 0.5)
			(layers "F.Cu" "F.Mask" "F.Paste")
			(net 1211 "unconnected-(SW3-Pad15)")
			(pinfunction "15")
			(pintype "passive+no_connect")
		)
		(pad "16" smd rect
			(at 2.95 -3.5 270)
			(size 1.2 0.5)
			(layers "F.Cu" "F.Mask" "F.Paste")
			(net 1212 "unconnected-(SW3-Pad16)")
			(pinfunction "16")
			(pintype "passive+no_connect")
		)
		(pad "17" smd rect
			(at -2.15 -4.5 270)
			(size 0.7 0.7)
			(layers "F.Cu" "F.Mask" "F.Paste")
			(net 1 "GND")
			(pinfunction "17")
			(pintype "power_in")
		)
		(pad "17" smd rect
			(at -2.15 4.498 270)
			(size 0.7 0.7)
			(layers "F.Cu" "F.Mask" "F.Paste")
			(net 1 "GND")
			(pinfunction "17")
			(pintype "power_in")
		)
		(pad "17" smd rect
			(at 2.148 -4.5 270)
			(size 0.7 0.7)
			(layers "F.Cu" "F.Mask" "F.Paste")
			(net 1 "GND")
			(pinfunction "17")
			(pintype "power_in")
		)
		(pad "17" smd rect
			(at 2.148 4.498 270)
			(size 0.7 0.7)
			(layers "F.Cu" "F.Mask" "F.Paste")
			(net 1 "GND")
			(pinfunction "17")
			(pintype "power_in")
		)
	)
	(footprint "antmicro-footprints:C_Pol_EIA-B"
		(layer "F.Cu")
		(at 201.061 149.4)
		(property "Reference" "C125"
			(at -1.401 -1.76 0)
			(layer "F.SilkS")
			(effects
				(font
					(size 0.7 0.7)
					(thickness 0.15)
				)
				(justify left bottom)
			)
		)
		(property "Value" "C_Pol_330u_6.3V_KEMET-T520-B"
			(at -2.34 2.45 0)
			(layer "F.Fab")
			(effects
				(font
					(size 0.7 0.7)
					(thickness 0.15)
				)
				(justify left bottom)
			)
		)
		(property "Description" "Tantalum Polymer Capacitor, KO-CAP®, 330 µF, ± 20%, 6.3 V, B, 0.04 ohm, 1411 [3528 Metric]"
			(at 0 0 0)
			(layer "F.Fab")
			(hide yes)
			(effects
				(font
					(size 1.27 1.27)
					(thickness 0.15)
				)
			)
		)
		(property "Author" "Antmicro"
			(at 0 0 0)
			(layer "F.Fab")
			(hide yes)
			(effects
				(font
					(size 1 1)
					(thickness 0.15)
				)
			)
		)
		(property "Dielectric" ""
			(at 0 0 0)
			(layer "F.Fab")
			(hide yes)
			(effects
				(font
					(size 1 1)
					(thickness 0.15)
				)
			)
		)
		(property "License" "Apache-2.0"
			(at 0 0 0)
			(layer "F.Fab")
			(hide yes)
			(effects
				(font
					(size 1 1)
					(thickness 0.15)
				)
			)
		)
		(property "MPN" "T520B337M006ATE040"
			(at 0 0 0)
			(layer "F.Fab")
			(hide yes)
			(effects
				(font
					(size 1 1)
					(thickness 0.15)
				)
			)
		)
		(property "Manufacturer" "KEMET"
			(at 0 0 0)
			(layer "F.Fab")
			(hide yes)
			(effects
				(font
					(size 1 1)
					(thickness 0.15)
				)
			)
		)
		(property "Val" "330u"
			(at 0 0 0)
			(layer "F.Fab")
			(hide yes)
			(effects
				(font
					(size 1 1)
					(thickness 0.15)
				)
			)
		)
		(property "Voltage" "6.3V"
			(at 0 0 0)
			(layer "F.Fab")
			(hide yes)
			(effects
				(font
					(size 1 1)
					(thickness 0.15)
				)
			)
		)
		(sheetname "FPGA supply")
		(sheetfile "fpga-supply.kicad_sch")
		(attr smd)
		(fp_line
			(start -2.521 -1.676)
			(end -2.123 -1.676)
			(stroke
				(width 0.15)
				(type solid)
			)
			(layer "F.SilkS")
		)
		(fp_line
			(start -2.325 -1.475)
			(end -2.325 -1.878)
			(stroke
				(width 0.15)
				(type solid)
			)
			(layer "F.SilkS")
		)
		(fp_line
			(start -1.8 -1.6)
			(end 1.8 -1.6)
			(stroke
				(width 0.15)
				(type solid)
			)
			(layer "F.SilkS")
		)
		(fp_line
			(start -1.8 -1.3)
			(end -1.8 -1.6)
			(stroke
				(width 0.15)
				(type solid)
			)
			(layer "F.SilkS")
		)
		(fp_line
			(start -1.8 1.3)
			(end -1.8 1.6)
			(stroke
				(width 0.15)
				(type solid)
			)
			(layer "F.SilkS")
		)
		(fp_line
			(start 1.8 -1.3)
			(end 1.8 -1.6)
			(stroke
				(width 0.15)
				(type solid)
			)
			(layer "F.SilkS")
		)
		(fp_line
			(start 1.8 1.3)
			(end 1.8 1.6)
			(stroke
				(width 0.15)
				(type solid)
			)
			(layer "F.SilkS")
		)
		(fp_line
			(start 1.8 1.6)
			(end -1.8 1.6)
			(stroke
				(width 0.15)
				(type solid)
			)
			(layer "F.SilkS")
		)
		(fp_line
			(start -2.411 -1.35)
			(end -2.41 1.35)
			(stroke
				(width 0.05)
				(type solid)
			)
			(layer "F.CrtYd")
		)
		(fp_line
			(start -1.97 -1.75)
			(end -1.97 -1.35)
			(stroke
				(width 0.05)
				(type solid)
			)
			(layer "F.CrtYd")
		)
		(fp_line
			(start -1.97 -1.35)
			(end -2.41 -1.35)
			(stroke
				(width 0.05)
				(type solid)
			)
			(layer "F.CrtYd")
		)
		(fp_line
			(start -1.97 1.35)
			(end -2.41 1.35)
			(stroke
				(width 0.05)
				(type solid)
			)
			(layer "F.CrtYd")
		)
		(fp_line
			(start -1.97 1.35)
			(end -1.97 1.75)
			(stroke
				(width 0.05)
				(type solid)
			)
			(layer "F.CrtYd")
		)
		(fp_line
			(start 1.959 -1.75)
			(end -1.971 -1.75)
			(stroke
				(width 0.05)
				(type solid)
			)
			(layer "F.CrtYd")
		)
		(fp_line
			(start 1.959 -1.75)
			(end 1.959 -1.35)
			(stroke
				(width 0.05)
				(type solid)
			)
			(layer "F.CrtYd")
		)
		(fp_line
			(start 1.96 1.35)
			(end 1.96 1.75)
			(stroke
				(width 0.05)
				(type solid)
			)
			(layer "F.CrtYd")
		)
		(fp_line
			(start 1.96 1.75)
			(end -1.97 1.75)
			(stroke
				(width 0.05)
				(type solid)
			)
			(layer "F.CrtYd")
		)
		(fp_line
			(start 2.399 -1.35)
			(end 1.959 -1.35)
			(stroke
				(width 0.05)
				(type solid)
			)
			(layer "F.CrtYd")
		)
		(fp_line
			(start 2.399 -1.35)
			(end 2.4 1.35)
			(stroke
				(width 0.05)
				(type solid)
			)
			(layer "F.CrtYd")
		)
		(fp_line
			(start 2.4 1.35)
			(end 1.96 1.35)
			(stroke
				(width 0.05)
				(type solid)
			)
			(layer "F.CrtYd")
		)
		(fp_line
			(start -1.7 1.324)
			(end -1.551 1.475)
			(stroke
				(width 0.15)
				(type solid)
			)
			(layer "F.Fab")
		)
		(fp_rect
			(start -1.72 -1.5)
			(end 1.719 1.499)
			(stroke
				(width 0.15)
				(type solid)
			)
			(fill no)
			(layer "F.Fab")
		)
		(pad "1" smd roundrect
			(at -1.551 0)
			(size 1.2 2.2)
			(layers "F.Cu" "F.Mask" "F.Paste")
			(roundrect_rratio 0.1)
			(net 650 "+1V0")
			(pintype "passive")
		)
		(pad "2" smd roundrect
			(at 1.55 0)
			(size 1.2 2.2)
			(layers "F.Cu" "F.Mask" "F.Paste")
			(roundrect_rratio 0.1)
			(net 1 "GND")
			(pintype "passive")
		)
	)
	(footprint "antmicro-footprints:C_0402_1005Metric"
		(layer "F.Cu")
		(at 195.803752 93.5615)
		(descr "Capacitor SMD 0402")
		(tags "capacitor SMD 0402")
		(property "Reference" "C288"
			(at -1.578752 -0.4115 0)
			(layer "F.SilkS")
			(effects
				(font
					(size 0.7 0.7)
					(thickness 0.15)
				)
				(justify left bottom)
			)
		)
		(property "Value" "C_100n_0402"
			(at 0 1.169 0)
			(layer "F.Fab")
			(effects
				(font
					(size 0.7 0.7)
					(thickness 0.15)
				)
				(justify left bottom)
			)
		)
		(property "Description" "SMD Multilayer Ceramic Capacitor, 0.1 µF, 50 V, 0402 [1005 Metric], ± 10%, X5R, GRM Series"
			(at 0 0 0)
			(layer "F.Fab")
			(hide yes)
			(effects
				(font
					(size 1.27 1.27)
					(thickness 0.15)
				)
			)
		)
		(property "Author" "Antmicro"
			(at 0 0 0)
			(layer "F.Fab")
			(hide yes)
			(effects
				(font
					(size 1 1)
					(thickness 0.15)
				)
			)
		)
		(property "Dielectric" "X5R"
			(at 0 0 0)
			(layer "F.Fab")
			(hide yes)
			(effects
				(font
					(size 1 1)
					(thickness 0.15)
				)
			)
		)
		(property "License" "Apache-2.0"
			(at 0 0 0)
			(layer "F.Fab")
			(hide yes)
			(effects
				(font
					(size 1 1)
					(thickness 0.15)
				)
			)
		)
		(property "MPN" "GRM155R61H104KE14D"
			(at 0 0 0)
			(layer "F.Fab")
			(hide yes)
			(effects
				(font
					(size 1 1)
					(thickness 0.15)
				)
			)
		)
		(property "Manufacturer" "Murata"
			(at 0 0 0)
			(layer "F.Fab")
			(hide yes)
			(effects
				(font
					(size 1 1)
					(thickness 0.15)
				)
			)
		)
		(property "Val" "100n"
			(at 0 0 0)
			(layer "F.Fab")
			(hide yes)
			(effects
				(font
					(size 1 1)
					(thickness 0.15)
				)
			)
		)
		(property "Voltage" "50V"
			(at 0 0 0)
			(layer "F.Fab")
			(hide yes)
			(effects
				(font
					(size 1 1)
					(thickness 0.15)
				)
			)
		)
		(sheetname "HDMI + Ethernet")
		(sheetfile "hdmi-ethernet.kicad_sch")
		(attr smd)
		(fp_rect
			(start -0.925 -0.47)
			(end 0.925 0.47)
			(stroke
				(width 0.05)
				(type default)
			)
			(fill no)
			(layer "F.CrtYd")
		)
		(fp_line
			(start -0.494 -0.25)
			(end 0.504 -0.25)
			(stroke
				(width 0.15)
				(type solid)
			)
			(layer "F.Fab")
		)
		(fp_line
			(start -0.494 0.248)
			(end -0.494 -0.25)
			(stroke
				(width 0.15)
				(type solid)
			)
			(layer "F.Fab")
		)
		(fp_line
			(start 0.504 -0.25)
			(end 0.504 0.248)
			(stroke
				(width 0.15)
				(type solid)
			)
			(layer "F.Fab")
		)
		(fp_line
			(start 0.504 0.248)
			(end -0.494 0.248)
			(stroke
				(width 0.15)
				(type solid)
			)
			(layer "F.Fab")
		)
		(pad "1" smd roundrect
			(at -0.48 0)
			(size 0.59 0.64)
			(layers "F.Cu" "F.Mask" "F.Paste")
			(roundrect_rratio 0.25)
			(net 1 "GND")
			(pintype "passive")
		)
		(pad "2" smd roundrect
			(at 0.48 0)
			(size 0.59 0.64)
			(layers "F.Cu" "F.Mask" "F.Paste")
			(roundrect_rratio 0.25)
			(net 727 "+1V2")
			(pintype "passive")
		)
	)
	(footprint "antmicro-footprints:Resonator_SMD_Abracon_ABM8G_3.2x2.5mm"
		(layer "F.Cu")
		(at 259.5075 138.985)
		(property "Reference" "Y2"
			(at 0.6425 2.415 180)
			(layer "F.SilkS")
			(effects
				(font
					(size 0.7 0.7)
					(thickness 0.15)
				)
				(justify left bottom)
			)
		)
		(property "Value" "Resonator_12MHz_ABM8G"
			(at -1.75 2.548 0)
			(layer "F.Fab")
			(effects
				(font
					(size 0.7 0.7)
					(thickness 0.15)
				)
				(justify left bottom)
			)
		)
		(property "Description" "Crystal, 12 MHz, SMT, 3.2mm x 2.5mm, 30 ppm, 18 pF, 20 ppm, ABM8G"
			(at 0 0 0)
			(layer "F.Fab")
			(hide yes)
			(effects
				(font
					(size 1.27 1.27)
					(thickness 0.15)
				)
			)
		)
		(property "Author" "Antmicro"
			(at 0 0 0)
			(layer "F.Fab")
			(hide yes)
			(effects
				(font
					(size 1 1)
					(thickness 0.15)
				)
			)
		)
		(property "License" "Apache-2.0"
			(at 0 0 0)
			(layer "F.Fab")
			(hide yes)
			(effects
				(font
					(size 1 1)
					(thickness 0.15)
				)
			)
		)
		(property "MPN" "ABM8G-12.000MHZ-18-D2Y-T"
			(at 0 0 0)
			(layer "F.Fab")
			(hide yes)
			(effects
				(font
					(size 1 1)
					(thickness 0.15)
				)
			)
		)
		(property "Manufacturer" "Abracon"
			(at 0 0 0)
			(layer "F.Fab")
			(hide yes)
			(effects
				(font
					(size 1 1)
					(thickness 0.15)
				)
			)
		)
		(property "Val" "12 MHz"
			(at 0 0 0)
			(layer "F.Fab")
			(hide yes)
			(effects
				(font
					(size 1 1)
					(thickness 0.15)
				)
			)
		)
		(sheetname "USB PHY")
		(sheetfile "usb-phy.kicad_sch")
		(attr smd)
		(fp_line
			(start -1.6 0.3)
			(end -1.6 -0.2)
			(stroke
				(width 0.15)
				(type solid)
			)
			(layer "F.SilkS")
		)
		(fp_line
			(start -0.35 -1.25)
			(end 0.45 -1.25)
			(stroke
				(width 0.15)
				(type solid)
			)
			(layer "F.SilkS")
		)
		(fp_line
			(start -0.35 1.25)
			(end 0.45 1.25)
			(stroke
				(width 0.15)
				(type solid)
			)
			(layer "F.SilkS")
		)
		(fp_line
			(start 1.6 0.3)
			(end 1.6 -0.2)
			(stroke
				(width 0.15)
				(type solid)
			)
			(layer "F.SilkS")
		)
		(fp_circle
			(center -1.75 1.5)
			(end -1.7 1.5)
			(stroke
				(width 0.15)
				(type solid)
			)
			(fill no)
			(layer "F.SilkS")
		)
		(fp_rect
			(start -1.907 -1.55)
			(end 2.006 1.649)
			(stroke
				(width 0.05)
				(type solid)
			)
			(fill no)
			(layer "F.CrtYd")
		)
		(pad "1" smd roundrect
			(at -1.101 0.949)
			(size 1.3 1.1)
			(layers "F.Cu" "F.Mask" "F.Paste")
			(roundrect_rratio 0)
			(chamfer_ratio 0.2)
			(chamfer bottom_left)
			(net 710 "/USB PHY/FTDI_XI")
			(pintype "passive")
		)
		(pad "2" smd rect
			(at 1.199 0.949)
			(size 1.3 1.1)
			(layers "F.Cu" "F.Mask" "F.Paste")
			(net 1 "GND")
			(pinfunction "SH")
			(pintype "passive")
		)
		(pad "3" smd rect
			(at 1.199 -0.85)
			(size 1.3 1.1)
			(layers "F.Cu" "F.Mask" "F.Paste")
			(net 713 "/USB PHY/FTDI_XO")
			(pintype "passive")
		)
		(pad "4" smd rect
			(at -1.101 -0.85)
			(size 1.3 1.1)
			(layers "F.Cu" "F.Mask" "F.Paste")
			(net 1 "GND")
			(pinfunction "SH")
			(pintype "passive")
		)
	)
	(footprint "antmicro-footprints:C_0402_1005Metric"
		(layer "F.Cu")
		(at 231.8 130.3 180)
		(descr "Capacitor SMD 0402")
		(tags "capacitor SMD 0402")
		(property "Reference" "C216"
			(at 0.9 -0.35 0)
			(layer "F.SilkS")
			(effects
				(font
					(size 0.7 0.7)
					(thickness 0.15)
				)
				(justify right bottom)
			)
		)
		(property "Value" "C_1u_0402"
			(at 0 1.4 0)
			(layer "F.Fab")
			(effects
				(font
					(size 0.7 0.7)
					(thickness 0.15)
				)
				(justify right bottom)
			)
		)
		(property "Description" "SMD Multilayer Ceramic Capacitor, 1 µF, 10 V, 0402 [1005 Metric], ± 10%, X6S, C"
			(at 0 0 180)
			(layer "F.Fab")
			(hide yes)
			(effects
				(font
					(size 1.27 1.27)
					(thickness 0.15)
				)
			)
		)
		(property "Author" "Antmicro"
			(at 463.6 260.6 0)
			(layer "F.Fab")
			(hide yes)
			(effects
				(font
					(size 1 1)
					(thickness 0.15)
				)
			)
		)
		(property "Dielectric" ""
			(at 463.6 260.6 0)
			(layer "F.Fab")
			(hide yes)
			(effects
				(font
					(size 1 1)
					(thickness 0.15)
				)
			)
		)
		(property "License" "Apache-2.0"
			(at 463.6 260.6 0)
			(layer "F.Fab")
			(hide yes)
			(effects
				(font
					(size 1 1)
					(thickness 0.15)
				)
			)
		)
		(property "MPN" "C1005X6S1A105K050BC"
			(at 463.6 260.6 0)
			(layer "F.Fab")
			(hide yes)
			(effects
				(font
					(size 1 1)
					(thickness 0.15)
				)
			)
		)
		(property "Manufacturer" "TDK"
			(at 463.6 260.6 0)
			(layer "F.Fab")
			(hide yes)
			(effects
				(font
					(size 1 1)
					(thickness 0.15)
				)
			)
		)
		(property "Val" "1u"
			(at 463.6 260.6 0)
			(layer "F.Fab")
			(hide yes)
			(effects
				(font
					(size 1 1)
					(thickness 0.15)
				)
			)
		)
		(property "Voltage" ""
			(at 463.6 260.6 0)
			(layer "F.Fab")
			(hide yes)
			(effects
				(font
					(size 1 1)
					(thickness 0.15)
				)
			)
		)
		(sheetname "User GPIO + LED + button + DIP switch")
		(sheetfile "user-gpio.kicad_sch")
		(attr smd)
		(fp_rect
			(start -0.925 -0.47)
			(end 0.925 0.47)
			(stroke
				(width 0.05)
				(type default)
			)
			(fill no)
			(layer "F.CrtYd")
		)
		(fp_line
			(start 0.504 0.248)
			(end -0.494 0.248)
			(stroke
				(width 0.15)
				(type solid)
			)
			(layer "F.Fab")
		)
		(fp_line
			(start 0.504 -0.25)
			(end 0.504 0.248)
			(stroke
				(width 0.15)
				(type solid)
			)
			(layer "F.Fab")
		)
		(fp_line
			(start -0.494 0.248)
			(end -0.494 -0.25)
			(stroke
				(width 0.15)
				(type solid)
			)
			(layer "F.Fab")
		)
		(fp_line
			(start -0.494 -0.25)
			(end 0.504 -0.25)
			(stroke
				(width 0.15)
				(type solid)
			)
			(layer "F.Fab")
		)
		(pad "1" smd roundrect
			(at -0.48 0 180)
			(size 0.59 0.64)
			(layers "F.Cu" "F.Mask" "F.Paste")
			(roundrect_rratio 0.25)
			(net 1 "GND")
			(pintype "passive")
		)
		(pad "2" smd roundrect
			(at 0.48 0 180)
			(size 0.59 0.64)
			(layers "F.Cu" "F.Mask" "F.Paste")
			(roundrect_rratio 0.25)
			(net 703 "+5V")
			(pintype "passive")
		)
	)
	(footprint "antmicro-footprints:NetTie-2_SMD_Pad0.127mm"
		(layer "F.Cu")
		(at 240 124.727 -90)
		(descr "Net tie, 2 pin, 0.127mm  SMD pads")
		(tags "net tie")
		(property "Reference" "NT16"
			(at -0.128 -1.345 270)
			(layer "F.SilkS")
			(hide yes)
			(effects
				(font
					(size 0.7 0.7)
					(thickness 0.15)
				)
				(justify left bottom)
			)
		)
		(property "Value" "Net-Tie_2"
			(at 0 1.199 270)
			(layer "F.Fab")
			(effects
				(font
					(size 0.7 0.7)
					(thickness 0.15)
				)
				(justify left bottom)
			)
		)
		(property "Description" "Net tie, 2 pins"
			(at 0 0 270)
			(layer "F.Fab")
			(hide yes)
			(effects
				(font
					(size 1.27 1.27)
					(thickness 0.15)
				)
			)
		)
		(property "Author" "Antmicro"
			(at 115.273 364.727 0)
			(layer "F.Fab")
			(hide yes)
			(effects
				(font
					(size 1 1)
					(thickness 0.15)
				)
			)
		)
		(property "License" "Apache-2.0"
			(at 115.273 364.727 0)
			(layer "F.Fab")
			(hide yes)
			(effects
				(font
					(size 1 1)
					(thickness 0.15)
				)
			)
		)
		(property "MPN" ""
			(at 115.273 364.727 0)
			(layer "F.Fab")
			(hide yes)
			(effects
				(font
					(size 1 1)
					(thickness 0.15)
				)
			)
		)
		(property "Manufacturer" ""
			(at 115.273 364.727 0)
			(layer "F.Fab")
			(hide yes)
			(effects
				(font
					(size 1 1)
					(thickness 0.15)
				)
			)
		)
		(sheetname "FPGA Bank 12 & 13")
		(sheetfile "fpga-bank-12-13.kicad_sch")
		(attr exclude_from_pos_files)
		(net_tie_pad_groups "1, 2")
		(fp_poly
			(pts
				(xy -0.0635 -0.0635) (xy 0.0625 -0.0635) (xy 0.0625 0.0635) (xy -0.0635 0.0635)
			)
			(stroke
				(width 0)
				(type solid)
			)
			(fill yes)
			(layer "F.Cu")
		)
		(pad "1" smd roundrect
			(at -0.127 0 90)
			(size 0.127 0.127)
			(layers "F.Cu")
			(roundrect_rratio 0.5)
			(chamfer_ratio 0)
			(chamfer top_left bottom_left)
			(net 1329 "/SUP_MCU.TX0")
			(pinfunction "1")
			(pintype "passive")
		)
		(pad "2" smd roundrect
			(at 0.126 0 270)
			(size 0.127 0.127)
			(layers "F.Cu")
			(roundrect_rratio 0.5)
			(chamfer_ratio 0)
			(chamfer top_left bottom_left)
			(net 46 "/FPGA Bank 12 & 13/UART0.RX")
			(pinfunction "2")
			(pintype "passive")
		)
	)
	(footprint "antmicro-footprints:C_0402_1005Metric"
		(layer "F.Cu")
		(at 196.1 165.149 180)
		(descr "Capacitor SMD 0402")
		(tags "capacitor SMD 0402")
		(property "Reference" "C342"
			(at -3.7 -0.301 0)
			(layer "F.SilkS")
			(effects
				(font
					(size 0.7 0.7)
					(thickness 0.15)
				)
				(justify right bottom)
			)
		)
		(property "Value" "C_470n_0402"
			(at 0 1.4 0)
			(layer "F.Fab")
			(effects
				(font
					(size 0.7 0.7)
					(thickness 0.15)
				)
				(justify right bottom)
			)
		)
		(property "Description" "SMD Multilayer Ceramic Capacitor, 0.47 µF, 25 V, 0402 [1005 Metric], ± 20%, X5R, C"
			(at 0 0 180)
			(layer "F.Fab")
			(hide yes)
			(effects
				(font
					(size 1.27 1.27)
					(thickness 0.15)
				)
			)
		)
		(property "Author" "Antmicro"
			(at 392.2 330.298 0)
			(layer "F.Fab")
			(hide yes)
			(effects
				(font
					(size 1 1)
					(thickness 0.15)
				)
			)
		)
		(property "Dielectric" ""
			(at 392.2 330.298 0)
			(layer "F.Fab")
			(hide yes)
			(effects
				(font
					(size 1 1)
					(thickness 0.15)
				)
			)
		)
		(property "License" "Apache-2.0"
			(at 392.2 330.298 0)
			(layer "F.Fab")
			(hide yes)
			(effects
				(font
					(size 1 1)
					(thickness 0.15)
				)
			)
		)
		(property "MPN" "C1005X5R1E474M050BB"
			(at 392.2 330.298 0)
			(layer "F.Fab")
			(hide yes)
			(effects
				(font
					(size 1 1)
					(thickness 0.15)
				)
			)
		)
		(property "Manufacturer" "TDK"
			(at 392.2 330.298 0)
			(layer "F.Fab")
			(hide yes)
			(effects
				(font
					(size 1 1)
					(thickness 0.15)
				)
			)
		)
		(property "Val" "470n"
			(at 392.2 330.298 0)
			(layer "F.Fab")
			(hide yes)
			(effects
				(font
					(size 1 1)
					(thickness 0.15)
				)
			)
		)
		(property "Voltage" ""
			(at 392.2 330.298 0)
			(layer "F.Fab")
			(hide yes)
			(effects
				(font
					(size 1 1)
					(thickness 0.15)
				)
			)
		)
		(sheetname "DC-DC Converters")
		(sheetfile "dc-dc.kicad_sch")
		(attr smd)
		(fp_rect
			(start -0.925 -0.47)
			(end 0.925 0.47)
			(stroke
				(width 0.05)
				(type default)
			)
			(fill no)
			(layer "F.CrtYd")
		)
		(fp_line
			(start 0.504 0.248)
			(end -0.494 0.248)
			(stroke
				(width 0.15)
				(type solid)
			)
			(layer "F.Fab")
		)
		(fp_line
			(start 0.504 -0.25)
			(end 0.504 0.248)
			(stroke
				(width 0.15)
				(type solid)
			)
			(layer "F.Fab")
		)
		(fp_line
			(start -0.494 0.248)
			(end -0.494 -0.25)
			(stroke
				(width 0.15)
				(type solid)
			)
			(layer "F.Fab")
		)
		(fp_line
			(start -0.494 -0.25)
			(end 0.504 -0.25)
			(stroke
				(width 0.15)
				(type solid)
			)
			(layer "F.Fab")
		)
		(pad "1" smd roundrect
			(at -0.48 0 180)
			(size 0.59 0.64)
			(layers "F.Cu" "F.Mask" "F.Paste")
			(roundrect_rratio 0.25)
			(net 1 "GND")
			(pintype "passive")
		)
		(pad "2" smd roundrect
			(at 0.48 0 180)
			(size 0.59 0.64)
			(layers "F.Cu" "F.Mask" "F.Paste")
			(roundrect_rratio 0.25)
			(net 741 "/DC-DC Converters/1V0_VCC")
			(pintype "passive")
		)
	)
	(footprint "antmicro-footprints:NetTie-2_SMD_Pad0.127mm"
		(layer "F.Cu")
		(at 249.3 143.602 90)
		(descr "Net tie, 2 pin, 0.127mm  SMD pads")
		(tags "net tie")
		(property "Reference" "NT4"
			(at -0.128 -1.345 90)
			(layer "F.SilkS")
			(hide yes)
			(effects
				(font
					(size 0.7 0.7)
					(thickness 0.15)
				)
				(justify left bottom)
			)
		)
		(property "Value" "Net-Tie_2"
			(at 0 1.199 90)
			(layer "F.Fab")
			(effects
				(font
					(size 0.7 0.7)
					(thickness 0.15)
				)
				(justify left bottom)
			)
		)
		(property "Description" "Net tie, 2 pins"
			(at 0 0 90)
			(layer "F.Fab")
			(hide yes)
			(effects
				(font
					(size 1.27 1.27)
					(thickness 0.15)
				)
			)
		)
		(property "Author" "Antmicro"
			(at 392.902 -105.698 0)
			(layer "F.Fab")
			(hide yes)
			(effects
				(font
					(size 1 1)
					(thickness 0.15)
				)
			)
		)
		(property "License" "Apache-2.0"
			(at 392.902 -105.698 0)
			(layer "F.Fab")
			(hide yes)
			(effects
				(font
					(size 1 1)
					(thickness 0.15)
				)
			)
		)
		(property "MPN" ""
			(at 392.902 -105.698 0)
			(layer "F.Fab")
			(hide yes)
			(effects
				(font
					(size 1 1)
					(thickness 0.15)
				)
			)
		)
		(property "Manufacturer" ""
			(at 392.902 -105.698 0)
			(layer "F.Fab")
			(hide yes)
			(effects
				(font
					(size 1 1)
					(thickness 0.15)
				)
			)
		)
		(sheetname "FPGA Config")
		(sheetfile "fpga-config.kicad_sch")
		(attr exclude_from_pos_files)
		(net_tie_pad_groups "1, 2")
		(fp_poly
			(pts
				(xy -0.0635 -0.0635) (xy 0.0625 -0.0635) (xy 0.0625 0.0635) (xy -0.0635 0.0635)
			)
			(stroke
				(width 0)
				(type solid)
			)
			(fill yes)
			(layer "F.Cu")
		)
		(pad "1" smd roundrect
			(at -0.127 0 270)
			(size 0.127 0.127)
			(layers "F.Cu")
			(roundrect_rratio 0.5)
			(chamfer_ratio 0)
			(chamfer top_left bottom_left)
			(net 1313 "/SUP_MCU.FPGA_M1")
			(pinfunction "1")
			(pintype "passive")
		)
		(pad "2" smd roundrect
			(at 0.126 0 90)
			(size 0.127 0.127)
			(layers "F.Cu")
			(roundrect_rratio 0.5)
			(chamfer_ratio 0)
			(chamfer top_left bottom_left)
			(net 299 "/FPGA Config/MODE1")
			(pinfunction "2")
			(pintype "passive")
		)
	)
	(footprint "antmicro-footprints:NetTie-2_SMD_Pad0.127mm"
		(layer "F.Cu")
		(at 258.12 120.04 90)
		(descr "Net tie, 2 pin, 0.127mm  SMD pads")
		(tags "net tie")
		(property "Reference" "NT26"
			(at -0.128 -1.345 90)
			(layer "F.SilkS")
			(hide yes)
			(effects
				(font
					(size 0.7 0.7)
					(thickness 0.15)
				)
				(justify left bottom)
			)
		)
		(property "Value" "Net-Tie_2"
			(at 0 1.199 90)
			(layer "F.Fab")
			(effects
				(font
					(size 0.7 0.7)
					(thickness 0.15)
				)
				(justify left bottom)
			)
		)
		(property "Description" "Net tie, 2 pins"
			(at 0 0 90)
			(layer "F.Fab")
			(hide yes)
			(effects
				(font
					(size 1.27 1.27)
					(thickness 0.15)
				)
			)
		)
		(property "Author" "Antmicro"
			(at 378.16 -138.08 0)
			(layer "F.Fab")
			(hide yes)
			(effects
				(font
					(size 1 1)
					(thickness 0.15)
				)
			)
		)
		(property "License" "Apache-2.0"
			(at 378.16 -138.08 0)
			(layer "F.Fab")
			(hide yes)
			(effects
				(font
					(size 1 1)
					(thickness 0.15)
				)
			)
		)
		(property "MPN" ""
			(at 378.16 -138.08 0)
			(layer "F.Fab")
			(hide yes)
			(effects
				(font
					(size 1 1)
					(thickness 0.15)
				)
			)
		)
		(property "Manufacturer" ""
			(at 378.16 -138.08 0)
			(layer "F.Fab")
			(hide yes)
			(effects
				(font
					(size 1 1)
					(thickness 0.15)
				)
			)
		)
		(sheetname "DC-DC Converters")
		(sheetfile "dc-dc.kicad_sch")
		(attr exclude_from_pos_files)
		(net_tie_pad_groups "1, 2")
		(fp_poly
			(pts
				(xy -0.0635 -0.0635) (xy 0.0625 -0.0635) (xy 0.0625 0.0635) (xy -0.0635 0.0635)
			)
			(stroke
				(width 0)
				(type solid)
			)
			(fill yes)
			(layer "F.Cu")
		)
		(pad "1" smd roundrect
			(at -0.127 0 270)
			(size 0.127 0.127)
			(layers "F.Cu")
			(roundrect_rratio 0.5)
			(chamfer_ratio 0)
			(chamfer top_left bottom_left)
			(net 1214 "/DC-DC Converters/SENSE_5V_P")
			(pinfunction "1")
			(pintype "passive")
		)
		(pad "2" smd roundrect
			(at 0.126 0 90)
			(size 0.127 0.127)
			(layers "F.Cu")
			(roundrect_rratio 0.5)
			(chamfer_ratio 0)
			(chamfer top_left bottom_left)
			(net 703 "+5V")
			(pinfunction "2")
			(pintype "passive")
		)
	)
	(footprint "antmicro-footprints:C_0402_1005Metric"
		(layer "F.Cu")
		(at 197.6 163.749 180)
		(descr "Capacitor SMD 0402")
		(tags "capacitor SMD 0402")
		(property "Reference" "C351"
			(at -5.95 -1.701 0)
			(layer "F.SilkS")
			(effects
				(font
					(size 0.7 0.7)
					(thickness 0.15)
				)
				(justify right bottom)
			)
		)
		(property "Value" "C_100n_0402"
			(at 0 1.4 0)
			(layer "F.Fab")
			(effects
				(font
					(size 0.7 0.7)
					(thickness 0.15)
				)
				(justify right bottom)
			)
		)
		(property "Description" "SMD Multilayer Ceramic Capacitor, 0.1 µF, 50 V, 0402 [1005 Metric], ± 10%, X5R, GRM Series"
			(at 0 0 180)
			(layer "F.Fab")
			(hide yes)
			(effects
				(font
					(size 1.27 1.27)
					(thickness 0.15)
				)
			)
		)
		(property "Author" "Antmicro"
			(at 395.2 327.498 0)
			(layer "F.Fab")
			(hide yes)
			(effects
				(font
					(size 1 1)
					(thickness 0.15)
				)
			)
		)
		(property "Dielectric" "X5R"
			(at 395.2 327.498 0)
			(layer "F.Fab")
			(hide yes)
			(effects
				(font
					(size 1 1)
					(thickness 0.15)
				)
			)
		)
		(property "License" "Apache-2.0"
			(at 395.2 327.498 0)
			(layer "F.Fab")
			(hide yes)
			(effects
				(font
					(size 1 1)
					(thickness 0.15)
				)
			)
		)
		(property "MPN" "GRM155R61H104KE14D"
			(at 395.2 327.498 0)
			(layer "F.Fab")
			(hide yes)
			(effects
				(font
					(size 1 1)
					(thickness 0.15)
				)
			)
		)
		(property "Manufacturer" "Murata"
			(at 395.2 327.498 0)
			(layer "F.Fab")
			(hide yes)
			(effects
				(font
					(size 1 1)
					(thickness 0.15)
				)
			)
		)
		(property "Val" "100n"
			(at 395.2 327.498 0)
			(layer "F.Fab")
			(hide yes)
			(effects
				(font
					(size 1 1)
					(thickness 0.15)
				)
			)
		)
		(property "Voltage" "50V"
			(at 395.2 327.498 0)
			(layer "F.Fab")
			(hide yes)
			(effects
				(font
					(size 1 1)
					(thickness 0.15)
				)
			)
		)
		(sheetname "DC-DC Converters")
		(sheetfile "dc-dc.kicad_sch")
		(attr smd)
		(fp_rect
			(start -0.925 -0.47)
			(end 0.925 0.47)
			(stroke
				(width 0.05)
				(type default)
			)
			(fill no)
			(layer "F.CrtYd")
		)
		(fp_line
			(start 0.504 0.248)
			(end -0.494 0.248)
			(stroke
				(width 0.15)
				(type solid)
			)
			(layer "F.Fab")
		)
		(fp_line
			(start 0.504 -0.25)
			(end 0.504 0.248)
			(stroke
				(width 0.15)
				(type solid)
			)
			(layer "F.Fab")
		)
		(fp_line
			(start -0.494 0.248)
			(end -0.494 -0.25)
			(stroke
				(width 0.15)
				(type solid)
			)
			(layer "F.Fab")
		)
		(fp_line
			(start -0.494 -0.25)
			(end 0.504 -0.25)
			(stroke
				(width 0.15)
				(type solid)
			)
			(layer "F.Fab")
		)
		(pad "1" smd roundrect
			(at -0.48 0 180)
			(size 0.59 0.64)
			(layers "F.Cu" "F.Mask" "F.Paste")
			(roundrect_rratio 0.25)
			(net 746 "/DC-DC Converters/1V0_SW")
			(pintype "passive")
		)
		(pad "2" smd roundrect
			(at 0.48 0 180)
			(size 0.59 0.64)
			(layers "F.Cu" "F.Mask" "F.Paste")
			(roundrect_rratio 0.25)
			(net 745 "/DC-DC Converters/1V0_BS")
			(pintype "passive")
		)
	)
	(footprint "antmicro-footprints:C_0402_1005Metric"
		(layer "F.Cu")
		(at 201.703752 98.9115)
		(descr "Capacitor SMD 0402")
		(tags "capacitor SMD 0402")
		(property "Reference" "C278"
			(at 4.296248 7.8885 0)
			(layer "F.SilkS")
			(effects
				(font
					(size 0.7 0.7)
					(thickness 0.15)
				)
				(justify left bottom)
			)
		)
		(property "Value" "C_22n_0402"
			(at 0 1.4 0)
			(layer "F.Fab")
			(effects
				(font
					(size 0.7 0.7)
					(thickness 0.15)
				)
				(justify left bottom)
			)
		)
		(property "Description" "SMD Multilayer Ceramic Capacitors, 0.022 µF, 50 V, 20%, 0402 [1005 Metric], X7R"
			(at 0 0 0)
			(layer "F.Fab")
			(hide yes)
			(effects
				(font
					(size 1.27 1.27)
					(thickness 0.15)
				)
			)
		)
		(property "Author" "Antmicro"
			(at 0 0 0)
			(layer "F.Fab")
			(hide yes)
			(effects
				(font
					(size 1 1)
					(thickness 0.15)
				)
			)
		)
		(property "Dielectric" ""
			(at 0 0 0)
			(layer "F.Fab")
			(hide yes)
			(effects
				(font
					(size 1 1)
					(thickness 0.15)
				)
			)
		)
		(property "License" "Apache-2.0"
			(at 0 0 0)
			(layer "F.Fab")
			(hide yes)
			(effects
				(font
					(size 1 1)
					(thickness 0.15)
				)
			)
		)
		(property "MPN" "GCM155R71H223MA55D"
			(at 0 0 0)
			(layer "F.Fab")
			(hide yes)
			(effects
				(font
					(size 1 1)
					(thickness 0.15)
				)
			)
		)
		(property "Manufacturer" "Murata"
			(at 0 0 0)
			(layer "F.Fab")
			(hide yes)
			(effects
				(font
					(size 1 1)
					(thickness 0.15)
				)
			)
		)
		(property "Val" "22n"
			(at 0 0 0)
			(layer "F.Fab")
			(hide yes)
			(effects
				(font
					(size 1 1)
					(thickness 0.15)
				)
			)
		)
		(property "Voltage" ""
			(at 0 0 0)
			(layer "F.Fab")
			(hide yes)
			(effects
				(font
					(size 1 1)
					(thickness 0.15)
				)
			)
		)
		(sheetname "HDMI + Ethernet")
		(sheetfile "hdmi-ethernet.kicad_sch")
		(attr smd)
		(fp_rect
			(start -0.925 -0.47)
			(end 0.925 0.47)
			(stroke
				(width 0.05)
				(type default)
			)
			(fill no)
			(layer "F.CrtYd")
		)
		(fp_line
			(start -0.494 -0.25)
			(end 0.504 -0.25)
			(stroke
				(width 0.15)
				(type solid)
			)
			(layer "F.Fab")
		)
		(fp_line
			(start -0.494 0.248)
			(end -0.494 -0.25)
			(stroke
				(width 0.15)
				(type solid)
			)
			(layer "F.Fab")
		)
		(fp_line
			(start 0.504 -0.25)
			(end 0.504 0.248)
			(stroke
				(width 0.15)
				(type solid)
			)
			(layer "F.Fab")
		)
		(fp_line
			(start 0.504 0.248)
			(end -0.494 0.248)
			(stroke
				(width 0.15)
				(type solid)
			)
			(layer "F.Fab")
		)
		(pad "1" smd roundrect
			(at -0.48 0)
			(size 0.59 0.64)
			(layers "F.Cu" "F.Mask" "F.Paste")
			(roundrect_rratio 0.25)
			(net 1 "GND")
			(pintype "passive")
		)
		(pad "2" smd roundrect
			(at 0.48 0)
			(size 0.59 0.64)
			(layers "F.Cu" "F.Mask" "F.Paste")
			(roundrect_rratio 0.25)
			(net 728 "/HDMI + Ethernet/GBE_AVDDL{slash}PLL")
			(pintype "passive")
		)
	)
	(footprint "antmicro-footprints:R_0402_1005Metric"
		(layer "F.Cu")
		(at 216.45 157.1 -90)
		(descr "Resistor SMD 0402")
		(tags "resistor SMD 0402")
		(property "Reference" "R82"
			(at -0.75 -0.4 270)
			(layer "F.SilkS")
			(effects
				(font
					(size 0.7 0.7)
					(thickness 0.15)
				)
				(justify left bottom)
			)
		)
		(property "Value" "R_0R_0402"
			(at 0 1.4 270)
			(layer "F.Fab")
			(effects
				(font
					(size 0.7 0.7)
					(thickness 0.15)
				)
				(justify left bottom)
			)
		)
		(property "Description" "SMD Chip Resistor, Jumper, 0 ohm, 100 mW, 0402 [1005 Metric], Thick Film, General Purpose"
			(at 0 0 270)
			(layer "F.Fab")
			(hide yes)
			(effects
				(font
					(size 1.27 1.27)
					(thickness 0.15)
				)
			)
		)
		(property "Author" "Antmicro"
			(at 59.35 373.55 0)
			(layer "F.Fab")
			(hide yes)
			(effects
				(font
					(size 1 1)
					(thickness 0.15)
				)
			)
		)
		(property "Current" "1A"
			(at 59.35 373.55 0)
			(layer "F.Fab")
			(hide yes)
			(effects
				(font
					(size 1 1)
					(thickness 0.15)
				)
			)
		)
		(property "License" "Apache-2.0"
			(at 59.35 373.55 0)
			(layer "F.Fab")
			(hide yes)
			(effects
				(font
					(size 1 1)
					(thickness 0.15)
				)
			)
		)
		(property "MPN" "ERJ2GE0R00X"
			(at 59.35 373.55 0)
			(layer "F.Fab")
			(hide yes)
			(effects
				(font
					(size 1 1)
					(thickness 0.15)
				)
			)
		)
		(property "Manufacturer" "Panasonic"
			(at 59.35 373.55 0)
			(layer "F.Fab")
			(hide yes)
			(effects
				(font
					(size 1 1)
					(thickness 0.15)
				)
			)
		)
		(property "Tolerance" ""
			(at 59.35 373.55 0)
			(layer "F.Fab")
			(hide yes)
			(effects
				(font
					(size 1 1)
					(thickness 0.15)
				)
			)
		)
		(property "Val" "0R"
			(at 59.35 373.55 0)
			(layer "F.Fab")
			(hide yes)
			(effects
				(font
					(size 1 1)
					(thickness 0.15)
				)
			)
		)
		(sheetname "SPI Flash + SD Card")
		(sheetfile "spi-flash.kicad_sch")
		(attr smd)
		(fp_rect
			(start -0.925 -0.47)
			(end 0.925 0.47)
			(stroke
				(width 0.05)
				(type default)
			)
			(fill no)
			(layer "F.CrtYd")
		)
		(fp_rect
			(start -0.5 -0.25)
			(end 0.5 0.25)
			(stroke
				(width 0.15)
				(type solid)
			)
			(fill no)
			(layer "F.Fab")
		)
		(pad "1" smd roundrect
			(at -0.48 0 270)
			(size 0.59 0.64)
			(layers "F.Cu" "F.Mask" "F.Paste")
			(roundrect_rratio 0.25)
			(net 410 "/FPGA Bank 33 & 34/USR_FLASH_0.DQ0")
			(pintype "passive")
		)
		(pad "2" smd roundrect
			(at 0.48 0 270)
			(size 0.59 0.64)
			(layers "F.Cu" "F.Mask" "F.Paste")
			(roundrect_rratio 0.25)
			(net 902 "/SPI Flash + SD Card/USR_FLASH_0_DQ0")
			(pintype "passive")
		)
	)
	(footprint "antmicro-footprints:SC70-3"
		(layer "F.Cu")
		(at 258.4 83.8)
		(property "Reference" "Q8"
			(at -1.6 1.1 90)
			(layer "F.SilkS")
			(effects
				(font
					(size 0.7 0.7)
					(thickness 0.15)
				)
				(justify left bottom)
			)
		)
		(property "Value" "BSS138PW"
			(at 0 2.3 0)
			(layer "F.Fab")
			(effects
				(font
					(size 0.7 0.7)
					(thickness 0.15)
				)
				(justify left bottom)
			)
		)
		(property "Description" "Power MOSFET, N Channel, 60 V, 320 mA, 0.9 ohm, SOT-323, Surface Mount"
			(at 0 0 0)
			(layer "F.Fab")
			(hide yes)
			(effects
				(font
					(size 1.27 1.27)
					(thickness 0.15)
				)
			)
		)
		(property "Author" "Antmicro"
			(at 0 0 0)
			(layer "F.Fab")
			(hide yes)
			(effects
				(font
					(size 1 1)
					(thickness 0.15)
				)
			)
		)
		(property "License" "Apache-2.0"
			(at 0 0 0)
			(layer "F.Fab")
			(hide yes)
			(effects
				(font
					(size 1 1)
					(thickness 0.15)
				)
			)
		)
		(property "MPN" "BSS138PW"
			(at 0 0 0)
			(layer "F.Fab")
			(hide yes)
			(effects
				(font
					(size 1 1)
					(thickness 0.15)
				)
			)
		)
		(property "Manufacturer" "Nexperia"
			(at 0 0 0)
			(layer "F.Fab")
			(hide yes)
			(effects
				(font
					(size 1 1)
					(thickness 0.15)
				)
			)
		)
		(sheetname "User GPIO + LED + button + DIP switch")
		(sheetfile "user-gpio.kicad_sch")
		(attr smd)
		(fp_line
			(start -0.3 -1)
			(end 0.627 -0.999)
			(stroke
				(width 0.15)
				(type solid)
			)
			(layer "F.SilkS")
		)
		(fp_line
			(start -0.3 1)
			(end 0.627 1.001)
			(stroke
				(width 0.15)
				(type solid)
			)
			(layer "F.SilkS")
		)
		(fp_line
			(start 0.627 -0.6)
			(end 0.627 -0.999)
			(stroke
				(width 0.15)
				(type solid)
			)
			(layer "F.SilkS")
		)
		(fp_line
			(start 0.627 0.6)
			(end 0.627 1.001)
			(stroke
				(width 0.15)
				(type solid)
			)
			(layer "F.SilkS")
		)
		(fp_line
			(start -1.4 1)
			(end -1.4 -1)
			(stroke
				(width 0.05)
				(type solid)
			)
			(layer "F.CrtYd")
		)
		(fp_line
			(start -0.9 -1.3)
			(end -0.9 -1)
			(stroke
				(width 0.05)
				(type solid)
			)
			(layer "F.CrtYd")
		)
		(fp_line
			(start -0.9 -1.3)
			(end 0.9 -1.3)
			(stroke
				(width 0.05)
				(type solid)
			)
			(layer "F.CrtYd")
		)
		(fp_line
			(start -0.9 -1)
			(end -1.4 -1)
			(stroke
				(width 0.05)
				(type solid)
			)
			(layer "F.CrtYd")
		)
		(fp_line
			(start -0.9 1)
			(end -1.4 1)
			(stroke
				(width 0.05)
				(type solid)
			)
			(layer "F.CrtYd")
		)
		(fp_line
			(start -0.9 1.3)
			(end -0.9 1)
			(stroke
				(width 0.05)
				(type solid)
			)
			(layer "F.CrtYd")
		)
		(fp_line
			(start 0.9 -1.3)
			(end 0.9 -0.4)
			(stroke
				(width 0.05)
				(type solid)
			)
			(layer "F.CrtYd")
		)
		(fp_line
			(start 0.9 -0.4)
			(end 1.4 -0.4)
			(stroke
				(width 0.05)
				(type solid)
			)
			(layer "F.CrtYd")
		)
		(fp_line
			(start 0.9 0.4)
			(end 0.9 1.3)
			(stroke
				(width 0.05)
				(type solid)
			)
			(layer "F.CrtYd")
		)
		(fp_line
			(start 0.9 1.3)
			(end -0.9 1.3)
			(stroke
				(width 0.05)
				(type solid)
			)
			(layer "F.CrtYd")
		)
		(fp_line
			(start 1.4 -0.4)
			(end 1.4 0.4)
			(stroke
				(width 0.05)
				(type solid)
			)
			(layer "F.CrtYd")
		)
		(fp_line
			(start 1.4 0.4)
			(end 0.9 0.4)
			(stroke
				(width 0.05)
				(type solid)
			)
			(layer "F.CrtYd")
		)
		(fp_rect
			(start -0.623 -0.999)
			(end 0.627 1.001)
			(stroke
				(width 0.15)
				(type solid)
			)
			(fill no)
			(layer "F.Fab")
		)
		(pad "1" smd rect
			(at -1.051 -0.65 90)
			(size 0.6 0.6)
			(layers "F.Cu" "F.Mask" "F.Paste")
			(net 1299 "/USER_IO.LED_GREEN0")
			(pinfunction "G")
			(pintype "passive")
		)
		(pad "2" smd rect
			(at -1.051 0.65 90)
			(size 0.6 0.6)
			(layers "F.Cu" "F.Mask" "F.Paste")
			(net 1 "GND")
			(pinfunction "S")
			(pintype "passive")
		)
		(pad "3" smd rect
			(at 1.05 0 90)
			(size 0.6 0.6)
			(layers "F.Cu" "F.Mask" "F.Paste")
			(net 772 "Net-(D18-C)")
			(pinfunction "D")
			(pintype "passive")
		)
	)
	(footprint "antmicro-footprints:R_0402_1005Metric"
		(layer "F.Cu")
		(at 235.925 110.6 180)
		(descr "Resistor SMD 0402")
		(tags "resistor SMD 0402")
		(property "Reference" "R93"
			(at -0.8 -0.375 180)
			(layer "F.SilkS")
			(effects
				(font
					(size 0.7 0.7)
					(thickness 0.15)
				)
				(justify left bottom)
			)
		)
		(property "Value" "R_10k_0402"
			(at 0 1.4 180)
			(layer "F.Fab")
			(effects
				(font
					(size 0.7 0.7)
					(thickness 0.15)
				)
				(justify left bottom)
			)
		)
		(property "Description" "SMD Chip Resistor, 10 kohm, ± 1%, 62.5 mW, 0402 [1005 Metric], Thick Film, General Purpose"
			(at 0 0 180)
			(layer "F.Fab")
			(hide yes)
			(effects
				(font
					(size 1.27 1.27)
					(thickness 0.15)
				)
			)
		)
		(property "Author" "Antmicro"
			(at 471.85 221.2 0)
			(layer "F.Fab")
			(hide yes)
			(effects
				(font
					(size 1 1)
					(thickness 0.15)
				)
			)
		)
		(property "License" "Apache-2.0"
			(at 471.85 221.2 0)
			(layer "F.Fab")
			(hide yes)
			(effects
				(font
					(size 1 1)
					(thickness 0.15)
				)
			)
		)
		(property "MPN" "CR0402-FX-1002GLF"
			(at 471.85 221.2 0)
			(layer "F.Fab")
			(hide yes)
			(effects
				(font
					(size 1 1)
					(thickness 0.15)
				)
			)
		)
		(property "Manufacturer" "Bourns"
			(at 471.85 221.2 0)
			(layer "F.Fab")
			(hide yes)
			(effects
				(font
					(size 1 1)
					(thickness 0.15)
				)
			)
		)
		(property "Tolerance" "1%"
			(at 471.85 221.2 0)
			(layer "F.Fab")
			(hide yes)
			(effects
				(font
					(size 1 1)
					(thickness 0.15)
				)
			)
		)
		(property "Val" "10k"
			(at 471.85 221.2 0)
			(layer "F.Fab")
			(hide yes)
			(effects
				(font
					(size 1 1)
					(thickness 0.15)
				)
			)
		)
		(sheetname "SPI Flash + SD Card")
		(sheetfile "spi-flash.kicad_sch")
		(attr smd)
		(fp_rect
			(start -0.925 -0.47)
			(end 0.925 0.47)
			(stroke
				(width 0.05)
				(type default)
			)
			(fill no)
			(layer "F.CrtYd")
		)
		(fp_rect
			(start -0.5 -0.25)
			(end 0.5 0.25)
			(stroke
				(width 0.15)
				(type solid)
			)
			(fill no)
			(layer "F.Fab")
		)
		(pad "1" smd roundrect
			(at -0.48 0 180)
			(size 0.59 0.64)
			(layers "F.Cu" "F.Mask" "F.Paste")
			(roundrect_rratio 0.25)
			(net 417 "/FPGA Bank 16 & 17/USR_FLASH_1.DQ3")
			(pintype "passive")
		)
		(pad "2" smd roundrect
			(at 0.48 0 180)
			(size 0.59 0.64)
			(layers "F.Cu" "F.Mask" "F.Paste")
			(roundrect_rratio 0.25)
			(net 3 "VCC_USR_B")
			(pintype "passive")
		)
	)
	(footprint "antmicro-footprints:R_0402_1005Metric"
		(layer "F.Cu")
		(at 225.025 118.5)
		(descr "Resistor SMD 0402")
		(tags "resistor SMD 0402")
		(property "Reference" "R74"
			(at -2.975 0.4 0)
			(layer "F.SilkS")
			(effects
				(font
					(size 0.7 0.7)
					(thickness 0.15)
				)
				(justify left bottom)
			)
		)
		(property "Value" "R_0R_0402"
			(at 0 1.4 0)
			(layer "F.Fab")
			(effects
				(font
					(size 0.7 0.7)
					(thickness 0.15)
				)
				(justify left bottom)
			)
		)
		(property "Description" "SMD Chip Resistor, Jumper, 0 ohm, 100 mW, 0402 [1005 Metric], Thick Film, General Purpose"
			(at 0 0 0)
			(layer "F.Fab")
			(hide yes)
			(effects
				(font
					(size 1.27 1.27)
					(thickness 0.15)
				)
			)
		)
		(property "Author" "Antmicro"
			(at 0 0 0)
			(layer "F.Fab")
			(hide yes)
			(effects
				(font
					(size 1 1)
					(thickness 0.15)
				)
			)
		)
		(property "Current" "1A"
			(at 0 0 0)
			(layer "F.Fab")
			(hide yes)
			(effects
				(font
					(size 1 1)
					(thickness 0.15)
				)
			)
		)
		(property "License" "Apache-2.0"
			(at 0 0 0)
			(layer "F.Fab")
			(hide yes)
			(effects
				(font
					(size 1 1)
					(thickness 0.15)
				)
			)
		)
		(property "MPN" "ERJ2GE0R00X"
			(at 0 0 0)
			(layer "F.Fab")
			(hide yes)
			(effects
				(font
					(size 1 1)
					(thickness 0.15)
				)
			)
		)
		(property "Manufacturer" "Panasonic"
			(at 0 0 0)
			(layer "F.Fab")
			(hide yes)
			(effects
				(font
					(size 1 1)
					(thickness 0.15)
				)
			)
		)
		(property "Tolerance" ""
			(at 0 0 0)
			(layer "F.Fab")
			(hide yes)
			(effects
				(font
					(size 1 1)
					(thickness 0.15)
				)
			)
		)
		(property "Val" "0R"
			(at 0 0 0)
			(layer "F.Fab")
			(hide yes)
			(effects
				(font
					(size 1 1)
					(thickness 0.15)
				)
			)
		)
		(sheetname "SPI Flash + SD Card")
		(sheetfile "spi-flash.kicad_sch")
		(attr smd)
		(fp_rect
			(start -0.925 -0.47)
			(end 0.925 0.47)
			(stroke
				(width 0.05)
				(type default)
			)
			(fill no)
			(layer "F.CrtYd")
		)
		(fp_rect
			(start -0.5 -0.25)
			(end 0.5 0.25)
			(stroke
				(width 0.15)
				(type solid)
			)
			(fill no)
			(layer "F.Fab")
		)
		(pad "1" smd roundrect
			(at -0.48 0)
			(size 0.59 0.64)
			(layers "F.Cu" "F.Mask" "F.Paste")
			(roundrect_rratio 0.25)
			(net 75 "/FPGA Bank 14 & 15/SYSTEM_FLASH.~{CS}")
			(pintype "passive")
		)
		(pad "2" smd roundrect
			(at 0.48 0)
			(size 0.59 0.64)
			(layers "F.Cu" "F.Mask" "F.Paste")
			(roundrect_rratio 0.25)
			(net 894 "/SPI Flash + SD Card/SYSTEM_FLASH_~{CS}")
			(pintype "passive")
		)
	)
	(footprint "antmicro-footprints:TP_SMD_0.75mm"
		(layer "F.Cu")
		(at 174.16 81.1308 180)
		(property "Reference" "TP1"
			(at -0.34 0.3308 270)
			(layer "F.SilkS")
			(effects
				(font
					(size 0.7 0.7)
					(thickness 0.15)
				)
				(justify left bottom)
			)
		)
		(property "Value" "TP_0.75mm_SMD"
			(at 0 1.2 180)
			(layer "F.Fab")
			(effects
				(font
					(size 0.7 0.7)
					(thickness 0.15)
				)
				(justify left bottom)
			)
		)
		(property "Description" "SMT test point"
			(at 0 0 180)
			(layer "F.Fab")
			(hide yes)
			(effects
				(font
					(size 1.27 1.27)
					(thickness 0.15)
				)
			)
		)
		(property "Author" "Antmicro"
			(at 348.32 162.2616 0)
			(layer "F.Fab")
			(hide yes)
			(effects
				(font
					(size 1 1)
					(thickness 0.15)
				)
			)
		)
		(property "License" "Apache-2.0"
			(at 348.32 162.2616 0)
			(layer "F.Fab")
			(hide yes)
			(effects
				(font
					(size 1 1)
					(thickness 0.15)
				)
			)
		)
		(property "MPN" ""
			(at 348.32 162.2616 0)
			(layer "F.Fab")
			(hide yes)
			(effects
				(font
					(size 1 1)
					(thickness 0.15)
				)
			)
		)
		(property "Manufacturer" ""
			(at 348.32 162.2616 0)
			(layer "F.Fab")
			(hide yes)
			(effects
				(font
					(size 1 1)
					(thickness 0.15)
				)
			)
		)
		(sheetname "FMC+ HSPC")
		(sheetfile "fmc-hspc.kicad_sch")
		(attr exclude_from_pos_files)
		(pad "1" smd circle
			(at 0 0 180)
			(size 0.75 0.75)
			(layers "F.Cu" "F.Mask")
			(net 194 "Net-(J18A-VREF_A_M2C)")
			(pinfunction "1")
			(pintype "passive")
		)
	)
	(footprint "antmicro-footprints:Nexperia_SOD128"
		(layer "F.Cu")
		(at 188.825 187.699)
		(property "Reference" "D15"
			(at -3.225 0.001 90)
			(layer "F.SilkS")
			(effects
				(font
					(size 0.7 0.7)
					(thickness 0.15)
				)
			)
		)
		(property "Value" "PMEG3050EP,115"
			(at 0 2.4765 0)
			(layer "F.Fab")
			(effects
				(font
					(size 1 1)
					(thickness 0.15)
				)
			)
		)
		(property "Description" "Schottky Rectifier, 30 V, 5 A, Single, SOD-128, 2 Pins, 360 mV"
			(at 0 0 0)
			(layer "F.Fab")
			(hide yes)
			(effects
				(font
					(size 1.27 1.27)
					(thickness 0.15)
				)
			)
		)
		(property "Author" "Antmicro"
			(at 0 0 0)
			(layer "F.Fab")
			(hide yes)
			(effects
				(font
					(size 1 1)
					(thickness 0.15)
				)
			)
		)
		(property "DNP" "DNP"
			(at 0 0 0)
			(layer "F.Fab")
			(hide yes)
			(effects
				(font
					(size 1 1)
					(thickness 0.15)
				)
			)
		)
		(property "License" "Apache-2.0"
			(at 0 0 0)
			(layer "F.Fab")
			(hide yes)
			(effects
				(font
					(size 1 1)
					(thickness 0.15)
				)
			)
		)
		(property "MPN" "PMEG3050EP,115"
			(at 0 0 0)
			(layer "F.Fab")
			(hide yes)
			(effects
				(font
					(size 1 1)
					(thickness 0.15)
				)
			)
		)
		(property "Manufacturer" "Nexperia"
			(at 0 0 0)
			(layer "F.Fab")
			(hide yes)
			(effects
				(font
					(size 1 1)
					(thickness 0.15)
				)
			)
		)
		(property "dnp" ""
			(at 0 0 0)
			(layer "F.Fab")
			(hide yes)
			(effects
				(font
					(size 1 1)
					(thickness 0.15)
				)
			)
		)
		(property "exclude_from_bom" ""
			(at 0 0 0)
			(layer "F.Fab")
			(hide yes)
			(effects
				(font
					(size 1 1)
					(thickness 0.15)
				)
			)
		)
		(sheetname "Power supply")
		(sheetfile "power-supply.kicad_sch")
		(attr smd exclude_from_bom)
		(fp_line
			(start -2.121 -1.474)
			(end -2.121 -1.287)
			(stroke
				(width 0.15)
				(type solid)
			)
			(layer "F.SilkS")
		)
		(fp_line
			(start -2.121 1.284)
			(end -2.121 1.473)
			(stroke
				(width 0.15)
				(type solid)
			)
			(layer "F.SilkS")
		)
		(fp_line
			(start -2.121 1.473)
			(end 2.12 1.473)
			(stroke
				(width 0.15)
				(type solid)
			)
			(layer "F.SilkS")
		)
		(fp_line
			(start -1.6 -1.4)
			(end -1.6 1.4)
			(stroke
				(width 0.12)
				(type solid)
			)
			(layer "F.SilkS")
		)
		(fp_line
			(start 2.12 -1.474)
			(end -2.121 -1.474)
			(stroke
				(width 0.15)
				(type solid)
			)
			(layer "F.SilkS")
		)
		(fp_line
			(start 2.12 -1.287)
			(end 2.12 -1.474)
			(stroke
				(width 0.15)
				(type solid)
			)
			(layer "F.SilkS")
		)
		(fp_line
			(start 2.12 1.473)
			(end 2.12 1.284)
			(stroke
				(width 0.15)
				(type solid)
			)
			(layer "F.SilkS")
		)
		(fp_rect
			(start -2.8 -1.6)
			(end 2.8 1.6)
			(stroke
				(width 0.05)
				(type solid)
			)
			(fill no)
			(layer "F.CrtYd")
		)
		(fp_line
			(start -2.503 -0.954)
			(end -2.503 0.952)
			(stroke
				(width 0.15)
				(type solid)
			)
			(layer "F.Fab")
		)
		(fp_line
			(start -2.503 0.952)
			(end -1.994 0.952)
			(stroke
				(width 0.15)
				(type solid)
			)
			(layer "F.Fab")
		)
		(fp_line
			(start -1.994 -1.347)
			(end -1.994 1.346)
			(stroke
				(width 0.15)
				(type solid)
			)
			(layer "F.Fab")
		)
		(fp_line
			(start -1.994 -0.954)
			(end -2.503 -0.954)
			(stroke
				(width 0.15)
				(type solid)
			)
			(layer "F.Fab")
		)
		(fp_line
			(start -1.994 -0.675)
			(end -1.321 -1.347)
			(stroke
				(width 0.15)
				(type solid)
			)
			(layer "F.Fab")
		)
		(fp_line
			(start -1.994 0.673)
			(end -1.321 1.346)
			(stroke
				(width 0.15)
				(type solid)
			)
			(layer "F.Fab")
		)
		(fp_line
			(start -1.994 0.952)
			(end -1.994 -0.954)
			(stroke
				(width 0.15)
				(type solid)
			)
			(layer "F.Fab")
		)
		(fp_line
			(start -1.994 1.346)
			(end 1.993 1.346)
			(stroke
				(width 0.15)
				(type solid)
			)
			(layer "F.Fab")
		)
		(fp_line
			(start 1.993 -1.347)
			(end -1.994 -1.347)
			(stroke
				(width 0.15)
				(type solid)
			)
			(layer "F.Fab")
		)
		(fp_line
			(start 1.993 -0.954)
			(end 1.993 0.952)
			(stroke
				(width 0.15)
				(type solid)
			)
			(layer "F.Fab")
		)
		(fp_line
			(start 1.993 0.952)
			(end 2.5 0.952)
			(stroke
				(width 0.15)
				(type solid)
			)
			(layer "F.Fab")
		)
		(fp_line
			(start 1.993 1.346)
			(end 1.993 -1.347)
			(stroke
				(width 0.15)
				(type solid)
			)
			(layer "F.Fab")
		)
		(fp_line
			(start 2.5 -0.954)
			(end 1.993 -0.954)
			(stroke
				(width 0.15)
				(type solid)
			)
			(layer "F.Fab")
		)
		(fp_line
			(start 2.5 0.952)
			(end 2.5 -0.954)
			(stroke
				(width 0.15)
				(type solid)
			)
			(layer "F.Fab")
		)
		(pad "1" smd rect
			(at -2.298 0)
			(size 0.8096 1.905)
			(layers "F.Cu" "F.Mask" "F.Paste")
			(net 702 "VDC")
			(pinfunction "1")
			(pintype "passive")
		)
		(pad "2" smd rect
			(at 2.297 0)
			(size 0.8096 1.905)
			(layers "F.Cu" "F.Mask" "F.Paste")
			(net 4 "/Power supply/DC_IN")
			(pinfunction "2")
			(pintype "passive")
		)
	)
	(footprint "antmicro-footprints:C_0402_1005Metric"
		(layer "F.Cu")
		(at 166.7 140 180)
		(descr "Capacitor SMD 0402")
		(tags "capacitor SMD 0402")
		(property "Reference" "C390"
			(at -0.8 -0.35 180)
			(layer "F.SilkS")
			(effects
				(font
					(size 0.7 0.7)
					(thickness 0.15)
				)
				(justify left bottom)
			)
		)
		(property "Value" "C_100n_0402"
			(at 0 1.169 180)
			(layer "F.Fab")
			(effects
				(font
					(size 0.7 0.7)
					(thickness 0.15)
				)
				(justify left bottom)
			)
		)
		(property "Description" "SMD Multilayer Ceramic Capacitor, 0.1 µF, 50 V, 0402 [1005 Metric], ± 10%, X5R, GRM Series"
			(at 0 0 180)
			(layer "F.Fab")
			(hide yes)
			(effects
				(font
					(size 1.27 1.27)
					(thickness 0.15)
				)
			)
		)
		(property "Author" "Antmicro"
			(at 333.4 280 0)
			(layer "F.Fab")
			(hide yes)
			(effects
				(font
					(size 1 1)
					(thickness 0.15)
				)
			)
		)
		(property "Dielectric" "X5R"
			(at 333.4 280 0)
			(layer "F.Fab")
			(hide yes)
			(effects
				(font
					(size 1 1)
					(thickness 0.15)
				)
			)
		)
		(property "License" "Apache-2.0"
			(at 333.4 280 0)
			(layer "F.Fab")
			(hide yes)
			(effects
				(font
					(size 1 1)
					(thickness 0.15)
				)
			)
		)
		(property "MPN" "GRM155R61H104KE14D"
			(at 333.4 280 0)
			(layer "F.Fab")
			(hide yes)
			(effects
				(font
					(size 1 1)
					(thickness 0.15)
				)
			)
		)
		(property "Manufacturer" "Murata"
			(at 333.4 280 0)
			(layer "F.Fab")
			(hide yes)
			(effects
				(font
					(size 1 1)
					(thickness 0.15)
				)
			)
		)
		(property "Val" "100n"
			(at 333.4 280 0)
			(layer "F.Fab")
			(hide yes)
			(effects
				(font
					(size 1 1)
					(thickness 0.15)
				)
			)
		)
		(property "Voltage" "50V"
			(at 333.4 280 0)
			(layer "F.Fab")
			(hide yes)
			(effects
				(font
					(size 1 1)
					(thickness 0.15)
				)
			)
		)
		(sheetname "DRAM + SRAM")
		(sheetfile "ram.kicad_sch")
		(attr smd)
		(fp_rect
			(start -0.925 -0.47)
			(end 0.925 0.47)
			(stroke
				(width 0.05)
				(type default)
			)
			(fill no)
			(layer "F.CrtYd")
		)
		(fp_line
			(start 0.504 0.248)
			(end -0.494 0.248)
			(stroke
				(width 0.15)
				(type solid)
			)
			(layer "F.Fab")
		)
		(fp_line
			(start 0.504 -0.25)
			(end 0.504 0.248)
			(stroke
				(width 0.15)
				(type solid)
			)
			(layer "F.Fab")
		)
		(fp_line
			(start -0.494 0.248)
			(end -0.494 -0.25)
			(stroke
				(width 0.15)
				(type solid)
			)
			(layer "F.Fab")
		)
		(fp_line
			(start -0.494 -0.25)
			(end 0.504 -0.25)
			(stroke
				(width 0.15)
				(type solid)
			)
			(layer "F.Fab")
		)
		(pad "1" smd roundrect
			(at -0.48 0 180)
			(size 0.59 0.64)
			(layers "F.Cu" "F.Mask" "F.Paste")
			(roundrect_rratio 0.25)
			(net 1 "GND")
			(pintype "passive")
		)
		(pad "2" smd roundrect
			(at 0.48 0 180)
			(size 0.59 0.64)
			(layers "F.Cu" "F.Mask" "F.Paste")
			(roundrect_rratio 0.25)
			(net 25 "+1V35")
			(pintype "passive")
		)
	)
	(footprint "antmicro-footprints:C_0805_2012Metric"
		(layer "F.Cu")
		(at 191.5 161.949 -90)
		(descr "Capacitor SMD 0805")
		(tags "capacitor SMD 0805")
		(property "Reference" "C345"
			(at -1.399 3.15 90)
			(layer "F.SilkS")
			(effects
				(font
					(size 0.7 0.7)
					(thickness 0.15)
				)
				(justify right bottom)
			)
		)
		(property "Value" "C_22u_25V_0805"
			(at 0 1.947 90)
			(layer "F.Fab")
			(effects
				(font
					(size 0.7 0.7)
					(thickness 0.15)
				)
				(justify right bottom)
			)
		)
		(property "Description" "SMT Multilayer Ceramic Capacitor, 22uF, +/-20%, 25V, X5R, 0805 [2012 Metric]"
			(at 0 0 270)
			(layer "F.Fab")
			(hide yes)
			(effects
				(font
					(size 1.27 1.27)
					(thickness 0.15)
				)
			)
		)
		(property "Author" "Antmicro"
			(at 29.551 353.449 0)
			(layer "F.Fab")
			(hide yes)
			(effects
				(font
					(size 1 1)
					(thickness 0.15)
				)
			)
		)
		(property "Dielectric" "X5R"
			(at 29.551 353.449 0)
			(layer "F.Fab")
			(hide yes)
			(effects
				(font
					(size 1 1)
					(thickness 0.15)
				)
			)
		)
		(property "License" "Apache-2.0"
			(at 29.551 353.449 0)
			(layer "F.Fab")
			(hide yes)
			(effects
				(font
					(size 1 1)
					(thickness 0.15)
				)
			)
		)
		(property "MPN" "CL21A226MAYNNNE"
			(at 29.551 353.449 0)
			(layer "F.Fab")
			(hide yes)
			(effects
				(font
					(size 1 1)
					(thickness 0.15)
				)
			)
		)
		(property "Manufacturer" "Samsung Electro-Mechanics"
			(at 29.551 353.449 0)
			(layer "F.Fab")
			(hide yes)
			(effects
				(font
					(size 1 1)
					(thickness 0.15)
				)
			)
		)
		(property "Val" "22u"
			(at 29.551 353.449 0)
			(layer "F.Fab")
			(hide yes)
			(effects
				(font
					(size 1 1)
					(thickness 0.15)
				)
			)
		)
		(property "Voltage" "25V"
			(at 29.551 353.449 0)
			(layer "F.Fab")
			(hide yes)
			(effects
				(font
					(size 1 1)
					(thickness 0.15)
				)
			)
		)
		(sheetname "DC-DC Converters")
		(sheetfile "dc-dc.kicad_sch")
		(attr smd)
		(fp_line
			(start -0.3 0.7)
			(end 0.3 0.7)
			(stroke
				(width 0.15)
				(type solid)
			)
			(layer "F.SilkS")
		)
		(fp_line
			(start -0.3 -0.7)
			(end 0.3 -0.7)
			(stroke
				(width 0.15)
				(type solid)
			)
			(layer "F.SilkS")
		)
		(fp_rect
			(start 1.95 -0.9)
			(end -1.95 0.9)
			(stroke
				(width 0.05)
				(type default)
			)
			(fill no)
			(layer "F.CrtYd")
		)
		(fp_rect
			(start -0.95 -0.675)
			(end 0.95 0.675)
			(stroke
				(width 0.15)
				(type solid)
			)
			(fill no)
			(layer "F.Fab")
		)
		(pad "1" smd roundrect
			(at -1.1 0 270)
			(size 1.2 1.3)
			(layers "F.Cu" "F.Mask" "F.Paste")
			(roundrect_rratio 0.25)
			(net 1 "GND")
			(pintype "passive")
		)
		(pad "2" smd roundrect
			(at 1.1 0 270)
			(size 1.2 1.3)
			(layers "F.Cu" "F.Mask" "F.Paste")
			(roundrect_rratio 0.25)
			(net 702 "VDC")
			(pintype "passive")
		)
	)
	(footprint "antmicro-footprints:C_0402_1005Metric"
		(layer "F.Cu")
		(at 173.570001 118.510001 180)
		(descr "Capacitor SMD 0402")
		(tags "capacitor SMD 0402")
		(property "Reference" "C305"
			(at -3.729999 -0.342499 0)
			(layer "F.SilkS")
			(effects
				(font
					(size 0.7 0.7)
					(thickness 0.15)
				)
				(justify right bottom)
			)
		)
		(property "Value" "C_100n_0402"
			(at 0 1.4 0)
			(layer "F.Fab")
			(effects
				(font
					(size 0.7 0.7)
					(thickness 0.15)
				)
				(justify right bottom)
			)
		)
		(property "Description" "SMD Multilayer Ceramic Capacitor, 0.1 µF, 50 V, 0402 [1005 Metric], ± 10%, X5R, GRM Series"
			(at 0 0 180)
			(layer "F.Fab")
			(hide yes)
			(effects
				(font
					(size 1.27 1.27)
					(thickness 0.15)
				)
			)
		)
		(property "Author" "Antmicro"
			(at 347.140002 237.020002 0)
			(layer "F.Fab")
			(hide yes)
			(effects
				(font
					(size 1 1)
					(thickness 0.15)
				)
			)
		)
		(property "Dielectric" "X5R"
			(at 347.140002 237.020002 0)
			(layer "F.Fab")
			(hide yes)
			(effects
				(font
					(size 1 1)
					(thickness 0.15)
				)
			)
		)
		(property "License" "Apache-2.0"
			(at 347.140002 237.020002 0)
			(layer "F.Fab")
			(hide yes)
			(effects
				(font
					(size 1 1)
					(thickness 0.15)
				)
			)
		)
		(property "MPN" "GRM155R61H104KE14D"
			(at 347.140002 237.020002 0)
			(layer "F.Fab")
			(hide yes)
			(effects
				(font
					(size 1 1)
					(thickness 0.15)
				)
			)
		)
		(property "Manufacturer" "Murata"
			(at 347.140002 237.020002 0)
			(layer "F.Fab")
			(hide yes)
			(effects
				(font
					(size 1 1)
					(thickness 0.15)
				)
			)
		)
		(property "Val" "100n"
			(at 347.140002 237.020002 0)
			(layer "F.Fab")
			(hide yes)
			(effects
				(font
					(size 1 1)
					(thickness 0.15)
				)
			)
		)
		(property "Voltage" "50V"
			(at 347.140002 237.020002 0)
			(layer "F.Fab")
			(hide yes)
			(effects
				(font
					(size 1 1)
					(thickness 0.15)
				)
			)
		)
		(sheetname "FMC+ HSPC")
		(sheetfile "fmc-hspc.kicad_sch")
		(attr smd)
		(fp_rect
			(start -0.925 -0.47)
			(end 0.925 0.47)
			(stroke
				(width 0.05)
				(type default)
			)
			(fill no)
			(layer "F.CrtYd")
		)
		(fp_line
			(start 0.504 0.248)
			(end -0.494 0.248)
			(stroke
				(width 0.15)
				(type solid)
			)
			(layer "F.Fab")
		)
		(fp_line
			(start 0.504 -0.25)
			(end 0.504 0.248)
			(stroke
				(width 0.15)
				(type solid)
			)
			(layer "F.Fab")
		)
		(fp_line
			(start -0.494 0.248)
			(end -0.494 -0.25)
			(stroke
				(width 0.15)
				(type solid)
			)
			(layer "F.Fab")
		)
		(fp_line
			(start -0.494 -0.25)
			(end 0.504 -0.25)
			(stroke
				(width 0.15)
				(type solid)
			)
			(layer "F.Fab")
		)
		(pad "1" smd roundrect
			(at -0.48 0 180)
			(size 0.59 0.64)
			(layers "F.Cu" "F.Mask" "F.Paste")
			(roundrect_rratio 0.25)
			(net 82 "/FMC+ HSPC/GTX116.TX0_N")
			(pintype "passive")
		)
		(pad "2" smd roundrect
			(at 0.48 0 180)
			(size 0.59 0.64)
			(layers "F.Cu" "F.Mask" "F.Paste")
			(roundrect_rratio 0.25)
			(net 81 "/FMC+ HSPC/GTX_TX3_C_N")
			(pintype "passive")
		)
	)
	(footprint "antmicro-footprints:R_0402_1005Metric"
		(layer "F.Cu")
		(at 194.1 167.149 180)
		(descr "Resistor SMD 0402")
		(tags "resistor SMD 0402")
		(property "Reference" "R332"
			(at -0.375 -4.101 180)
			(layer "F.SilkS")
			(effects
				(font
					(size 0.7 0.7)
					(thickness 0.15)
				)
				(justify left bottom)
			)
		)
		(property "Value" "R_205k_0402"
			(at 0 1.4 180)
			(layer "F.Fab")
			(effects
				(font
					(size 0.7 0.7)
					(thickness 0.15)
				)
				(justify left bottom)
			)
		)
		(property "Description" "SMD Chip Resistor"
			(at 0 0 180)
			(layer "F.Fab")
			(hide yes)
			(effects
				(font
					(size 1.27 1.27)
					(thickness 0.15)
				)
			)
		)
		(property "Author" "Antmicro"
			(at 388.2 334.298 0)
			(layer "F.Fab")
			(hide yes)
			(effects
				(font
					(size 1 1)
					(thickness 0.15)
				)
			)
		)
		(property "License" "Apache-2.0"
			(at 388.2 334.298 0)
			(layer "F.Fab")
			(hide yes)
			(effects
				(font
					(size 1 1)
					(thickness 0.15)
				)
			)
		)
		(property "MPN" "CR0402-FX-2053GLF"
			(at 388.2 334.298 0)
			(layer "F.Fab")
			(hide yes)
			(effects
				(font
					(size 1 1)
					(thickness 0.15)
				)
			)
		)
		(property "Manufacturer" "Bourns"
			(at 388.2 334.298 0)
			(layer "F.Fab")
			(hide yes)
			(effects
				(font
					(size 1 1)
					(thickness 0.15)
				)
			)
		)
		(property "Tolerance" "1%"
			(at 388.2 334.298 0)
			(layer "F.Fab")
			(hide yes)
			(effects
				(font
					(size 1 1)
					(thickness 0.15)
				)
			)
		)
		(property "Val" "205k"
			(at 388.2 334.298 0)
			(layer "F.Fab")
			(hide yes)
			(effects
				(font
					(size 1 1)
					(thickness 0.15)
				)
			)
		)
		(sheetname "DC-DC Converters")
		(sheetfile "dc-dc.kicad_sch")
		(attr smd)
		(fp_rect
			(start -0.925 -0.47)
			(end 0.925 0.47)
			(stroke
				(width 0.05)
				(type default)
			)
			(fill no)
			(layer "F.CrtYd")
		)
		(fp_rect
			(start -0.5 -0.25)
			(end 0.5 0.25)
			(stroke
				(width 0.15)
				(type solid)
			)
			(fill no)
			(layer "F.Fab")
		)
		(pad "1" smd roundrect
			(at -0.48 0 180)
			(size 0.59 0.64)
			(layers "F.Cu" "F.Mask" "F.Paste")
			(roundrect_rratio 0.25)
			(net 1 "GND")
			(pintype "passive")
		)
		(pad "2" smd roundrect
			(at 0.48 0 180)
			(size 0.59 0.64)
			(layers "F.Cu" "F.Mask" "F.Paste")
			(roundrect_rratio 0.25)
			(net 1230 "Net-(C364-Pad1)")
			(pintype "passive")
		)
	)
	(footprint "antmicro-footprints:DFN-10-1EP_3x3mm"
		(layer "F.Cu")
		(at 155.175 154.7 180)
		(property "Reference" "U39"
			(at -2.175 1.9 180)
			(layer "F.SilkS")
			(effects
				(font
					(size 0.7 0.7)
					(thickness 0.15)
				)
				(justify right bottom)
			)
		)
		(property "Value" "NCP51400MNTXG"
			(at 0 2.8 0)
			(layer "F.Fab")
			(effects
				(font
					(size 0.7 0.7)
					(thickness 0.15)
				)
				(justify right bottom)
			)
		)
		(property "Description" "Fixed LDO Voltage Regulator, 2.375V to 5.5V, 1.2 V Drop, 750 mV/3A out, DFN-10 Pins"
			(at 0 0 180)
			(layer "F.Fab")
			(hide yes)
			(effects
				(font
					(size 1.27 1.27)
					(thickness 0.15)
				)
			)
		)
		(property "Author" "Antmicro"
			(at 310.35 309.4 0)
			(layer "F.Fab")
			(hide yes)
			(effects
				(font
					(size 1 1)
					(thickness 0.15)
				)
			)
		)
		(property "License" "Apache-2.0"
			(at 310.35 309.4 0)
			(layer "F.Fab")
			(hide yes)
			(effects
				(font
					(size 1 1)
					(thickness 0.15)
				)
			)
		)
		(property "MPN" "NCP51400MNTXG"
			(at 310.35 309.4 0)
			(layer "F.Fab")
			(hide yes)
			(effects
				(font
					(size 1 1)
					(thickness 0.15)
				)
			)
		)
		(property "Manufacturer" "ON Semiconductor"
			(at 310.35 309.4 0)
			(layer "F.Fab")
			(hide yes)
			(effects
				(font
					(size 1 1)
					(thickness 0.15)
				)
			)
		)
		(sheetname "DC-DC Converters")
		(sheetfile "dc-dc.kicad_sch")
		(attr smd)
		(fp_line
			(start 1.601 1.6)
			(end 1.601 1.35)
			(stroke
				(width 0.15)
				(type solid)
			)
			(layer "F.SilkS")
		)
		(fp_line
			(start 1.601 1.6)
			(end 1.401 1.6)
			(stroke
				(width 0.15)
				(type solid)
			)
			(layer "F.SilkS")
		)
		(fp_line
			(start 1.601 -1.601)
			(end 1.601 -1.401)
			(stroke
				(width 0.15)
				(type solid)
			)
			(layer "F.SilkS")
		)
		(fp_line
			(start 1.601 -1.601)
			(end 1.351 -1.601)
			(stroke
				(width 0.15)
				(type solid)
			)
			(layer "F.SilkS")
		)
		(fp_line
			(start -1.249 -1.601)
			(end -0.824 -1.601)
			(stroke
				(width 0.15)
				(type solid)
			)
			(layer "F.SilkS")
		)
		(fp_line
			(start -1.249 -1.601)
			(end -1.624 -1.226)
			(stroke
				(width 0.15)
				(type solid)
			)
			(layer "F.SilkS")
		)
		(fp_line
			(start -1.6 1.6)
			(end -1.35 1.6)
			(stroke
				(width 0.15)
				(type solid)
			)
			(layer "F.SilkS")
		)
		(fp_line
			(start -1.6 1.6)
			(end -1.6 1.35)
			(stroke
				(width 0.15)
				(type solid)
			)
			(layer "F.SilkS")
		)
		(fp_line
			(start -1.624 -1.226)
			(end -1.773 -1.226)
			(stroke
				(width 0.15)
				(type solid)
			)
			(layer "F.SilkS")
		)
		(fp_circle
			(center -1.8 -1.6)
			(end -1.8 -1.551)
			(stroke
				(width 0.15)
				(type solid)
			)
			(fill yes)
			(layer "F.SilkS")
		)
		(fp_line
			(start 1.89 1.75)
			(end 1.89 -1.73)
			(stroke
				(width 0.05)
				(type solid)
			)
			(layer "F.CrtYd")
		)
		(fp_line
			(start 1.89 1.75)
			(end -1.91 1.75)
			(stroke
				(width 0.05)
				(type solid)
			)
			(layer "F.CrtYd")
		)
		(fp_line
			(start -1.91 1.75)
			(end -1.91 -1.73)
			(stroke
				(width 0.05)
				(type solid)
			)
			(layer "F.CrtYd")
		)
		(fp_line
			(start -1.91 -1.73)
			(end 1.89 -1.73)
			(stroke
				(width 0.05)
				(type solid)
			)
			(layer "F.CrtYd")
		)
		(fp_line
			(start 1.5 1.499)
			(end -1.499 1.499)
			(stroke
				(width 0.15)
				(type solid)
			)
			(layer "F.Fab")
		)
		(fp_line
			(start 1.5 -1.5)
			(end 1.5 1.499)
			(stroke
				(width 0.15)
				(type solid)
			)
			(layer "F.Fab")
		)
		(fp_line
			(start 1.5 -1.5)
			(end -1.175 -1.5)
			(stroke
				(width 0.15)
				(type solid)
			)
			(layer "F.Fab")
		)
		(fp_line
			(start -1.499 1.499)
			(end -1.499 -1.176)
			(stroke
				(width 0.15)
				(type solid)
			)
			(layer "F.Fab")
		)
		(fp_line
			(start -1.499 -1.18)
			(end -1.179 -1.5)
			(stroke
				(width 0.15)
				(type solid)
			)
			(layer "F.Fab")
		)
		(pad "1" smd roundrect
			(at -1.425 -1 90)
			(size 0.25 0.7)
			(layers "F.Cu" "F.Mask" "F.Paste")
			(roundrect_rratio 0.25)
			(net 744 "/DC-DC Converters/VDDR_VRI")
			(pinfunction "VRI")
			(pintype "unspecified")
		)
		(pad "2" smd roundrect
			(at -1.425 -0.5 90)
			(size 0.25 0.7)
			(layers "F.Cu" "F.Mask" "F.Paste")
			(roundrect_rratio 0.25)
			(net 25 "+1V35")
			(pinfunction "PVCC")
			(pintype "unspecified")
		)
		(pad "3" smd roundrect
			(at -1.425 0 90)
			(size 0.25 0.7)
			(layers "F.Cu" "F.Mask" "F.Paste")
			(roundrect_rratio 0.25)
			(net 750 "/DC-DC Converters/VDDR_VTT")
			(pinfunction "VTT")
			(pintype "unspecified")
		)
		(pad "4" smd roundrect
			(at -1.425 0.498 90)
			(size 0.25 0.7)
			(layers "F.Cu" "F.Mask" "F.Paste")
			(roundrect_rratio 0.25)
			(net 1 "GND")
			(pinfunction "PGND")
			(pintype "power_in")
		)
		(pad "5" smd roundrect
			(at -1.425 0.998 90)
			(size 0.25 0.7)
			(layers "F.Cu" "F.Mask" "F.Paste")
			(roundrect_rratio 0.25)
			(net 750 "/DC-DC Converters/VDDR_VTT")
			(pinfunction "VTTS")
			(pintype "unspecified")
		)
		(pad "6" smd roundrect
			(at 1.426 0.998 90)
			(size 0.25 0.7)
			(layers "F.Cu" "F.Mask" "F.Paste")
			(roundrect_rratio 0.25)
			(net 11 "+0V675_VREF")
			(pinfunction "VRO")
			(pintype "unspecified")
		)
		(pad "7" smd roundrect
			(at 1.426 0.498 90)
			(size 0.25 0.7)
			(layers "F.Cu" "F.Mask" "F.Paste")
			(roundrect_rratio 0.25)
			(net 1191 "/DC-DC Converters/+0V675_EN")
			(pinfunction "EN")
			(pintype "unspecified")
		)
		(pad "8" smd roundrect
			(at 1.426 0 90)
			(size 0.25 0.7)
			(layers "F.Cu" "F.Mask" "F.Paste")
			(roundrect_rratio 0.25)
			(net 1 "GND")
			(pinfunction "GND")
			(pintype "power_in")
		)
		(pad "9" smd roundrect
			(at 1.426 -0.5 90)
			(size 0.25 0.7)
			(layers "F.Cu" "F.Mask" "F.Paste")
			(roundrect_rratio 0.25)
			(net 1055 "/DC-DC Converters/VDDR_PGOOD")
			(pinfunction "PGOOD")
			(pintype "power_in")
		)
		(pad "10" smd roundrect
			(at 1.426 -1 90)
			(size 0.25 0.7)
			(layers "F.Cu" "F.Mask" "F.Paste")
			(roundrect_rratio 0.25)
			(net 24 "+3V3")
			(pinfunction "VCC")
			(pintype "power_in")
		)
		(pad "11" smd roundrect
			(at 0 0 90)
			(size 2.38 1.65)
			(layers "F.Cu" "F.Mask" "F.Paste")
			(roundrect_rratio 0.05)
			(net 1 "GND")
			(pinfunction "EPAD")
			(pintype "unspecified")
		)
	)
	(footprint "antmicro-footprints:C_0402_1005Metric"
		(layer "F.Cu")
		(at 252.999 101)
		(descr "Capacitor SMD 0402")
		(tags "capacitor SMD 0402")
		(property "Reference" "C394"
			(at -1.349 1.25 0)
			(layer "F.SilkS")
			(effects
				(font
					(size 0.7 0.7)
					(thickness 0.15)
				)
				(justify left bottom)
			)
		)
		(property "Value" "C_100n_0402"
			(at 0 1.169 0)
			(layer "F.Fab")
			(effects
				(font
					(size 0.7 0.7)
					(thickness 0.15)
				)
				(justify left bottom)
			)
		)
		(property "Description" "SMD Multilayer Ceramic Capacitor, 0.1 µF, 50 V, 0402 [1005 Metric], ± 10%, X5R, GRM Series"
			(at 0 0 0)
			(layer "F.Fab")
			(hide yes)
			(effects
				(font
					(size 1.27 1.27)
					(thickness 0.15)
				)
			)
		)
		(property "Author" "Antmicro"
			(at 0 0 0)
			(layer "F.Fab")
			(hide yes)
			(effects
				(font
					(size 1 1)
					(thickness 0.15)
				)
			)
		)
		(property "Dielectric" "X5R"
			(at 0 0 0)
			(layer "F.Fab")
			(hide yes)
			(effects
				(font
					(size 1 1)
					(thickness 0.15)
				)
			)
		)
		(property "License" "Apache-2.0"
			(at 0 0 0)
			(layer "F.Fab")
			(hide yes)
			(effects
				(font
					(size 1 1)
					(thickness 0.15)
				)
			)
		)
		(property "MPN" "GRM155R61H104KE14D"
			(at 0 0 0)
			(layer "F.Fab")
			(hide yes)
			(effects
				(font
					(size 1 1)
					(thickness 0.15)
				)
			)
		)
		(property "Manufacturer" "Murata"
			(at 0 0 0)
			(layer "F.Fab")
			(hide yes)
			(effects
				(font
					(size 1 1)
					(thickness 0.15)
				)
			)
		)
		(property "Val" "100n"
			(at 0 0 0)
			(layer "F.Fab")
			(hide yes)
			(effects
				(font
					(size 1 1)
					(thickness 0.15)
				)
			)
		)
		(property "Voltage" "50V"
			(at 0 0 0)
			(layer "F.Fab")
			(hide yes)
			(effects
				(font
					(size 1 1)
					(thickness 0.15)
				)
			)
		)
		(sheetname "USB PHY")
		(sheetfile "usb-phy.kicad_sch")
		(attr smd)
		(fp_rect
			(start -0.925 -0.47)
			(end 0.925 0.47)
			(stroke
				(width 0.05)
				(type default)
			)
			(fill no)
			(layer "F.CrtYd")
		)
		(fp_line
			(start -0.494 -0.25)
			(end 0.504 -0.25)
			(stroke
				(width 0.15)
				(type solid)
			)
			(layer "F.Fab")
		)
		(fp_line
			(start -0.494 0.248)
			(end -0.494 -0.25)
			(stroke
				(width 0.15)
				(type solid)
			)
			(layer "F.Fab")
		)
		(fp_line
			(start 0.504 -0.25)
			(end 0.504 0.248)
			(stroke
				(width 0.15)
				(type solid)
			)
			(layer "F.Fab")
		)
		(fp_line
			(start 0.504 0.248)
			(end -0.494 0.248)
			(stroke
				(width 0.15)
				(type solid)
			)
			(layer "F.Fab")
		)
		(pad "1" smd roundrect
			(at -0.48 0)
			(size 0.59 0.64)
			(layers "F.Cu" "F.Mask" "F.Paste")
			(roundrect_rratio 0.25)
			(net 1 "GND")
			(pintype "passive")
		)
		(pad "2" smd roundrect
			(at 0.48 0)
			(size 0.59 0.64)
			(layers "F.Cu" "F.Mask" "F.Paste")
			(roundrect_rratio 0.25)
			(net 705 "/USB PHY/USB_HOST_VBUS")
			(pintype "passive")
		)
	)
	(footprint "antmicro-footprints:C_0402_1005Metric"
		(layer "F.Cu")
		(at 240.55 140.2 180)
		(descr "Capacitor SMD 0402")
		(tags "capacitor SMD 0402")
		(property "Reference" "C247"
			(at 0.4 -1.3 180)
			(layer "F.SilkS")
			(effects
				(font
					(size 0.7 0.7)
					(thickness 0.15)
				)
				(justify left bottom)
			)
		)
		(property "Value" "C_100n_0402"
			(at 0 1.169 180)
			(layer "F.Fab")
			(effects
				(font
					(size 0.7 0.7)
					(thickness 0.15)
				)
				(justify left bottom)
			)
		)
		(property "Description" "SMD Multilayer Ceramic Capacitor, 0.1 µF, 50 V, 0402 [1005 Metric], ± 10%, X5R, GRM Series"
			(at 0 0 180)
			(layer "F.Fab")
			(hide yes)
			(effects
				(font
					(size 1.27 1.27)
					(thickness 0.15)
				)
			)
		)
		(property "Author" "Antmicro"
			(at 481.1 280.4 0)
			(layer "F.Fab")
			(hide yes)
			(effects
				(font
					(size 1 1)
					(thickness 0.15)
				)
			)
		)
		(property "Dielectric" "X5R"
			(at 481.1 280.4 0)
			(layer "F.Fab")
			(hide yes)
			(effects
				(font
					(size 1 1)
					(thickness 0.15)
				)
			)
		)
		(property "License" "Apache-2.0"
			(at 481.1 280.4 0)
			(layer "F.Fab")
			(hide yes)
			(effects
				(font
					(size 1 1)
					(thickness 0.15)
				)
			)
		)
		(property "MPN" "GRM155R61H104KE14D"
			(at 481.1 280.4 0)
			(layer "F.Fab")
			(hide yes)
			(effects
				(font
					(size 1 1)
					(thickness 0.15)
				)
			)
		)
		(property "Manufacturer" "Murata"
			(at 481.1 280.4 0)
			(layer "F.Fab")
			(hide yes)
			(effects
				(font
					(size 1 1)
					(thickness 0.15)
				)
			)
		)
		(property "Val" "100n"
			(at 481.1 280.4 0)
			(layer "F.Fab")
			(hide yes)
			(effects
				(font
					(size 1 1)
					(thickness 0.15)
				)
			)
		)
		(property "Voltage" "50V"
			(at 481.1 280.4 0)
			(layer "F.Fab")
			(hide yes)
			(effects
				(font
					(size 1 1)
					(thickness 0.15)
				)
			)
		)
		(sheetname "USB PHY")
		(sheetfile "usb-phy.kicad_sch")
		(attr smd)
		(fp_rect
			(start -0.925 -0.47)
			(end 0.925 0.47)
			(stroke
				(width 0.05)
				(type default)
			)
			(fill no)
			(layer "F.CrtYd")
		)
		(fp_line
			(start 0.504 0.248)
			(end -0.494 0.248)
			(stroke
				(width 0.15)
				(type solid)
			)
			(layer "F.Fab")
		)
		(fp_line
			(start 0.504 -0.25)
			(end 0.504 0.248)
			(stroke
				(width 0.15)
				(type solid)
			)
			(layer "F.Fab")
		)
		(fp_line
			(start -0.494 0.248)
			(end -0.494 -0.25)
			(stroke
				(width 0.15)
				(type solid)
			)
			(layer "F.Fab")
		)
		(fp_line
			(start -0.494 -0.25)
			(end 0.504 -0.25)
			(stroke
				(width 0.15)
				(type solid)
			)
			(layer "F.Fab")
		)
		(pad "1" smd roundrect
			(at -0.48 0 180)
			(size 0.59 0.64)
			(layers "F.Cu" "F.Mask" "F.Paste")
			(roundrect_rratio 0.25)
			(net 1 "GND")
			(pintype "passive")
		)
		(pad "2" smd roundrect
			(at 0.48 0 180)
			(size 0.59 0.64)
			(layers "F.Cu" "F.Mask" "F.Paste")
			(roundrect_rratio 0.25)
			(net 707 "/USB PHY/FTDI_3V3")
			(pintype "passive")
		)
	)
	(footprint "antmicro-footprints:Micron_FBGA-78"
		(layer "F.Cu")
		(at 169.2 145.6 -90)
		(property "Reference" "U5"
			(at -4.27 -6.51 90)
			(layer "F.SilkS")
			(effects
				(font
					(size 0.7 0.7)
					(thickness 0.15)
				)
				(justify right bottom)
			)
		)
		(property "Value" "MT41K512M8DA"
			(at -4.37 6.69 90)
			(layer "F.Fab")
			(effects
				(font
					(size 0.7 0.7)
					(thickness 0.15)
				)
				(justify right bottom)
			)
		)
		(property "Description" "SDRAM - DDR3L Memory IC 4Gbit Parallel 933 MHz 20 ns 78-FBGA (8x10.5)"
			(at 0 0 270)
			(layer "F.Fab")
			(hide yes)
			(effects
				(font
					(size 1.27 1.27)
					(thickness 0.15)
				)
			)
		)
		(property "Author" "Antmicro"
			(at 23.6 314.8 0)
			(layer "F.Fab")
			(hide yes)
			(effects
				(font
					(size 1 1)
					(thickness 0.15)
				)
			)
		)
		(property "License" "Apache-2.0"
			(at 23.6 314.8 0)
			(layer "F.Fab")
			(hide yes)
			(effects
				(font
					(size 1 1)
					(thickness 0.15)
				)
			)
		)
		(property "MPN" "MT41K512M8DA-107 XIT:P TR"
			(at 23.6 314.8 0)
			(layer "F.Fab")
			(hide yes)
			(effects
				(font
					(size 1 1)
					(thickness 0.15)
				)
			)
		)
		(property "Manufacturer" "Micron Technology"
			(at 23.6 314.8 0)
			(layer "F.Fab")
			(hide yes)
			(effects
				(font
					(size 1 1)
					(thickness 0.15)
				)
			)
		)
		(sheetname "DRAM + SRAM")
		(sheetfile "ram.kicad_sch")
		(attr smd)
		(fp_line
			(start -4.05 5.334)
			(end -2.025 5.334)
			(stroke
				(width 0.15)
				(type solid)
			)
			(layer "F.SilkS")
		)
		(fp_line
			(start -4.05 5.334)
			(end -4.05 2.667)
			(stroke
				(width 0.15)
				(type solid)
			)
			(layer "F.SilkS")
		)
		(fp_line
			(start 4.049 5.334)
			(end 2.023 5.334)
			(stroke
				(width 0.15)
				(type solid)
			)
			(layer "F.SilkS")
		)
		(fp_line
			(start 4.049 5.334)
			(end 4.049 2.667)
			(stroke
				(width 0.15)
				(type solid)
			)
			(layer "F.SilkS")
		)
		(fp_line
			(start -4.05 -5.335)
			(end -4.05 -2.669)
			(stroke
				(width 0.15)
				(type solid)
			)
			(layer "F.SilkS")
		)
		(fp_line
			(start -4.05 -5.335)
			(end -2.025 -5.335)
			(stroke
				(width 0.15)
				(type solid)
			)
			(layer "F.SilkS")
		)
		(fp_line
			(start 4.049 -5.335)
			(end 4.049 -2.669)
			(stroke
				(width 0.15)
				(type solid)
			)
			(layer "F.SilkS")
		)
		(fp_line
			(start 4.049 -5.335)
			(end 2.023 -5.335)
			(stroke
				(width 0.15)
				(type solid)
			)
			(layer "F.SilkS")
		)
		(fp_circle
			(center -4.56 -4.8)
			(end -4.511 -4.8)
			(stroke
				(width 0.15)
				(type solid)
			)
			(fill yes)
			(layer "F.SilkS")
		)
		(fp_rect
			(start -4.553 -5.797)
			(end 4.551 5.796)
			(stroke
				(width 0.05)
				(type solid)
			)
			(fill no)
			(layer "F.CrtYd")
		)
		(fp_line
			(start -4.05 5.299)
			(end -4.05 -5.3)
			(stroke
				(width 0.15)
				(type solid)
			)
			(layer "F.Fab")
		)
		(fp_line
			(start 4.049 5.299)
			(end -4.05 5.299)
			(stroke
				(width 0.15)
				(type solid)
			)
			(layer "F.Fab")
		)
		(fp_line
			(start 4.049 5.299)
			(end 4.049 -5.3)
			(stroke
				(width 0.15)
				(type solid)
			)
			(layer "F.Fab")
		)
		(fp_line
			(start -4.05 -5.1)
			(end -3.85 -5.3)
			(stroke
				(width 0.15)
				(type solid)
			)
			(layer "F.Fab")
		)
		(fp_line
			(start 4.049 -5.3)
			(end -4.05 -5.3)
			(stroke
				(width 0.15)
				(type solid)
			)
			(layer "F.Fab")
		)
		(pad "A1" smd circle
			(at -3.202 -4.8 270)
			(size 0.43 0.43)
			(layers "F.Cu" "F.Mask" "F.Paste")
			(net 1 "GND")
			(pinfunction "VSS")
			(pintype "passive")
		)
		(pad "A2" smd circle
			(at -2.4 -4.8 270)
			(size 0.43 0.43)
			(layers "F.Cu" "F.Mask" "F.Paste")
			(net 25 "+1V35")
			(pinfunction "VDD")
			(pintype "power_in")
		)
		(pad "A3" smd circle
			(at -1.601 -4.8 270)
			(size 0.43 0.43)
			(layers "F.Cu" "F.Mask" "F.Paste")
			(net 1134 "unconnected-(U5-NC-PadA3)")
			(pinfunction "NC")
			(pintype "no_connect")
		)
		(pad "A7" smd circle
			(at 1.6 -4.8 270)
			(size 0.43 0.43)
			(layers "F.Cu" "F.Mask" "F.Paste")
			(net 1135 "unconnected-(U5-NF{slash}TDQS#-PadA7)")
			(pinfunction "NF/TDQS#")
			(pintype "output+no_connect")
		)
		(pad "A8" smd circle
			(at 2.398 -4.8 270)
			(size 0.43 0.43)
			(layers "F.Cu" "F.Mask" "F.Paste")
			(net 1 "GND")
			(pinfunction "VSS")
			(pintype "passive")
		)
		(pad "A9" smd circle
			(at 3.2 -4.8 270)
			(size 0.43 0.43)
			(layers "F.Cu" "F.Mask" "F.Paste")
			(net 25 "+1V35")
			(pinfunction "VDD")
			(pintype "passive")
		)
		(pad "B1" smd circle
			(at -3.202 -4 270)
			(size 0.43 0.43)
			(layers "F.Cu" "F.Mask" "F.Paste")
			(net 1 "GND")
			(pinfunction "VSS")
			(pintype "passive")
		)
		(pad "B2" smd circle
			(at -2.4 -4 270)
			(size 0.43 0.43)
			(layers "F.Cu" "F.Mask" "F.Paste")
			(net 1 "GND")
			(pinfunction "VSSQ")
			(pintype "passive")
		)
		(pad "B3" smd circle
			(at -1.601 -4 270)
			(size 0.43 0.43)
			(layers "F.Cu" "F.Mask" "F.Paste")
			(net 661 "/DRAM + SRAM/DDR.DQ0")
			(pinfunction "DQ0")
			(pintype "bidirectional")
		)
		(pad "B7" smd circle
			(at 1.6 -4 270)
			(size 0.43 0.43)
			(layers "F.Cu" "F.Mask" "F.Paste")
			(net 557 "/DRAM + SRAM/DDR.DM")
			(pinfunction "DM/TDQS")
			(pintype "bidirectional")
		)
		(pad "B8" smd circle
			(at 2.398 -4 270)
			(size 0.43 0.43)
			(layers "F.Cu" "F.Mask" "F.Paste")
			(net 1 "GND")
			(pinfunction "VSSQ")
			(pintype "passive")
		)
		(pad "B9" smd circle
			(at 3.2 -4 270)
			(size 0.43 0.43)
			(layers "F.Cu" "F.Mask" "F.Paste")
			(net 25 "+1V35")
			(pinfunction "VDDQ")
			(pintype "power_in")
		)
		(pad "C1" smd circle
			(at -3.202 -3.202 270)
			(size 0.43 0.43)
			(layers "F.Cu" "F.Mask" "F.Paste")
			(net 25 "+1V35")
			(pinfunction "VDDQ")
			(pintype "passive")
		)
		(pad "C2" smd circle
			(at -2.4 -3.202 270)
			(size 0.43 0.43)
			(layers "F.Cu" "F.Mask" "F.Paste")
			(net 662 "/DRAM + SRAM/DDR.DQ2")
			(pinfunction "DQ2")
			(pintype "bidirectional")
		)
		(pad "C3" smd circle
			(at -1.601 -3.202 270)
			(size 0.43 0.43)
			(layers "F.Cu" "F.Mask" "F.Paste")
			(net 656 "/DRAM + SRAM/DDR.DQS_P")
			(pinfunction "DQS")
			(pintype "bidirectional")
		)
		(pad "C7" smd circle
			(at 1.6 -3.202 270)
			(size 0.43 0.43)
			(layers "F.Cu" "F.Mask" "F.Paste")
			(net 663 "/DRAM + SRAM/DDR.DQ1")
			(pinfunction "DQ1")
			(pintype "bidirectional")
		)
		(pad "C8" smd circle
			(at 2.398 -3.202 270)
			(size 0.43 0.43)
			(layers "F.Cu" "F.Mask" "F.Paste")
			(net 657 "/DRAM + SRAM/DDR.DQ3")
			(pinfunction "DQ3")
			(pintype "bidirectional")
		)
		(pad "C9" smd circle
			(at 3.2 -3.202 270)
			(size 0.43 0.43)
			(layers "F.Cu" "F.Mask" "F.Paste")
			(net 1 "GND")
			(pinfunction "VSSQ")
			(pintype "passive")
		)
		(pad "D1" smd circle
			(at -3.202 -2.4 270)
			(size 0.43 0.43)
			(layers "F.Cu" "F.Mask" "F.Paste")
			(net 1 "GND")
			(pinfunction "VSSQ")
			(pintype "passive")
		)
		(pad "D2" smd circle
			(at -2.4 -2.4 270)
			(size 0.43 0.43)
			(layers "F.Cu" "F.Mask" "F.Paste")
			(net 660 "/DRAM + SRAM/DDR.DQ6")
			(pinfunction "NF/DQ6")
			(pintype "bidirectional")
		)
		(pad "D3" smd circle
			(at -1.601 -2.4 270)
			(size 0.43 0.43)
			(layers "F.Cu" "F.Mask" "F.Paste")
			(net 658 "/DRAM + SRAM/DDR.DQS_N")
			(pinfunction "DQS#")
			(pintype "bidirectional")
		)
		(pad "D7" smd circle
			(at 1.6 -2.4 270)
			(size 0.43 0.43)
			(layers "F.Cu" "F.Mask" "F.Paste")
			(net 25 "+1V35")
			(pinfunction "VDD")
			(pintype "passive")
		)
		(pad "D8" smd circle
			(at 2.398 -2.4 270)
			(size 0.43 0.43)
			(layers "F.Cu" "F.Mask" "F.Paste")
			(net 1 "GND")
			(pinfunction "VSS")
			(pintype "passive")
		)
		(pad "D9" smd circle
			(at 3.2 -2.4 270)
			(size 0.43 0.43)
			(layers "F.Cu" "F.Mask" "F.Paste")
			(net 1 "GND")
			(pinfunction "VSSQ")
			(pintype "passive")
		)
		(pad "E1" smd circle
			(at -3.202 -1.601 270)
			(size 0.43 0.43)
			(layers "F.Cu" "F.Mask" "F.Paste")
			(net 11 "+0V675_VREF")
			(pinfunction "VREFDQ")
			(pintype "power_in")
		)
		(pad "E2" smd circle
			(at -2.4 -1.601 270)
			(size 0.43 0.43)
			(layers "F.Cu" "F.Mask" "F.Paste")
			(net 25 "+1V35")
			(pinfunction "VDDQ")
			(pintype "passive")
		)
		(pad "E3" smd circle
			(at -1.601 -1.601 270)
			(size 0.43 0.43)
			(layers "F.Cu" "F.Mask" "F.Paste")
			(net 655 "/DRAM + SRAM/DDR.DQ4")
			(pinfunction "NF/DQ4")
			(pintype "bidirectional")
		)
		(pad "E7" smd circle
			(at 1.6 -1.601 270)
			(size 0.43 0.43)
			(layers "F.Cu" "F.Mask" "F.Paste")
			(net 654 "/DRAM + SRAM/DDR.DQ7")
			(pinfunction "NF/DQ7")
			(pintype "bidirectional")
		)
		(pad "E8" smd circle
			(at 2.398 -1.601 270)
			(size 0.43 0.43)
			(layers "F.Cu" "F.Mask" "F.Paste")
			(net 659 "/DRAM + SRAM/DDR.DQ5")
			(pinfunction "NF/DQ5")
			(pintype "bidirectional")
		)
		(pad "E9" smd circle
			(at 3.2 -1.601 270)
			(size 0.43 0.43)
			(layers "F.Cu" "F.Mask" "F.Paste")
			(net 25 "+1V35")
			(pinfunction "VDDQ")
			(pintype "passive")
		)
		(pad "F1" smd circle
			(at -3.202 -0.802 270)
			(size 0.43 0.43)
			(layers "F.Cu" "F.Mask" "F.Paste")
			(net 1136 "unconnected-(U5-NC-PadF1)")
			(pinfunction "NC")
			(pintype "no_connect")
		)
		(pad "F2" smd circle
			(at -2.4 -0.802 270)
			(size 0.43 0.43)
			(layers "F.Cu" "F.Mask" "F.Paste")
			(net 1 "GND")
			(pinfunction "VSS")
			(pintype "passive")
		)
		(pad "F3" smd circle
			(at -1.601 -0.802 270)
			(size 0.43 0.43)
			(layers "F.Cu" "F.Mask" "F.Paste")
			(net 560 "/DRAM + SRAM/DDR.~{RAS}")
			(pinfunction "RAS#")
			(pintype "input")
		)
		(pad "F7" smd circle
			(at 1.6 -0.802 270)
			(size 0.43 0.43)
			(layers "F.Cu" "F.Mask" "F.Paste")
			(net 551 "/DRAM + SRAM/DDR.CK_P")
			(pinfunction "CK")
			(pintype "input")
		)
		(pad "F8" smd circle
			(at 2.398 -0.802 270)
			(size 0.43 0.43)
			(layers "F.Cu" "F.Mask" "F.Paste")
			(net 1 "GND")
			(pinfunction "VSS")
			(pintype "passive")
		)
		(pad "F9" smd circle
			(at 3.2 -0.802 270)
			(size 0.43 0.43)
			(layers "F.Cu" "F.Mask" "F.Paste")
			(net 1137 "unconnected-(U5-NC-PadF9)")
			(pinfunction "NC")
			(pintype "no_connect")
		)
		(pad "G1" smd circle
			(at -3.202 0 270)
			(size 0.43 0.43)
			(layers "F.Cu" "F.Mask" "F.Paste")
			(net 553 "/DRAM + SRAM/DDR.ODT")
			(pinfunction "ODT")
			(pintype "input")
		)
		(pad "G2" smd circle
			(at -2.4 0 270)
			(size 0.43 0.43)
			(layers "F.Cu" "F.Mask" "F.Paste")
			(net 25 "+1V35")
			(pinfunction "VDD")
			(pintype "passive")
		)
		(pad "G3" smd circle
			(at -1.601 0 270)
			(size 0.43 0.43)
			(layers "F.Cu" "F.Mask" "F.Paste")
			(net 559 "/DRAM + SRAM/DDR.~{CAS}")
			(pinfunction "CAS#")
			(pintype "input")
		)
		(pad "G7" smd circle
			(at 1.6 0 270)
			(size 0.43 0.43)
			(layers "F.Cu" "F.Mask" "F.Paste")
			(net 552 "/DRAM + SRAM/DDR.CK_N")
			(pinfunction "CK#")
			(pintype "input")
		)
		(pad "G8" smd circle
			(at 2.398 0 270)
			(size 0.43 0.43)
			(layers "F.Cu" "F.Mask" "F.Paste")
			(net 25 "+1V35")
			(pinfunction "VDD")
			(pintype "passive")
		)
		(pad "G9" smd circle
			(at 3.2 0 270)
			(size 0.43 0.43)
			(layers "F.Cu" "F.Mask" "F.Paste")
			(net 550 "/DRAM + SRAM/DDR.CKE")
			(pinfunction "CKE")
			(pintype "input")
		)
		(pad "H1" smd circle
			(at -3.202 0.8 270)
			(size 0.43 0.43)
			(layers "F.Cu" "F.Mask" "F.Paste")
			(net 1138 "unconnected-(U5-NC-PadH1)")
			(pinfunction "NC")
			(pintype "no_connect")
		)
		(pad "H2" smd circle
			(at -2.4 0.8 270)
			(size 0.43 0.43)
			(layers "F.Cu" "F.Mask" "F.Paste")
			(net 561 "/DRAM + SRAM/DDR.~{CS}")
			(pinfunction "CS#")
			(pintype "input")
		)
		(pad "H3" smd circle
			(at -1.601 0.8 270)
			(size 0.43 0.43)
			(layers "F.Cu" "F.Mask" "F.Paste")
			(net 558 "/DRAM + SRAM/DDR.~{WE}")
			(pinfunction "WE#")
			(pintype "input")
		)
		(pad "H7" smd circle
			(at 1.6 0.8 270)
			(size 0.43 0.43)
			(layers "F.Cu" "F.Mask" "F.Paste")
			(net 541 "/DRAM + SRAM/DDR.A10")
			(pinfunction "A10/AP")
			(pintype "input")
		)
		(pad "H8" smd circle
			(at 2.398 0.8 270)
			(size 0.43 0.43)
			(layers "F.Cu" "F.Mask" "F.Paste")
			(net 555 "/DRAM + SRAM/DDR_ZQ")
			(pinfunction "ZQ")
			(pintype "output")
		)
		(pad "H9" smd circle
			(at 3.2 0.8 270)
			(size 0.43 0.43)
			(layers "F.Cu" "F.Mask" "F.Paste")
			(net 1139 "unconnected-(U5-NC-PadH9)")
			(pinfunction "NC")
			(pintype "no_connect")
		)
		(pad "J1" smd circle
			(at -3.202 1.6 270)
			(size 0.43 0.43)
			(layers "F.Cu" "F.Mask" "F.Paste")
			(net 1 "GND")
			(pinfunction "VSS")
			(pintype "passive")
		)
		(pad "J2" smd circle
			(at -2.4 1.6 270)
			(size 0.43 0.43)
			(layers "F.Cu" "F.Mask" "F.Paste")
			(net 547 "/DRAM + SRAM/DDR.BA0")
			(pinfunction "BA0")
			(pintype "input")
		)
		(pad "J3" smd circle
			(at -1.601 1.6 270)
			(size 0.43 0.43)
			(layers "F.Cu" "F.Mask" "F.Paste")
			(net 549 "/DRAM + SRAM/DDR.BA2")
			(pinfunction "BA2")
			(pintype "input")
		)
		(pad "J7" smd circle
			(at 1.6 1.6 270)
			(size 0.43 0.43)
			(layers "F.Cu" "F.Mask" "F.Paste")
			(net 546 "/DRAM + SRAM/DDR.A15")
			(pinfunction "A15")
			(pintype "input")
		)
		(pad "J8" smd circle
			(at 2.398 1.6 270)
			(size 0.43 0.43)
			(layers "F.Cu" "F.Mask" "F.Paste")
			(net 11 "+0V675_VREF")
			(pinfunction "VREFCA")
			(pintype "power_in")
		)
		(pad "J9" smd circle
			(at 3.2 1.6 270)
			(size 0.43 0.43)
			(layers "F.Cu" "F.Mask" "F.Paste")
			(net 1 "GND")
			(pinfunction "VSS")
			(pintype "passive")
		)
		(pad "K1" smd circle
			(at -3.202 2.398 270)
			(size 0.43 0.43)
			(layers "F.Cu" "F.Mask" "F.Paste")
			(net 25 "+1V35")
			(pinfunction "VDD")
			(pintype "passive")
		)
		(pad "K2" smd circle
			(at -2.4 2.398 270)
			(size 0.43 0.43)
			(layers "F.Cu" "F.Mask" "F.Paste")
			(net 534 "/DRAM + SRAM/DDR.A3")
			(pinfunction "A3")
			(pintype "input")
		)
		(pad "K3" smd circle
			(at -1.601 2.398 270)
			(size 0.43 0.43)
			(layers "F.Cu" "F.Mask" "F.Paste")
			(net 531 "/DRAM + SRAM/DDR.A0")
			(pinfunction "A0")
			(pintype "input")
		)
		(pad "K7" smd circle
			(at 1.6 2.398 270)
			(size 0.43 0.43)
			(layers "F.Cu" "F.Mask" "F.Paste")
			(net 543 "/DRAM + SRAM/DDR.A12")
			(pinfunction "A12/BC#")
			(pintype "input")
		)
		(pad "K8" smd circle
			(at 2.398 2.398 270)
			(size 0.43 0.43)
			(layers "F.Cu" "F.Mask" "F.Paste")
			(net 548 "/DRAM + SRAM/DDR.BA1")
			(pinfunction "BA1")
			(pintype "input")
		)
		(pad "K9" smd circle
			(at 3.2 2.398 270)
			(size 0.43 0.43)
			(layers "F.Cu" "F.Mask" "F.Paste")
			(net 25 "+1V35")
			(pinfunction "VDD")
			(pintype "passive")
		)
		(pad "L1" smd circle
			(at -3.202 3.2 270)
			(size 0.43 0.43)
			(layers "F.Cu" "F.Mask" "F.Paste")
			(net 1 "GND")
			(pinfunction "VSS")
			(pintype "passive")
		)
		(pad "L2" smd circle
			(at -2.4 3.2 270)
			(size 0.43 0.43)
			(layers "F.Cu" "F.Mask" "F.Paste")
			(net 536 "/DRAM + SRAM/DDR.A5")
			(pinfunction "A5")
			(pintype "input")
		)
		(pad "L3" smd circle
			(at -1.601 3.2 270)
			(size 0.43 0.43)
			(layers "F.Cu" "F.Mask" "F.Paste")
			(net 533 "/DRAM + SRAM/DDR.A2")
			(pinfunction "A2")
			(pintype "input")
		)
		(pad "L7" smd circle
			(at 1.6 3.2 270)
			(size 0.43 0.43)
			(layers "F.Cu" "F.Mask" "F.Paste")
			(net 532 "/DRAM + SRAM/DDR.A1")
			(pinfunction "A1")
			(pintype "input")
		)
		(pad "L8" smd circle
			(at 2.398 3.2 270)
			(size 0.43 0.43)
			(layers "F.Cu" "F.Mask" "F.Paste")
			(net 535 "/DRAM + SRAM/DDR.A4")
			(pinfunction "A4")
			(pintype "input")
		)
		(pad "L9" smd circle
			(at 3.2 3.2 270)
			(size 0.43 0.43)
			(layers "F.Cu" "F.Mask" "F.Paste")
			(net 1 "GND")
			(pinfunction "VSS")
			(pintype "passive")
		)
		(pad "M1" smd circle
			(at -3.202 3.999 270)
			(size 0.43 0.43)
			(layers "F.Cu" "F.Mask" "F.Paste")
			(net 25 "+1V35")
			(pinfunction "VDD")
			(pintype "passive")
		)
		(pad "M2" smd circle
			(at -2.4 3.999 270)
			(size 0.43 0.43)
			(layers "F.Cu" "F.Mask" "F.Paste")
			(net 538 "/DRAM + SRAM/DDR.A7")
			(pinfunction "A7")
			(pintype "input")
		)
		(pad "M3" smd circle
			(at -1.601 3.999 270)
			(size 0.43 0.43)
			(layers "F.Cu" "F.Mask" "F.Paste")
			(net 540 "/DRAM + SRAM/DDR.A9")
			(pinfunction "A9")
			(pintype "input")
		)
		(pad "M7" smd circle
			(at 1.6 3.999 270)
			(size 0.43 0.43)
			(layers "F.Cu" "F.Mask" "F.Paste")
			(net 542 "/DRAM + SRAM/DDR.A11")
			(pinfunction "A11")
			(pintype "input")
		)
		(pad "M8" smd circle
			(at 2.398 3.999 270)
			(size 0.43 0.43)
			(layers "F.Cu" "F.Mask" "F.Paste")
			(net 537 "/DRAM + SRAM/DDR.A6")
			(pinfunction "A6")
			(pintype "input")
		)
		(pad "M9" smd circle
			(at 3.2 3.999 270)
			(size 0.43 0.43)
			(layers "F.Cu" "F.Mask" "F.Paste")
			(net 25 "+1V35")
			(pinfunction "VDD")
			(pintype "passive")
		)
		(pad "N1" smd circle
			(at -3.202 4.799 270)
			(size 0.43 0.43)
			(layers "F.Cu" "F.Mask" "F.Paste")
			(net 1 "GND")
			(pinfunction "VSS")
			(pintype "passive")
		)
		(pad "N2" smd circle
			(at -2.4 4.799 270)
			(size 0.43 0.43)
			(layers "F.Cu" "F.Mask" "F.Paste")
			(net 554 "/DRAM + SRAM/DDR.~{RESET}")
			(pinfunction "RESET#")
			(pintype "input")
		)
		(pad "N3" smd circle
			(at -1.601 4.799 270)
			(size 0.43 0.43)
			(layers "F.Cu" "F.Mask" "F.Paste")
			(net 544 "/DRAM + SRAM/DDR.A13")
			(pinfunction "A13")
			(pintype "input")
		)
		(pad "N7" smd circle
			(at 1.6 4.799 270)
			(size 0.43 0.43)
			(layers "F.Cu" "F.Mask" "F.Paste")
			(net 545 "/DRAM + SRAM/DDR.A14")
			(pinfunction "A14")
			(pintype "input")
		)
		(pad "N8" smd circle
			(at 2.398 4.799 270)
			(size 0.43 0.43)
			(layers "F.Cu" "F.Mask" "F.Paste")
			(net 539 "/DRAM + SRAM/DDR.A8")
			(pinfunction "A8")
			(pintype "input")
		)
		(pad "N9" smd circle
			(at 3.2 4.799 270)
			(size 0.43 0.43)
			(layers "F.Cu" "F.Mask" "F.Paste")
			(net 1 "GND")
			(pinfunction "VSS")
			(pintype "passive")
		)
	)
	(footprint "antmicro-footprints:NetTie-2_SMD_Pad0.127mm"
		(layer "F.Cu")
		(at 160.773 145.7)
		(descr "Net tie, 2 pin, 0.127mm  SMD pads")
		(tags "net tie")
		(property "Reference" "NT1"
			(at -0.128 -1.345 0)
			(layer "F.SilkS")
			(hide yes)
			(effects
				(font
					(size 0.7 0.7)
					(thickness 0.15)
				)
				(justify left bottom)
			)
		)
		(property "Value" "Net-Tie_2"
			(at 0 1.199 0)
			(layer "F.Fab")
			(effects
				(font
					(size 0.7 0.7)
					(thickness 0.15)
				)
				(justify left bottom)
			)
		)
		(property "Description" "Net tie, 2 pins"
			(at 0 0 0)
			(layer "F.Fab")
			(hide yes)
			(effects
				(font
					(size 1.27 1.27)
					(thickness 0.15)
				)
			)
		)
		(property "Author" "Antmicro"
			(at 0 0 0)
			(layer "F.Fab")
			(hide yes)
			(effects
				(font
					(size 1 1)
					(thickness 0.15)
				)
			)
		)
		(property "License" "Apache-2.0"
			(at 0 0 0)
			(layer "F.Fab")
			(hide yes)
			(effects
				(font
					(size 1 1)
					(thickness 0.15)
				)
			)
		)
		(property "MPN" ""
			(at 0 0 0)
			(layer "F.Fab")
			(hide yes)
			(effects
				(font
					(size 1 1)
					(thickness 0.15)
				)
			)
		)
		(property "Manufacturer" ""
			(at 0 0 0)
			(layer "F.Fab")
			(hide yes)
			(effects
				(font
					(size 1 1)
					(thickness 0.15)
				)
			)
		)
		(sheetname "DC-DC Converters")
		(sheetfile "dc-dc.kicad_sch")
		(attr exclude_from_pos_files)
		(net_tie_pad_groups "1, 2")
		(fp_poly
			(pts
				(xy -0.0635 -0.0635) (xy 0.0625 -0.0635) (xy 0.0625 0.0635) (xy -0.0635 0.0635)
			)
			(stroke
				(width 0)
				(type solid)
			)
			(fill yes)
			(layer "F.Cu")
		)
		(pad "1" smd roundrect
			(at -0.127 0 180)
			(size 0.127 0.127)
			(layers "F.Cu")
			(roundrect_rratio 0.5)
			(chamfer_ratio 0)
			(chamfer top_left bottom_left)
			(net 869 "Net-(NT1-Pad1)")
			(pinfunction "1")
			(pintype "passive")
		)
		(pad "2" smd roundrect
			(at 0.126 0)
			(size 0.127 0.127)
			(layers "F.Cu")
			(roundrect_rratio 0.5)
			(chamfer_ratio 0)
			(chamfer top_left bottom_left)
			(net 649 "VREFP")
			(pinfunction "2")
			(pintype "passive")
		)
	)
	(footprint "antmicro-footprints:Alliance_TFBGA-48"
		(layer "F.Cu")
		(at 221.75 130.65 180)
		(property "Reference" "U4"
			(at 0.7 4.2 180)
			(layer "F.SilkS")
			(effects
				(font
					(size 0.7 0.7)
					(thickness 0.15)
				)
				(justify left bottom)
			)
		)
		(property "Value" "AS6C8008-55BIN"
			(at -4.65 5.35 180)
			(layer "F.Fab")
			(effects
				(font
					(size 0.7 0.7)
					(thickness 0.15)
				)
				(justify left bottom)
			)
		)
		(property "Description" "SRAM, Asynchronous SRAM, 8 Mbit, TFBGA, 48 Pins, 2.7 V"
			(at 0 0 180)
			(layer "F.Fab")
			(hide yes)
			(effects
				(font
					(size 1.27 1.27)
					(thickness 0.15)
				)
			)
		)
		(property "Author" "Antmicro"
			(at 443.5 261.3 0)
			(layer "F.Fab")
			(hide yes)
			(effects
				(font
					(size 1 1)
					(thickness 0.15)
				)
			)
		)
		(property "License" "Apache-2.0"
			(at 443.5 261.3 0)
			(layer "F.Fab")
			(hide yes)
			(effects
				(font
					(size 1 1)
					(thickness 0.15)
				)
			)
		)
		(property "MPN" "AS6C8008-55BIN"
			(at 443.5 261.3 0)
			(layer "F.Fab")
			(hide yes)
			(effects
				(font
					(size 1 1)
					(thickness 0.15)
				)
			)
		)
		(property "Manufacturer" "Alliance Memory"
			(at 443.5 261.3 0)
			(layer "F.Fab")
			(hide yes)
			(effects
				(font
					(size 1 1)
					(thickness 0.15)
				)
			)
		)
		(sheetname "DRAM + SRAM")
		(sheetfile "ram.kicad_sch")
		(attr smd)
		(fp_line
			(start 2.999 3.999)
			(end 2.999 2.023)
			(stroke
				(width 0.15)
				(type solid)
			)
			(layer "F.SilkS")
		)
		(fp_line
			(start 2.999 3.999)
			(end 1.523 3.999)
			(stroke
				(width 0.15)
				(type solid)
			)
			(layer "F.SilkS")
		)
		(fp_line
			(start 2.999 -4)
			(end 2.999 -2.025)
			(stroke
				(width 0.15)
				(type solid)
			)
			(layer "F.SilkS")
		)
		(fp_line
			(start 2.999 -4)
			(end 1.523 -4)
			(stroke
				(width 0.15)
				(type solid)
			)
			(layer "F.SilkS")
		)
		(fp_line
			(start -3 3.999)
			(end -1.526 3.999)
			(stroke
				(width 0.15)
				(type solid)
			)
			(layer "F.SilkS")
		)
		(fp_line
			(start -3 3.999)
			(end -3 2.023)
			(stroke
				(width 0.15)
				(type solid)
			)
			(layer "F.SilkS")
		)
		(fp_line
			(start -3 -4)
			(end -1.526 -4)
			(stroke
				(width 0.15)
				(type solid)
			)
			(layer "F.SilkS")
		)
		(fp_line
			(start -3 -4)
			(end -3 -2.025)
			(stroke
				(width 0.15)
				(type solid)
			)
			(layer "F.SilkS")
		)
		(fp_circle
			(center -3.5 -2.63)
			(end -3.45 -2.63)
			(stroke
				(width 0.15)
				(type solid)
			)
			(fill yes)
			(layer "F.SilkS")
		)
		(fp_rect
			(start -3.5 -4.5)
			(end 3.499 4.499)
			(stroke
				(width 0.05)
				(type solid)
			)
			(fill no)
			(layer "F.CrtYd")
		)
		(fp_line
			(start 2.999 3.999)
			(end 2.999 -4)
			(stroke
				(width 0.15)
				(type solid)
			)
			(layer "F.Fab")
		)
		(fp_line
			(start 2.999 3.999)
			(end -3 3.999)
			(stroke
				(width 0.15)
				(type solid)
			)
			(layer "F.Fab")
		)
		(fp_line
			(start 2.999 -4)
			(end -3 -4)
			(stroke
				(width 0.15)
				(type solid)
			)
			(layer "F.Fab")
		)
		(fp_line
			(start -3 3.999)
			(end -3 -4)
			(stroke
				(width 0.15)
				(type solid)
			)
			(layer "F.Fab")
		)
		(fp_line
			(start -3 -3.8)
			(end -2.8 -4)
			(stroke
				(width 0.15)
				(type solid)
			)
			(layer "F.Fab")
		)
		(pad "A1" smd circle
			(at -1.875 -2.625 180)
			(size 0.33 0.33)
			(layers "F.Cu" "F.Mask" "F.Paste")
			(net 1122 "unconnected-(U4-NC-PadA1)")
			(pinfunction "NC")
			(pintype "no_connect")
		)
		(pad "A2" smd circle
			(at -1.125 -2.625 180)
			(size 0.33 0.33)
			(layers "F.Cu" "F.Mask" "F.Paste")
			(net 564 "/DRAM + SRAM/SRAM.~{OE}")
			(pinfunction "OE#")
			(pintype "input")
		)
		(pad "A3" smd circle
			(at -0.375 -2.625 180)
			(size 0.33 0.33)
			(layers "F.Cu" "F.Mask" "F.Paste")
			(net 680 "/DRAM + SRAM/SRAM.A0")
			(pinfunction "A0")
			(pintype "input")
		)
		(pad "A4" smd circle
			(at 0.372 -2.625 180)
			(size 0.33 0.33)
			(layers "F.Cu" "F.Mask" "F.Paste")
			(net 686 "/DRAM + SRAM/SRAM.A1")
			(pinfunction "A1")
			(pintype "input")
		)
		(pad "A5" smd circle
			(at 1.124 -2.625 180)
			(size 0.33 0.33)
			(layers "F.Cu" "F.Mask" "F.Paste")
			(net 671 "/DRAM + SRAM/SRAM.A2")
			(pinfunction "A2")
			(pintype "input")
		)
		(pad "A6" smd circle
			(at 1.874 -2.625 180)
			(size 0.33 0.33)
			(layers "F.Cu" "F.Mask" "F.Paste")
			(net 562 "/DRAM + SRAM/SRAM.CE2")
			(pinfunction "CE2")
			(pintype "input")
		)
		(pad "B1" smd circle
			(at -1.875 -1.875 180)
			(size 0.33 0.33)
			(layers "F.Cu" "F.Mask" "F.Paste")
			(net 1123 "unconnected-(U4-NC-PadB1)")
			(pinfunction "NC")
			(pintype "no_connect")
		)
		(pad "B2" smd circle
			(at -1.125 -1.875 180)
			(size 0.33 0.33)
			(layers "F.Cu" "F.Mask" "F.Paste")
			(net 1124 "unconnected-(U4-NC-PadB2)")
			(pinfunction "NC")
			(pintype "no_connect")
		)
		(pad "B3" smd circle
			(at -0.375 -1.875 180)
			(size 0.33 0.33)
			(layers "F.Cu" "F.Mask" "F.Paste")
			(net 672 "/DRAM + SRAM/SRAM.A3")
			(pinfunction "A3")
			(pintype "input")
		)
		(pad "B4" smd circle
			(at 0.372 -1.875 180)
			(size 0.33 0.33)
			(layers "F.Cu" "F.Mask" "F.Paste")
			(net 682 "/DRAM + SRAM/SRAM.A4")
			(pinfunction "A4")
			(pintype "input")
		)
		(pad "B5" smd circle
			(at 1.124 -1.875 180)
			(size 0.33 0.33)
			(layers "F.Cu" "F.Mask" "F.Paste")
			(net 556 "/DRAM + SRAM/SRAM.~{CE}")
			(pinfunction "CE#")
			(pintype "input")
		)
		(pad "B6" smd circle
			(at 1.874 -1.875 180)
			(size 0.33 0.33)
			(layers "F.Cu" "F.Mask" "F.Paste")
			(net 1125 "unconnected-(U4-NC-PadB6)")
			(pinfunction "NC")
			(pintype "no_connect")
		)
		(pad "C1" smd circle
			(at -1.875 -1.125 180)
			(size 0.33 0.33)
			(layers "F.Cu" "F.Mask" "F.Paste")
			(net 683 "/DRAM + SRAM/SRAM.DQ0")
			(pinfunction "DQ0")
			(pintype "bidirectional")
		)
		(pad "C2" smd circle
			(at -1.125 -1.125 180)
			(size 0.33 0.33)
			(layers "F.Cu" "F.Mask" "F.Paste")
			(net 1126 "unconnected-(U4-NC-PadC2)")
			(pinfunction "NC")
			(pintype "no_connect")
		)
		(pad "C3" smd circle
			(at -0.375 -1.125 180)
			(size 0.33 0.33)
			(layers "F.Cu" "F.Mask" "F.Paste")
			(net 664 "/DRAM + SRAM/SRAM.A5")
			(pinfunction "A5")
			(pintype "input")
		)
		(pad "C4" smd circle
			(at 0.372 -1.125 180)
			(size 0.33 0.33)
			(layers "F.Cu" "F.Mask" "F.Paste")
			(net 665 "/DRAM + SRAM/SRAM.A6")
			(pinfunction "A6")
			(pintype "input")
		)
		(pad "C5" smd circle
			(at 1.124 -1.125 180)
			(size 0.33 0.33)
			(layers "F.Cu" "F.Mask" "F.Paste")
			(net 1127 "unconnected-(U4-NC-PadC5)")
			(pinfunction "NC")
			(pintype "no_connect")
		)
		(pad "C6" smd circle
			(at 1.874 -1.125 180)
			(size 0.33 0.33)
			(layers "F.Cu" "F.Mask" "F.Paste")
			(net 676 "/DRAM + SRAM/SRAM.DQ4")
			(pinfunction "DQ4")
			(pintype "bidirectional")
		)
		(pad "D1" smd circle
			(at -1.875 -0.375 180)
			(size 0.33 0.33)
			(layers "F.Cu" "F.Mask" "F.Paste")
			(net 1 "GND")
			(pinfunction "VSS")
			(pintype "passive")
		)
		(pad "D2" smd circle
			(at -1.125 -0.375 180)
			(size 0.33 0.33)
			(layers "F.Cu" "F.Mask" "F.Paste")
			(net 687 "/DRAM + SRAM/SRAM.DQ1")
			(pinfunction "DQ1")
			(pintype "bidirectional")
		)
		(pad "D3" smd circle
			(at -0.375 -0.375 180)
			(size 0.33 0.33)
			(layers "F.Cu" "F.Mask" "F.Paste")
			(net 690 "/DRAM + SRAM/SRAM.A17")
			(pinfunction "A17")
			(pintype "input")
		)
		(pad "D4" smd circle
			(at 0.372 -0.375 180)
			(size 0.33 0.33)
			(layers "F.Cu" "F.Mask" "F.Paste")
			(net 684 "/DRAM + SRAM/SRAM.A7")
			(pinfunction "A7")
			(pintype "input")
		)
		(pad "D5" smd circle
			(at 1.124 -0.375 180)
			(size 0.33 0.33)
			(layers "F.Cu" "F.Mask" "F.Paste")
			(net 674 "/DRAM + SRAM/SRAM.DQ5")
			(pinfunction "DQ5")
			(pintype "bidirectional")
		)
		(pad "D6" smd circle
			(at 1.874 -0.375 180)
			(size 0.33 0.33)
			(layers "F.Cu" "F.Mask" "F.Paste")
			(net 24 "+3V3")
			(pinfunction "VCC")
			(pintype "power_in")
		)
		(pad "E1" smd circle
			(at -1.875 0.372 180)
			(size 0.33 0.33)
			(layers "F.Cu" "F.Mask" "F.Paste")
			(net 24 "+3V3")
			(pinfunction "VCC")
			(pintype "passive")
		)
		(pad "E2" smd circle
			(at -1.125 0.372 180)
			(size 0.33 0.33)
			(layers "F.Cu" "F.Mask" "F.Paste")
			(net 688 "/DRAM + SRAM/SRAM.DQ2")
			(pinfunction "DQ2")
			(pintype "bidirectional")
		)
		(pad "E3" smd circle
			(at -0.375 0.372 180)
			(size 0.33 0.33)
			(layers "F.Cu" "F.Mask" "F.Paste")
			(net 1128 "unconnected-(U4-NC-PadE3)")
			(pinfunction "NC")
			(pintype "no_connect")
		)
		(pad "E4" smd circle
			(at 0.372 0.372 180)
			(size 0.33 0.33)
			(layers "F.Cu" "F.Mask" "F.Paste")
			(net 689 "/DRAM + SRAM/SRAM.A16")
			(pinfunction "A16")
			(pintype "input")
		)
		(pad "E5" smd circle
			(at 1.124 0.372 180)
			(size 0.33 0.33)
			(layers "F.Cu" "F.Mask" "F.Paste")
			(net 668 "/DRAM + SRAM/SRAM.DQ6")
			(pinfunction "DQ6")
			(pintype "bidirectional")
		)
		(pad "E6" smd circle
			(at 1.874 0.372 180)
			(size 0.33 0.33)
			(layers "F.Cu" "F.Mask" "F.Paste")
			(net 1 "GND")
			(pinfunction "VSS")
			(pintype "passive")
		)
		(pad "F1" smd circle
			(at -1.875 1.124 180)
			(size 0.33 0.33)
			(layers "F.Cu" "F.Mask" "F.Paste")
			(net 666 "/DRAM + SRAM/SRAM.DQ3")
			(pinfunction "DQ3")
			(pintype "bidirectional")
		)
		(pad "F2" smd circle
			(at -1.125 1.124 180)
			(size 0.33 0.33)
			(layers "F.Cu" "F.Mask" "F.Paste")
			(net 1129 "unconnected-(U4-NC-PadF2)")
			(pinfunction "NC")
			(pintype "no_connect")
		)
		(pad "F3" smd circle
			(at -0.375 1.124 180)
			(size 0.33 0.33)
			(layers "F.Cu" "F.Mask" "F.Paste")
			(net 677 "/DRAM + SRAM/SRAM.A14")
			(pinfunction "A14")
			(pintype "input")
		)
		(pad "F4" smd circle
			(at 0.372 1.124 180)
			(size 0.33 0.33)
			(layers "F.Cu" "F.Mask" "F.Paste")
			(net 675 "/DRAM + SRAM/SRAM.A15")
			(pinfunction "A15")
			(pintype "input")
		)
		(pad "F5" smd circle
			(at 1.124 1.124 180)
			(size 0.33 0.33)
			(layers "F.Cu" "F.Mask" "F.Paste")
			(net 1130 "unconnected-(U4-NC-PadF5)")
			(pinfunction "NC")
			(pintype "no_connect")
		)
		(pad "F6" smd circle
			(at 1.874 1.124 180)
			(size 0.33 0.33)
			(layers "F.Cu" "F.Mask" "F.Paste")
			(net 669 "/DRAM + SRAM/SRAM.DQ7")
			(pinfunction "DQ7")
			(pintype "bidirectional")
		)
		(pad "G1" smd circle
			(at -1.875 1.874 180)
			(size 0.33 0.33)
			(layers "F.Cu" "F.Mask" "F.Paste")
			(net 1131 "unconnected-(U4-NC-PadG1)")
			(pinfunction "NC")
			(pintype "no_connect")
		)
		(pad "G2" smd circle
			(at -1.125 1.874 180)
			(size 0.33 0.33)
			(layers "F.Cu" "F.Mask" "F.Paste")
			(net 1132 "unconnected-(U4-NC-PadG2)")
			(pinfunction "NC")
			(pintype "no_connect")
		)
		(pad "G3" smd circle
			(at -0.375 1.874 180)
			(size 0.33 0.33)
			(layers "F.Cu" "F.Mask" "F.Paste")
			(net 681 "/DRAM + SRAM/SRAM.A12")
			(pinfunction "A12")
			(pintype "input")
		)
		(pad "G4" smd circle
			(at 0.372 1.874 180)
			(size 0.33 0.33)
			(layers "F.Cu" "F.Mask" "F.Paste")
			(net 673 "/DRAM + SRAM/SRAM.A13")
			(pinfunction "A13")
			(pintype "input")
		)
		(pad "G5" smd circle
			(at 1.124 1.874 180)
			(size 0.33 0.33)
			(layers "F.Cu" "F.Mask" "F.Paste")
			(net 563 "/DRAM + SRAM/SRAM.~{WE}")
			(pinfunction "WE#")
			(pintype "input")
		)
		(pad "G6" smd circle
			(at 1.874 1.874 180)
			(size 0.33 0.33)
			(layers "F.Cu" "F.Mask" "F.Paste")
			(net 1133 "unconnected-(U4-NC-PadG6)")
			(pinfunction "NC")
			(pintype "no_connect")
		)
		(pad "H1" smd circle
			(at -1.875 2.624 180)
			(size 0.33 0.33)
			(layers "F.Cu" "F.Mask" "F.Paste")
			(net 685 "/DRAM + SRAM/SRAM.A18")
			(pinfunction "A18")
			(pintype "input")
		)
		(pad "H2" smd circle
			(at -1.125 2.624 180)
			(size 0.33 0.33)
			(layers "F.Cu" "F.Mask" "F.Paste")
			(net 667 "/DRAM + SRAM/SRAM.A8")
			(pinfunction "A8")
			(pintype "input")
		)
		(pad "H3" smd circle
			(at -0.375 2.624 180)
			(size 0.33 0.33)
			(layers "F.Cu" "F.Mask" "F.Paste")
			(net 670 "/DRAM + SRAM/SRAM.A9")
			(pinfunction "A9")
			(pintype "input")
		)
		(pad "H4" smd circle
			(at 0.372 2.624 180)
			(size 0.33 0.33)
			(layers "F.Cu" "F.Mask" "F.Paste")
			(net 679 "/DRAM + SRAM/SRAM.A10")
			(pinfunction "A10")
			(pintype "input")
		)
		(pad "H5" smd circle
			(at 1.124 2.624 180)
			(size 0.33 0.33)
			(layers "F.Cu" "F.Mask" "F.Paste")
			(net 678 "/DRAM + SRAM/SRAM.A11")
			(pinfunction "A11")
			(pintype "input")
		)
		(pad "H6" smd circle
			(at 1.874 2.624 180)
			(size 0.33 0.33)
			(layers "F.Cu" "F.Mask" "F.Paste")
			(net 691 "/DRAM + SRAM/SRAM.A19")
			(pinfunction "A19")
			(pintype "input")
		)
	)
	(footprint "antmicro-footprints:LGA-33_7x7mm_P0.65mm"
		(layer "F.Cu")
		(at 176.1125 170.825 180)
		(property "Reference" "U32"
			(at 6.0625 3.625 180)
			(layer "F.SilkS")
			(effects
				(font
					(size 0.7 0.7)
					(thickness 0.15)
				)
				(justify left bottom)
			)
		)
		(property "Value" "MPM54304GMN"
			(at -3.5 0.3 180)
			(layer "F.Fab")
			(effects
				(font
					(size 0.7 0.7)
					(thickness 0.15)
				)
				(justify left bottom)
			)
		)
		(property "Description" "DC-DC Switching Synchronous Step-Down Regulator, Multi Output, 4-16V in, 1V/3.3V, 4.2/3A out, LGA33"
			(at 0 0 180)
			(layer "F.Fab")
			(hide yes)
			(effects
				(font
					(size 1.27 1.27)
					(thickness 0.15)
				)
			)
		)
		(property "Author" "Antmicro"
			(at 352.225 341.65 0)
			(layer "F.Fab")
			(hide yes)
			(effects
				(font
					(size 1 1)
					(thickness 0.15)
				)
			)
		)
		(property "License" "Apache-2.0"
			(at 352.225 341.65 0)
			(layer "F.Fab")
			(hide yes)
			(effects
				(font
					(size 1 1)
					(thickness 0.15)
				)
			)
		)
		(property "MPN" "MPM54304GMN-0000"
			(at 352.225 341.65 0)
			(layer "F.Fab")
			(hide yes)
			(effects
				(font
					(size 1 1)
					(thickness 0.15)
				)
			)
		)
		(property "Manufacturer" "Monolithic Power Systems"
			(at 352.225 341.65 0)
			(layer "F.Fab")
			(hide yes)
			(effects
				(font
					(size 1 1)
					(thickness 0.15)
				)
			)
		)
		(sheetname "DC-DC Converters")
		(sheetfile "dc-dc.kicad_sch")
		(solder_paste_margin_ratio -0.1)
		(attr smd)
		(fp_line
			(start 3.648 3.648)
			(end 3.648 2.922)
			(stroke
				(width 0.15)
				(type solid)
			)
			(layer "F.SilkS")
		)
		(fp_line
			(start 3.648 -3.65)
			(end 3.648 -2.926)
			(stroke
				(width 0.15)
				(type solid)
			)
			(layer "F.SilkS")
		)
		(fp_line
			(start 2.922 3.648)
			(end 3.648 3.648)
			(stroke
				(width 0.15)
				(type solid)
			)
			(layer "F.SilkS")
		)
		(fp_line
			(start 2.922 -3.65)
			(end 3.648 -3.65)
			(stroke
				(width 0.15)
				(type solid)
			)
			(layer "F.SilkS")
		)
		(fp_line
			(start -2.926 3.648)
			(end -3.65 3.648)
			(stroke
				(width 0.15)
				(type solid)
			)
			(layer "F.SilkS")
		)
		(fp_line
			(start -3.65 3.648)
			(end -3.65 2.922)
			(stroke
				(width 0.15)
				(type solid)
			)
			(layer "F.SilkS")
		)
		(fp_line
			(start -3.665 -2.928)
			(end -3.665 -3.653)
			(stroke
				(width 0.15)
				(type solid)
			)
			(layer "F.SilkS")
		)
		(fp_line
			(start -3.665 -3.653)
			(end -2.94 -3.653)
			(stroke
				(width 0.15)
				(type solid)
			)
			(layer "F.SilkS")
		)
		(fp_circle
			(center -3.8 -1.925)
			(end -3.75 -1.925)
			(stroke
				(width 0.15)
				(type solid)
			)
			(fill yes)
			(layer "F.SilkS")
		)
		(fp_rect
			(start -4 -4)
			(end 3.999 3.999)
			(stroke
				(width 0.05)
				(type solid)
			)
			(fill no)
			(layer "F.CrtYd")
		)
		(fp_line
			(start 3.499 3.499)
			(end 3.499 -3.5)
			(stroke
				(width 0.15)
				(type solid)
			)
			(layer "F.Fab")
		)
		(fp_line
			(start 3.499 -3.5)
			(end -3.5 -3.5)
			(stroke
				(width 0.15)
				(type solid)
			)
			(layer "F.Fab")
		)
		(fp_line
			(start -3.101 -3.5)
			(end -3.5 -3.101)
			(stroke
				(width 0.15)
				(type solid)
			)
			(layer "F.Fab")
		)
		(fp_line
			(start -3.5 3.499)
			(end 3.499 3.499)
			(stroke
				(width 0.15)
				(type solid)
			)
			(layer "F.Fab")
		)
		(fp_line
			(start -3.5 -3.5)
			(end -3.5 3.499)
			(stroke
				(width 0.15)
				(type solid)
			)
			(layer "F.Fab")
		)
		(pad "1" smd rect
			(at -3.138 -1.625 270)
			(size 0.3 1.125)
			(layers "F.Cu" "F.Mask" "F.Paste")
			(net 739 "/DC-DC Converters/5V_local")
			(pinfunction "VOUT3")
			(pintype "power_out")
		)
		(pad "2" smd rect
			(at -3.138 -0.975 270)
			(size 0.3 1.125)
			(layers "F.Cu" "F.Mask" "F.Paste")
			(net 1 "GND")
			(pinfunction "GND")
			(pintype "passive")
		)
		(pad "3" smd rect
			(at -3.138 -0.328 270)
			(size 0.3 1.125)
			(layers "F.Cu" "F.Mask" "F.Paste")
			(net 1336 "/I2C.SDA")
			(pinfunction "SDA")
			(pintype "bidirectional")
		)
		(pad "4" smd rect
			(at -3.138 0.325 270)
			(size 0.3 1.125)
			(layers "F.Cu" "F.Mask" "F.Paste")
			(net 1393 "/I2C.QDCDC2_SCL")
			(pinfunction "SCL")
			(pintype "input")
		)
		(pad "5" smd rect
			(at -3.138 0.972 270)
			(size 0.3 1.125)
			(layers "F.Cu" "F.Mask" "F.Paste")
			(net 1 "GND")
			(pinfunction "GND")
			(pintype "passive")
		)
		(pad "6" smd rect
			(at -3.138 1.624 270)
			(size 0.3 1.125)
			(layers "F.Cu" "F.Mask" "F.Paste")
			(net 957 "/DC-DC Converters/FB6")
			(pinfunction "FB2")
			(pintype "input")
		)
		(pad "7" smd rect
			(at -2.926 3.136)
			(size 0.3 1.125)
			(layers "F.Cu" "F.Mask" "F.Paste")
			(net 1 "GND")
			(pinfunction "GND")
			(pintype "passive")
		)
		(pad "8" smd rect
			(at -2.275 3.136)
			(size 0.3 1.125)
			(layers "F.Cu" "F.Mask" "F.Paste")
			(net 736 "/DC-DC Converters/3V3_local_2")
			(pinfunction "VOUT2")
			(pintype "power_out")
		)
		(pad "9" smd rect
			(at -1.625 3.136 180)
			(size 0.3 1.125)
			(layers "F.Cu" "F.Mask" "F.Paste")
			(net 736 "/DC-DC Converters/3V3_local_2")
			(pinfunction "VOUT2")
			(pintype "passive")
		)
		(pad "10" smd rect
			(at -0.975 3.136 180)
			(size 0.3 1.125)
			(layers "F.Cu" "F.Mask" "F.Paste")
			(net 1 "GND")
			(pinfunction "GND")
			(pintype "passive")
		)
		(pad "11" smd rect
			(at -0.328 3.136 180)
			(size 0.3 1.125)
			(layers "F.Cu" "F.Mask" "F.Paste")
			(net 1052 "/DC-DC Converters/SW2")
			(pinfunction "SW2")
			(pintype "power_out")
		)
		(pad "12" smd rect
			(at 0.325 3.136 180)
			(size 0.3 1.125)
			(layers "F.Cu" "F.Mask" "F.Paste")
			(net 1143 "/DC-DC Converters/SW1")
			(pinfunction "SW1")
			(pintype "power_out")
		)
		(pad "13" smd rect
			(at 0.972 3.136 180)
			(size 0.3 1.125)
			(layers "F.Cu" "F.Mask" "F.Paste")
			(net 1 "GND")
			(pinfunction "GND")
			(pintype "passive")
		)
		(pad "14" smd rect
			(at 1.624 3.136 180)
			(size 0.3 1.125)
			(layers "F.Cu" "F.Mask" "F.Paste")
			(net 735 "/DC-DC Converters/3V3_local")
			(pinfunction "VOUT1")
			(pintype "power_out")
		)
		(pad "15" smd rect
			(at 2.273 3.136 180)
			(size 0.3 1.125)
			(layers "F.Cu" "F.Mask" "F.Paste")
			(net 735 "/DC-DC Converters/3V3_local")
			(pinfunction "VOUT1")
			(pintype "passive")
		)
		(pad "16" smd rect
			(at 2.922 3.136 180)
			(size 0.3 1.125)
			(layers "F.Cu" "F.Mask" "F.Paste")
			(net 1 "GND")
			(pinfunction "GND")
			(pintype "passive")
		)
		(pad "17" smd rect
			(at 3.136 1.624 270)
			(size 0.3 1.125)
			(layers "F.Cu" "F.Mask" "F.Paste")
			(net 1 "GND")
			(pinfunction "SGND1")
			(pintype "power_out")
		)
		(pad "18" smd rect
			(at 3.136 0.972 270)
			(size 0.3 1.125)
			(layers "F.Cu" "F.Mask" "F.Paste")
			(net 958 "/DC-DC Converters/FB5")
			(pinfunction "FB1")
			(pintype "input")
		)
		(pad "19" smd rect
			(at 3.136 0.325 270)
			(size 0.3 1.125)
			(layers "F.Cu" "F.Mask" "F.Paste")
			(net 968 "/DC-DC Converters/EN3")
			(pinfunction "EN/SYNCI")
			(pintype "input")
		)
		(pad "20" smd rect
			(at 3.136 -0.328 270)
			(size 0.3 1.125)
			(layers "F.Cu" "F.Mask" "F.Paste")
			(net 1 "GND")
			(pinfunction "GND")
			(pintype "passive")
		)
		(pad "21" smd rect
			(at 3.136 -0.975 270)
			(size 0.3 1.125)
			(layers "F.Cu" "F.Mask" "F.Paste")
			(net 1 "GND")
			(pinfunction "GND")
			(pintype "passive")
		)
		(pad "22" smd rect
			(at 3.136 -1.625 270)
			(size 0.3 1.125)
			(layers "F.Cu" "F.Mask" "F.Paste")
			(net 740 "/DC-DC Converters/1V35_local")
			(pinfunction "VOUT4")
			(pintype "power_out")
		)
		(pad "23" smd rect
			(at 2.922 -3.138)
			(size 0.3 1.125)
			(layers "F.Cu" "F.Mask" "F.Paste")
			(net 740 "/DC-DC Converters/1V35_local")
			(pinfunction "VOUT4")
			(pintype "passive")
		)
		(pad "24" smd rect
			(at 2.273 -3.138)
			(size 0.3 1.125)
			(layers "F.Cu" "F.Mask" "F.Paste")
			(net 965 "/DC-DC Converters/FB8")
			(pinfunction "FB4")
			(pintype "input")
		)
		(pad "25" smd rect
			(at 1.624 -3.138 180)
			(size 0.3 1.125)
			(layers "F.Cu" "F.Mask" "F.Paste")
			(net 732 "/DC-DC Converters/QDCDC2_VCC")
			(pinfunction "VCC")
			(pintype "input")
		)
		(pad "26" smd rect
			(at 0.972 -3.138 180)
			(size 0.3 1.125)
			(layers "F.Cu" "F.Mask" "F.Paste")
			(net 954 "/DC-DC Converters/QDCDC2_GPIO")
			(pinfunction "GPIO")
			(pintype "input")
		)
		(pad "27" smd rect
			(at 0.325 -3.138 180)
			(size 0.3 1.125)
			(layers "F.Cu" "F.Mask" "F.Paste")
			(net 1 "GND")
			(pinfunction "GND")
			(pintype "passive")
		)
		(pad "28" smd rect
			(at -0.328 -3.138 180)
			(size 0.3 1.125)
			(layers "F.Cu" "F.Mask" "F.Paste")
			(net 702 "VDC")
			(pinfunction "VIN")
			(pintype "input")
		)
		(pad "29" smd rect
			(at -0.975 -3.138 180)
			(size 0.3 1.125)
			(layers "F.Cu" "F.Mask" "F.Paste")
			(net 702 "VDC")
			(pinfunction "VIN")
			(pintype "passive")
		)
		(pad "30" smd rect
			(at -1.625 -3.138 180)
			(size 0.3 1.125)
			(layers "F.Cu" "F.Mask" "F.Paste")
			(net 1 "GND")
			(pinfunction "SGND2")
			(pintype "power_out")
		)
		(pad "31" smd rect
			(at -2.275 -3.138 180)
			(size 0.3 1.125)
			(layers "F.Cu" "F.Mask" "F.Paste")
			(net 964 "/DC-DC Converters/FB7")
			(pinfunction "FB3")
			(pintype "input")
		)
		(pad "32" smd rect
			(at -2.926 -3.138 180)
			(size 0.3 1.125)
			(layers "F.Cu" "F.Mask" "F.Paste")
			(net 739 "/DC-DC Converters/5V_local")
			(pinfunction "VOUT3")
			(pintype "passive")
		)
		(pad "33" smd rect
			(at -0.863 -0.863 180)
			(size 1.725 1.725)
			(layers "F.Cu" "F.Mask" "F.Paste")
			(net 1 "GND")
			(pinfunction "GND")
			(pintype "passive")
			(solder_paste_margin -0.1)
		)
		(pad "33" smd rect
			(at -0.863 0.86 180)
			(size 1.725 1.725)
			(layers "F.Cu" "F.Mask" "F.Paste")
			(net 1 "GND")
			(pinfunction "GND")
			(pintype "passive")
			(solder_paste_margin -0.1)
		)
		(pad "33" smd rect
			(at 0.86 -0.863 180)
			(size 1.725 1.725)
			(layers "F.Cu" "F.Mask" "F.Paste")
			(net 1 "GND")
			(pinfunction "GND")
			(pintype "passive")
			(solder_paste_margin -0.1)
		)
		(pad "33" smd rect
			(at 0.86 0.86 180)
			(size 1.725 1.725)
			(layers "F.Cu" "F.Mask" "F.Paste")
			(net 1 "GND")
			(pinfunction "GND")
			(pintype "passive")
			(solder_paste_margin -0.1)
		)
	)
	(footprint "antmicro-footprints:C_0402_1005Metric"
		(layer "F.Cu")
		(at 221.5 146.7)
		(descr "Capacitor SMD 0402")
		(tags "capacitor SMD 0402")
		(property "Reference" "C257"
			(at 0.75 0.4 0)
			(layer "F.SilkS")
			(effects
				(font
					(size 0.7 0.7)
					(thickness 0.15)
				)
				(justify left bottom)
			)
		)
		(property "Value" "C_100n_0402"
			(at 0 1.169 0)
			(layer "F.Fab")
			(effects
				(font
					(size 0.7 0.7)
					(thickness 0.15)
				)
				(justify left bottom)
			)
		)
		(property "Description" "SMD Multilayer Ceramic Capacitor, 0.1 µF, 50 V, 0402 [1005 Metric], ± 10%, X5R, GRM Series"
			(at 0 0 0)
			(layer "F.Fab")
			(hide yes)
			(effects
				(font
					(size 1.27 1.27)
					(thickness 0.15)
				)
			)
		)
		(property "Author" "Antmicro"
			(at 0 0 0)
			(layer "F.Fab")
			(hide yes)
			(effects
				(font
					(size 1 1)
					(thickness 0.15)
				)
			)
		)
		(property "Dielectric" "X5R"
			(at 0 0 0)
			(layer "F.Fab")
			(hide yes)
			(effects
				(font
					(size 1 1)
					(thickness 0.15)
				)
			)
		)
		(property "License" "Apache-2.0"
			(at 0 0 0)
			(layer "F.Fab")
			(hide yes)
			(effects
				(font
					(size 1 1)
					(thickness 0.15)
				)
			)
		)
		(property "MPN" "GRM155R61H104KE14D"
			(at 0 0 0)
			(layer "F.Fab")
			(hide yes)
			(effects
				(font
					(size 1 1)
					(thickness 0.15)
				)
			)
		)
		(property "Manufacturer" "Murata"
			(at 0 0 0)
			(layer "F.Fab")
			(hide yes)
			(effects
				(font
					(size 1 1)
					(thickness 0.15)
				)
			)
		)
		(property "Val" "100n"
			(at 0 0 0)
			(layer "F.Fab")
			(hide yes)
			(effects
				(font
					(size 1 1)
					(thickness 0.15)
				)
			)
		)
		(property "Voltage" "50V"
			(at 0 0 0)
			(layer "F.Fab")
			(hide yes)
			(effects
				(font
					(size 1 1)
					(thickness 0.15)
				)
			)
		)
		(sheetname "HDMI + Ethernet")
		(sheetfile "hdmi-ethernet.kicad_sch")
		(attr smd)
		(fp_rect
			(start -0.925 -0.47)
			(end 0.925 0.47)
			(stroke
				(width 0.05)
				(type default)
			)
			(fill no)
			(layer "F.CrtYd")
		)
		(fp_line
			(start -0.494 -0.25)
			(end 0.504 -0.25)
			(stroke
				(width 0.15)
				(type solid)
			)
			(layer "F.Fab")
		)
		(fp_line
			(start -0.494 0.248)
			(end -0.494 -0.25)
			(stroke
				(width 0.15)
				(type solid)
			)
			(layer "F.Fab")
		)
		(fp_line
			(start 0.504 -0.25)
			(end 0.504 0.248)
			(stroke
				(width 0.15)
				(type solid)
			)
			(layer "F.Fab")
		)
		(fp_line
			(start 0.504 0.248)
			(end -0.494 0.248)
			(stroke
				(width 0.15)
				(type solid)
			)
			(layer "F.Fab")
		)
		(pad "1" smd roundrect
			(at -0.48 0)
			(size 0.59 0.64)
			(layers "F.Cu" "F.Mask" "F.Paste")
			(roundrect_rratio 0.25)
			(net 1 "GND")
			(pintype "passive")
		)
		(pad "2" smd roundrect
			(at 0.48 0)
			(size 0.59 0.64)
			(layers "F.Cu" "F.Mask" "F.Paste")
			(roundrect_rratio 0.25)
			(net 26 "+1V8")
			(pintype "passive")
		)
	)
	(footprint "antmicro-footprints:C_0402_1005Metric"
		(layer "F.Cu")
		(at 201.703752 100.9115)
		(descr "Capacitor SMD 0402")
		(tags "capacitor SMD 0402")
		(property "Reference" "C285"
			(at 4.296248 8.0885 0)
			(layer "F.SilkS")
			(effects
				(font
					(size 0.7 0.7)
					(thickness 0.15)
				)
				(justify left bottom)
			)
		)
		(property "Value" "C_10u_0402"
			(at 0 1.4 0)
			(layer "F.Fab")
			(effects
				(font
					(size 0.7 0.7)
					(thickness 0.15)
				)
				(justify left bottom)
			)
		)
		(property "Description" "SMD Multilayer Ceramic Capacitor, 10 µF, 6.3 V, 0402 [1005 Metric], ± 20%, X5R, CC Series"
			(at 0 0 0)
			(layer "F.Fab")
			(hide yes)
			(effects
				(font
					(size 1.27 1.27)
					(thickness 0.15)
				)
			)
		)
		(property "Author" "Antmicro"
			(at 0 0 0)
			(layer "F.Fab")
			(hide yes)
			(effects
				(font
					(size 1 1)
					(thickness 0.15)
				)
			)
		)
		(property "Dielectric" ""
			(at 0 0 0)
			(layer "F.Fab")
			(hide yes)
			(effects
				(font
					(size 1 1)
					(thickness 0.15)
				)
			)
		)
		(property "License" "Apache-2.0"
			(at 0 0 0)
			(layer "F.Fab")
			(hide yes)
			(effects
				(font
					(size 1 1)
					(thickness 0.15)
				)
			)
		)
		(property "MPN" "CC0402MRX5R5BB106"
			(at 0 0 0)
			(layer "F.Fab")
			(hide yes)
			(effects
				(font
					(size 1 1)
					(thickness 0.15)
				)
			)
		)
		(property "Manufacturer" "YAGEO"
			(at 0 0 0)
			(layer "F.Fab")
			(hide yes)
			(effects
				(font
					(size 1 1)
					(thickness 0.15)
				)
			)
		)
		(property "Val" "10u"
			(at 0 0 0)
			(layer "F.Fab")
			(hide yes)
			(effects
				(font
					(size 1 1)
					(thickness 0.15)
				)
			)
		)
		(property "Voltage" ""
			(at 0 0 0)
			(layer "F.Fab")
			(hide yes)
			(effects
				(font
					(size 1 1)
					(thickness 0.15)
				)
			)
		)
		(sheetname "HDMI + Ethernet")
		(sheetfile "hdmi-ethernet.kicad_sch")
		(attr smd)
		(fp_rect
			(start -0.925 -0.47)
			(end 0.925 0.47)
			(stroke
				(width 0.05)
				(type default)
			)
			(fill no)
			(layer "F.CrtYd")
		)
		(fp_line
			(start -0.494 -0.25)
			(end 0.504 -0.25)
			(stroke
				(width 0.15)
				(type solid)
			)
			(layer "F.Fab")
		)
		(fp_line
			(start -0.494 0.248)
			(end -0.494 -0.25)
			(stroke
				(width 0.15)
				(type solid)
			)
			(layer "F.Fab")
		)
		(fp_line
			(start 0.504 -0.25)
			(end 0.504 0.248)
			(stroke
				(width 0.15)
				(type solid)
			)
			(layer "F.Fab")
		)
		(fp_line
			(start 0.504 0.248)
			(end -0.494 0.248)
			(stroke
				(width 0.15)
				(type solid)
			)
			(layer "F.Fab")
		)
		(pad "1" smd roundrect
			(at -0.48 0)
			(size 0.59 0.64)
			(layers "F.Cu" "F.Mask" "F.Paste")
			(roundrect_rratio 0.25)
			(net 1 "GND")
			(pintype "passive")
		)
		(pad "2" smd roundrect
			(at 0.48 0)
			(size 0.59 0.64)
			(layers "F.Cu" "F.Mask" "F.Paste")
			(roundrect_rratio 0.25)
			(net 728 "/HDMI + Ethernet/GBE_AVDDL{slash}PLL")
			(pintype "passive")
		)
	)
	(footprint "antmicro-footprints:C_0805_2012Metric"
		(layer "F.Cu")
		(at 176.05 176.1625)
		(descr "Capacitor SMD 0805")
		(tags "capacitor SMD 0805")
		(property "Reference" "C320"
			(at -1.3 3.8375 0)
			(layer "F.SilkS")
			(effects
				(font
					(size 0.7 0.7)
					(thickness 0.15)
				)
				(justify left bottom)
			)
		)
		(property "Value" "C_22u_25V_0805"
			(at 0 1.947 0)
			(layer "F.Fab")
			(effects
				(font
					(size 0.7 0.7)
					(thickness 0.15)
				)
				(justify left bottom)
			)
		)
		(property "Description" "SMT Multilayer Ceramic Capacitor, 22uF, +/-20%, 25V, X5R, 0805 [2012 Metric]"
			(at 0 0 0)
			(layer "F.Fab")
			(hide yes)
			(effects
				(font
					(size 1.27 1.27)
					(thickness 0.15)
				)
			)
		)
		(property "Author" "Antmicro"
			(at 0 0 0)
			(layer "F.Fab")
			(hide yes)
			(effects
				(font
					(size 1 1)
					(thickness 0.15)
				)
			)
		)
		(property "Dielectric" "X5R"
			(at 0 0 0)
			(layer "F.Fab")
			(hide yes)
			(effects
				(font
					(size 1 1)
					(thickness 0.15)
				)
			)
		)
		(property "License" "Apache-2.0"
			(at 0 0 0)
			(layer "F.Fab")
			(hide yes)
			(effects
				(font
					(size 1 1)
					(thickness 0.15)
				)
			)
		)
		(property "MPN" "CL21A226MAYNNNE"
			(at 0 0 0)
			(layer "F.Fab")
			(hide yes)
			(effects
				(font
					(size 1 1)
					(thickness 0.15)
				)
			)
		)
		(property "Manufacturer" "Samsung Electro-Mechanics"
			(at 0 0 0)
			(layer "F.Fab")
			(hide yes)
			(effects
				(font
					(size 1 1)
					(thickness 0.15)
				)
			)
		)
		(property "Val" "22u"
			(at 0 0 0)
			(layer "F.Fab")
			(hide yes)
			(effects
				(font
					(size 1 1)
					(thickness 0.15)
				)
			)
		)
		(property "Voltage" "25V"
			(at 0 0 0)
			(layer "F.Fab")
			(hide yes)
			(effects
				(font
					(size 1 1)
					(thickness 0.15)
				)
			)
		)
		(sheetname "DC-DC Converters")
		(sheetfile "dc-dc.kicad_sch")
		(attr smd)
		(fp_line
			(start -0.3 -0.7)
			(end 0.3 -0.7)
			(stroke
				(width 0.15)
				(type solid)
			)
			(layer "F.SilkS")
		)
		(fp_line
			(start -0.3 0.7)
			(end 0.3 0.7)
			(stroke
				(width 0.15)
				(type solid)
			)
			(layer "F.SilkS")
		)
		(fp_rect
			(start 1.95 -0.9)
			(end -1.95 0.9)
			(stroke
				(width 0.05)
				(type default)
			)
			(fill no)
			(layer "F.CrtYd")
		)
		(fp_rect
			(start -0.95 -0.675)
			(end 0.95 0.675)
			(stroke
				(width 0.15)
				(type solid)
			)
			(fill no)
			(layer "F.Fab")
		)
		(pad "1" smd roundrect
			(at -1.1 0)
			(size 1.2 1.3)
			(layers "F.Cu" "F.Mask" "F.Paste")
			(roundrect_rratio 0.25)
			(net 1 "GND")
			(pintype "passive")
		)
		(pad "2" smd roundrect
			(at 1.1 0)
			(size 1.2 1.3)
			(layers "F.Cu" "F.Mask" "F.Paste")
			(roundrect_rratio 0.25)
			(net 702 "VDC")
			(pintype "passive")
		)
	)
	(footprint "antmicro-footprints:D_SOD-123F"
		(layer "F.Cu")
		(at 249.6 179.7)
		(property "Reference" "D10"
			(at 2.15 0.35 0)
			(layer "F.SilkS")
			(effects
				(font
					(size 0.7 0.7)
					(thickness 0.15)
				)
				(justify left bottom)
			)
		)
		(property "Value" "PTVS58VS1UR,115"
			(at 0 2.1 0)
			(layer "F.Fab")
			(effects
				(font
					(size 0.7 0.7)
					(thickness 0.15)
				)
				(justify left bottom)
			)
		)
		(property "Description" "Unidirectional TVS, 8 kV,  SOD-123F, 58 V"
			(at 0 0 0)
			(layer "F.Fab")
			(hide yes)
			(effects
				(font
					(size 1.27 1.27)
					(thickness 0.15)
				)
			)
		)
		(property "Author" "Antmicro"
			(at 0 0 0)
			(layer "F.Fab")
			(hide yes)
			(effects
				(font
					(size 1 1)
					(thickness 0.15)
				)
			)
		)
		(property "License" "Apache-2.0"
			(at 0 0 0)
			(layer "F.Fab")
			(hide yes)
			(effects
				(font
					(size 1 1)
					(thickness 0.15)
				)
			)
		)
		(property "MPN" "PTVS58VS1UR,115"
			(at 0 0 0)
			(layer "F.Fab")
			(hide yes)
			(effects
				(font
					(size 1 1)
					(thickness 0.15)
				)
			)
		)
		(property "Manufacturer" "Nexperia"
			(at 0 0 0)
			(layer "F.Fab")
			(hide yes)
			(effects
				(font
					(size 1 1)
					(thickness 0.15)
				)
			)
		)
		(property "Public" "False"
			(at 0 0 0)
			(layer "F.Fab")
			(hide yes)
			(effects
				(font
					(size 1 1)
					(thickness 0.15)
				)
			)
		)
		(sheetname "Power supply")
		(sheetfile "power-supply.kicad_sch")
		(attr smd)
		(fp_line
			(start -0.65 -0.6)
			(end -0.65 0.6)
			(stroke
				(width 0.15)
				(type solid)
			)
			(layer "F.SilkS")
		)
		(fp_line
			(start -2.21 1.1)
			(end -2.21 -1.1)
			(stroke
				(width 0.05)
				(type solid)
			)
			(layer "F.CrtYd")
		)
		(fp_line
			(start 2.2 -1.1)
			(end -2.21 -1.1)
			(stroke
				(width 0.05)
				(type solid)
			)
			(layer "F.CrtYd")
		)
		(fp_line
			(start 2.2 -1.1)
			(end 2.2 1.1)
			(stroke
				(width 0.05)
				(type solid)
			)
			(layer "F.CrtYd")
		)
		(fp_line
			(start 2.2 1.1)
			(end -2.21 1.1)
			(stroke
				(width 0.05)
				(type solid)
			)
			(layer "F.CrtYd")
		)
		(fp_line
			(start -0.8 -0.8)
			(end -0.8 0.8)
			(stroke
				(width 0.1)
				(type solid)
			)
			(layer "F.Fab")
		)
		(fp_rect
			(start -1.75 -0.802)
			(end 1.749 0.8)
			(stroke
				(width 0.1)
				(type solid)
			)
			(fill no)
			(layer "F.Fab")
		)
		(pad "1" smd roundrect
			(at -1.401 0)
			(size 1.2 1.2)
			(layers "F.Cu" "F.Mask" "F.Paste")
			(roundrect_rratio 0.25)
			(net 698 "/Power supply/VDD")
			(pinfunction "C")
			(pintype "passive")
		)
		(pad "2" smd roundrect
			(at 1.398 0)
			(size 1.2 1.2)
			(layers "F.Cu" "F.Mask" "F.Paste")
			(roundrect_rratio 0.25)
			(net 697 "/Power supply/VSS")
			(pinfunction "A")
			(pintype "passive")
		)
	)
	(footprint "antmicro-footprints:Conn_JST_SH_1x4_BM04B-SRSS-TB-LF-SN"
		(layer "F.Cu")
		(at 230.8 127.4 -90)
		(property "Reference" "J8"
			(at -1.9 1.95 90)
			(layer "F.SilkS")
			(effects
				(font
					(size 0.7 0.7)
					(thickness 0.15)
				)
				(justify right bottom)
			)
		)
		(property "Value" "JST_SH_1x4_BM04B-SRSS-TB-LF-SN"
			(at 0 3.1 90)
			(layer "F.Fab")
			(effects
				(font
					(size 0.7 0.7)
					(thickness 0.15)
				)
				(justify right bottom)
			)
		)
		(property "Description" "Pin Header, Top Entry, Wire-to-Board, 1 mm, 1 Rows, 4 Contacts, Surface Mount, SR"
			(at 0 0 270)
			(layer "F.Fab")
			(hide yes)
			(effects
				(font
					(size 1.27 1.27)
					(thickness 0.15)
				)
			)
		)
		(property "Author" "Antmicro"
			(at 103.4 358.2 0)
			(layer "F.Fab")
			(hide yes)
			(effects
				(font
					(size 1 1)
					(thickness 0.15)
				)
			)
		)
		(property "License" "Apache-2.0"
			(at 103.4 358.2 0)
			(layer "F.Fab")
			(hide yes)
			(effects
				(font
					(size 1 1)
					(thickness 0.15)
				)
			)
		)
		(property "MPN" "BM04B-SRSS-TB(LF)(SN) "
			(at 103.4 358.2 0)
			(layer "F.Fab")
			(hide yes)
			(effects
				(font
					(size 1 1)
					(thickness 0.15)
				)
			)
		)
		(property "Manufacturer" "JST Automotive Connectors"
			(at 103.4 358.2 0)
			(layer "F.Fab")
			(hide yes)
			(effects
				(font
					(size 1 1)
					(thickness 0.15)
				)
			)
		)
		(sheetname "User GPIO + LED + button + DIP switch")
		(sheetfile "user-gpio.kicad_sch")
		(attr smd)
		(fp_line
			(start -1.125 2.999)
			(end -1.125 2.201)
			(stroke
				(width 0.15)
				(type solid)
			)
			(layer "F.SilkS")
		)
		(fp_line
			(start -0.251 2.999)
			(end -1.125 2.999)
			(stroke
				(width 0.15)
				(type solid)
			)
			(layer "F.SilkS")
		)
		(fp_line
			(start 1.774 -1.7)
			(end 1.774 1.702)
			(stroke
				(width 0.15)
				(type solid)
			)
			(layer "F.SilkS")
		)
		(fp_line
			(start -1.125 -2.999)
			(end -1.125 -2.201)
			(stroke
				(width 0.15)
				(type solid)
			)
			(layer "F.SilkS")
		)
		(fp_line
			(start -0.251 -2.999)
			(end -1.125 -2.999)
			(stroke
				(width 0.15)
				(type solid)
			)
			(layer "F.SilkS")
		)
		(fp_circle
			(center -1.6 -2.1)
			(end -1.55 -2.1)
			(stroke
				(width 0.15)
				(type solid)
			)
			(fill yes)
			(layer "F.SilkS")
		)
		(fp_rect
			(start -2.05 -3.95)
			(end 2.05 3.95)
			(stroke
				(width 0.05)
				(type solid)
			)
			(fill no)
			(layer "F.CrtYd")
		)
		(fp_rect
			(start -1.8 -3)
			(end 1.8 3)
			(stroke
				(width 0.15)
				(type solid)
			)
			(fill no)
			(layer "F.Fab")
		)
		(pad "1" smd roundrect
			(at -1.45 -1.5 180)
			(size 0.6 1.55)
			(layers "F.Cu" "F.Mask" "F.Paste")
			(roundrect_rratio 0.25)
			(net 1 "GND")
			(pinfunction "Pin_1")
			(pintype "passive")
		)
		(pad "2" smd roundrect
			(at -1.45 -0.5 180)
			(size 0.6 1.55)
			(layers "F.Cu" "F.Mask" "F.Paste")
			(roundrect_rratio 0.25)
			(net 703 "+5V")
			(pinfunction "Pin_2")
			(pintype "passive")
		)
		(pad "3" smd roundrect
			(at -1.45 0.5 180)
			(size 0.6 1.55)
			(layers "F.Cu" "F.Mask" "F.Paste")
			(roundrect_rratio 0.25)
			(net 31 "unconnected-(J8-Pin_3-Pad3)")
			(pinfunction "Pin_3")
			(pintype "passive+no_connect")
		)
		(pad "4" smd roundrect
			(at -1.45 1.5 180)
			(size 0.6 1.55)
			(layers "F.Cu" "F.Mask" "F.Paste")
			(roundrect_rratio 0.25)
			(net 801 "/User GPIO + LED + button + DIP switch/FAN_PWM_PIN")
			(pinfunction "Pin_4")
			(pintype "passive")
		)
		(pad "MP" smd roundrect
			(at 1.075 -2.8 180)
			(size 1.2 1.8)
			(layers "F.Cu" "F.Mask" "F.Paste")
			(roundrect_rratio 0.25)
			(net 1 "GND")
			(pinfunction "MP")
			(pintype "passive")
		)
		(pad "MP" smd roundrect
			(at 1.075 2.8 180)
			(size 1.2 1.8)
			(layers "F.Cu" "F.Mask" "F.Paste")
			(roundrect_rratio 0.25)
			(net 1 "GND")
			(pinfunction "MP")
			(pintype "passive")
		)
	)
	(footprint "antmicro-footprints:LED_0603_1608Metric_R"
		(layer "F.Cu")
		(at 261.5 79)
		(descr "LED SMD 0603 Red")
		(tags "LED SMD 0603 Red")
		(property "Reference" "D24"
			(at -1.15 1.5 0)
			(layer "F.SilkS")
			(effects
				(font
					(size 0.7 0.7)
					(thickness 0.15)
				)
				(justify left bottom)
			)
		)
		(property "Value" "LED_R_0603_KP-1608EC"
			(at 0 1.6 0)
			(layer "F.Fab")
			(effects
				(font
					(size 0.7 0.7)
					(thickness 0.15)
				)
				(justify left bottom)
			)
		)
		(property "Description" "LED, Red, SMD, 0603, 30 mA, 2 V, 617 nm"
			(at 0 0 0)
			(layer "F.Fab")
			(hide yes)
			(effects
				(font
					(size 1.27 1.27)
					(thickness 0.15)
				)
			)
		)
		(property "Author" "Antmicro"
			(at 0 0 0)
			(layer "F.Fab")
			(hide yes)
			(effects
				(font
					(size 1 1)
					(thickness 0.15)
				)
			)
		)
		(property "Color" "Red"
			(at 0 0 0)
			(layer "F.Fab")
			(hide yes)
			(effects
				(font
					(size 1 1)
					(thickness 0.15)
				)
			)
		)
		(property "License" "Apache-2.0"
			(at 0 0 0)
			(layer "F.Fab")
			(hide yes)
			(effects
				(font
					(size 1 1)
					(thickness 0.15)
				)
			)
		)
		(property "MPN" "KP-1608EC"
			(at 0 0 0)
			(layer "F.Fab")
			(hide yes)
			(effects
				(font
					(size 1 1)
					(thickness 0.15)
				)
			)
		)
		(property "Manufacturer" "Kingbright"
			(at 0 0 0)
			(layer "F.Fab")
			(hide yes)
			(effects
				(font
					(size 1 1)
					(thickness 0.15)
				)
			)
		)
		(property "Public" "False"
			(at 0 0 0)
			(layer "F.Fab")
			(hide yes)
			(effects
				(font
					(size 1 1)
					(thickness 0.15)
				)
			)
		)
		(sheetname "User GPIO + LED + button + DIP switch")
		(sheetfile "user-gpio.kicad_sch")
		(attr smd)
		(fp_line
			(start -1.18 -0.319)
			(end -1.18 0.321)
			(stroke
				(width 0.15)
				(type solid)
			)
			(layer "F.SilkS")
		)
		(fp_line
			(start -0.094672 0.001008)
			(end -0.24 0.001008)
			(stroke
				(width 0.1)
				(type solid)
			)
			(layer "F.SilkS")
		)
		(fp_line
			(start -0.094672 0.001008)
			(end 0.105328 -0.198992)
			(stroke
				(width 0.1)
				(type solid)
			)
			(layer "F.SilkS")
		)
		(fp_line
			(start -0.094672 0.201008)
			(end -0.094672 -0.198992)
			(stroke
				(width 0.1)
				(type solid)
			)
			(layer "F.SilkS")
		)
		(fp_line
			(start 0.105328 0.001008)
			(end 0.24 0.001)
			(stroke
				(width 0.1)
				(type solid)
			)
			(layer "F.SilkS")
		)
		(fp_line
			(start 0.105328 0.201008)
			(end -0.094672 0.001008)
			(stroke
				(width 0.1)
				(type solid)
			)
			(layer "F.SilkS")
		)
		(fp_line
			(start 0.105328 0.201008)
			(end 0.105328 -0.198992)
			(stroke
				(width 0.1)
				(type solid)
			)
			(layer "F.SilkS")
		)
		(fp_line
			(start 0.22 -0.35)
			(end -0.22 -0.35)
			(stroke
				(width 0.15)
				(type solid)
			)
			(layer "F.SilkS")
		)
		(fp_line
			(start 0.22 0.35)
			(end -0.22 0.35)
			(stroke
				(width 0.15)
				(type solid)
			)
			(layer "F.SilkS")
		)
		(fp_rect
			(start 1.25 0.65)
			(end -1.25 -0.65)
			(stroke
				(width 0.05)
				(type solid)
			)
			(fill no)
			(layer "F.CrtYd")
		)
		(fp_line
			(start -0.199 -0.202)
			(end -0.199 0.1)
			(stroke
				(width 0.15)
				(type solid)
			)
			(layer "F.Fab")
		)
		(fp_line
			(start -0.199 0)
			(end -0.597 0)
			(stroke
				(width 0.15)
				(type solid)
			)
			(layer "F.Fab")
		)
		(fp_line
			(start -0.199 0.2)
			(end -0.199 0.1)
			(stroke
				(width 0.15)
				(type solid)
			)
			(layer "F.Fab")
		)
		(fp_line
			(start -0.101 0)
			(end 0.201 0.2)
			(stroke
				(width 0.15)
				(type solid)
			)
			(layer "F.Fab")
		)
		(fp_line
			(start 0.201 -0.202)
			(end -0.101 0)
			(stroke
				(width 0.15)
				(type solid)
			)
			(layer "F.Fab")
		)
		(fp_line
			(start 0.201 0)
			(end 0.201 -0.202)
			(stroke
				(width 0.15)
				(type solid)
			)
			(layer "F.Fab")
		)
		(fp_line
			(start 0.201 0.2)
			(end 0.201 0)
			(stroke
				(width 0.15)
				(type solid)
			)
			(layer "F.Fab")
		)
		(fp_line
			(start 0.599 0)
			(end 0.201 0)
			(stroke
				(width 0.15)
				(type solid)
			)
			(layer "F.Fab")
		)
		(fp_rect
			(start 0.848 0.4)
			(end -0.85 -0.402)
			(stroke
				(width 0.15)
				(type solid)
			)
			(fill no)
			(layer "F.Fab")
		)
		(pad "1" smd roundrect
			(at -0.7 0 180)
			(size 0.8 1)
			(layers "F.Cu" "F.Mask" "F.Paste")
			(roundrect_rratio 0.2)
			(net 770 "Net-(D24-C)")
			(pinfunction "C")
			(pintype "passive")
		)
		(pad "2" smd roundrect
			(at 0.7 0 180)
			(size 0.8 1)
			(layers "F.Cu" "F.Mask" "F.Paste")
			(roundrect_rratio 0.2)
			(net 773 "Net-(D24-A)")
			(pinfunction "A")
			(pintype "passive")
		)
	)
	(footprint "antmicro-footprints:R_0603_1608Metric"
		(layer "F.Cu")
		(at 197.8 153.624 90)
		(descr "Resistor SMD 0603")
		(tags "resistor SMD 0603")
		(property "Reference" "R37"
			(at 1.174 -1.1 180)
			(layer "F.SilkS")
			(effects
				(font
					(size 0.7 0.7)
					(thickness 0.15)
				)
				(justify left bottom)
			)
		)
		(property "Value" "R_0R_22.4A_0603"
			(at 0 1.6 90)
			(layer "F.Fab")
			(effects
				(font
					(size 0.7 0.7)
					(thickness 0.15)
				)
				(justify left bottom)
			)
		)
		(property "Description" "SMD Chip Resistor"
			(at 0 0 90)
			(layer "F.Fab")
			(hide yes)
			(effects
				(font
					(size 1.27 1.27)
					(thickness 0.15)
				)
			)
		)
		(property "Author" "Antmicro"
			(at 351.424 -44.176 0)
			(layer "F.Fab")
			(hide yes)
			(effects
				(font
					(size 1 1)
					(thickness 0.15)
				)
			)
		)
		(property "License" "Apache-2.0"
			(at 351.424 -44.176 0)
			(layer "F.Fab")
			(hide yes)
			(effects
				(font
					(size 1 1)
					(thickness 0.15)
				)
			)
		)
		(property "MPN" "PMR03EZPJ000"
			(at 351.424 -44.176 0)
			(layer "F.Fab")
			(hide yes)
			(effects
				(font
					(size 1 1)
					(thickness 0.15)
				)
			)
		)
		(property "Manufacturer" "ROHM Semiconductor"
			(at 351.424 -44.176 0)
			(layer "F.Fab")
			(hide yes)
			(effects
				(font
					(size 1 1)
					(thickness 0.15)
				)
			)
		)
		(property "Max. Curr." "22.4A"
			(at 351.424 -44.176 0)
			(layer "F.Fab")
			(hide yes)
			(effects
				(font
					(size 1 1)
					(thickness 0.15)
				)
			)
		)
		(property "Tolerance" "template_tolerance"
			(at 351.424 -44.176 0)
			(layer "F.Fab")
			(hide yes)
			(effects
				(font
					(size 1 1)
					(thickness 0.15)
				)
			)
		)
		(property "Val" "0R"
			(at 351.424 -44.176 0)
			(layer "F.Fab")
			(hide yes)
			(effects
				(font
					(size 1 1)
					(thickness 0.15)
				)
			)
		)
		(sheetname "DC-DC Converters")
		(sheetfile "dc-dc.kicad_sch")
		(attr smd)
		(fp_line
			(start -0.15 -0.4)
			(end 0.15 -0.4)
			(stroke
				(width 0.15)
				(type solid)
			)
			(layer "F.SilkS")
		)
		(fp_line
			(start -0.15 0.4)
			(end 0.15 0.4)
			(stroke
				(width 0.15)
				(type solid)
			)
			(layer "F.SilkS")
		)
		(fp_rect
			(start -1.25 -0.65)
			(end 1.25 0.65)
			(stroke
				(width 0.05)
				(type solid)
			)
			(fill no)
			(layer "F.CrtYd")
		)
		(fp_rect
			(start -0.8 -0.4)
			(end 0.8 0.4)
			(stroke
				(width 0.15)
				(type solid)
			)
			(fill no)
			(layer "F.Fab")
		)
		(pad "1" smd roundrect
			(at -0.7 0 90)
			(size 0.8 1)
			(layers "F.Cu" "F.Mask" "F.Paste")
			(roundrect_rratio 0.2)
			(net 751 "/DC-DC Converters/1V0_REG")
			(pintype "passive")
		)
		(pad "2" smd roundrect
			(at 0.7 0 90)
			(size 0.8 1)
			(layers "F.Cu" "F.Mask" "F.Paste")
			(roundrect_rratio 0.2)
			(net 650 "+1V0")
			(pintype "passive")
		)
	)
	(footprint "antmicro-footprints:R_0402_1005Metric"
		(layer "F.Cu")
		(at 238 134.7 -90)
		(descr "Resistor SMD 0402")
		(tags "resistor SMD 0402")
		(property "Reference" "R187"
			(at -1.625 -3.925 90)
			(layer "F.SilkS")
			(effects
				(font
					(size 0.7 0.7)
					(thickness 0.15)
				)
				(justify left bottom)
			)
		)
		(property "Value" "R_0R_0402"
			(at 0 1.4 270)
			(layer "F.Fab")
			(effects
				(font
					(size 0.7 0.7)
					(thickness 0.15)
				)
				(justify left bottom)
			)
		)
		(property "Description" "SMD Chip Resistor, Jumper, 0 ohm, 100 mW, 0402 [1005 Metric], Thick Film, General Purpose"
			(at 0 0 270)
			(layer "F.Fab")
			(hide yes)
			(effects
				(font
					(size 1.27 1.27)
					(thickness 0.15)
				)
			)
		)
		(property "Author" "Antmicro"
			(at 103.3 372.7 0)
			(layer "F.Fab")
			(hide yes)
			(effects
				(font
					(size 1 1)
					(thickness 0.15)
				)
			)
		)
		(property "Current" "1A"
			(at 103.3 372.7 0)
			(layer "F.Fab")
			(hide yes)
			(effects
				(font
					(size 1 1)
					(thickness 0.15)
				)
			)
		)
		(property "DNP" "DNP"
			(at 103.3 372.7 0)
			(layer "F.Fab")
			(hide yes)
			(effects
				(font
					(size 1 1)
					(thickness 0.15)
				)
			)
		)
		(property "License" "Apache-2.0"
			(at 103.3 372.7 0)
			(layer "F.Fab")
			(hide yes)
			(effects
				(font
					(size 1 1)
					(thickness 0.15)
				)
			)
		)
		(property "MPN" "ERJ2GE0R00X"
			(at 103.3 372.7 0)
			(layer "F.Fab")
			(hide yes)
			(effects
				(font
					(size 1 1)
					(thickness 0.15)
				)
			)
		)
		(property "Manufacturer" "Panasonic"
			(at 103.3 372.7 0)
			(layer "F.Fab")
			(hide yes)
			(effects
				(font
					(size 1 1)
					(thickness 0.15)
				)
			)
		)
		(property "Tolerance" ""
			(at 103.3 372.7 0)
			(layer "F.Fab")
			(hide yes)
			(effects
				(font
					(size 1 1)
					(thickness 0.15)
				)
			)
		)
		(property "Val" "0R"
			(at 103.3 372.7 0)
			(layer "F.Fab")
			(hide yes)
			(effects
				(font
					(size 1 1)
					(thickness 0.15)
				)
			)
		)
		(property "dnp" ""
			(at 103.3 372.7 0)
			(layer "F.Fab")
			(hide yes)
			(effects
				(font
					(size 1 1)
					(thickness 0.15)
				)
			)
		)
		(property "exclude_from_bom" ""
			(at 103.3 372.7 0)
			(layer "F.Fab")
			(hide yes)
			(effects
				(font
					(size 1 1)
					(thickness 0.15)
				)
			)
		)
		(sheetname "USB PHY")
		(sheetfile "usb-phy.kicad_sch")
		(attr smd exclude_from_bom)
		(fp_rect
			(start -0.925 -0.47)
			(end 0.925 0.47)
			(stroke
				(width 0.05)
				(type default)
			)
			(fill no)
			(layer "F.CrtYd")
		)
		(fp_rect
			(start -0.5 -0.25)
			(end 0.5 0.25)
			(stroke
				(width 0.15)
				(type solid)
			)
			(fill no)
			(layer "F.Fab")
		)
		(pad "1" smd roundrect
			(at -0.48 0 270)
			(size 0.59 0.64)
			(layers "F.Cu" "F.Mask" "F.Paste")
			(roundrect_rratio 0.25)
			(net 940 "/USB PHY/I2C_EN")
			(pintype "passive")
		)
		(pad "2" smd roundrect
			(at 0.48 0 270)
			(size 0.59 0.64)
			(layers "F.Cu" "F.Mask" "F.Paste")
			(roundrect_rratio 0.25)
			(net 379 "Net-(U24-OE)")
			(pintype "passive")
		)
	)
	(footprint "antmicro-footprints:C_0402_1005Metric"
		(layer "F.Cu")
		(at 191.301 107.749 90)
		(descr "Capacitor SMD 0402")
		(tags "capacitor SMD 0402")
		(property "Reference" "C226"
			(at -1.351 -0.501 90)
			(layer "F.SilkS")
			(effects
				(font
					(size 0.7 0.7)
					(thickness 0.15)
				)
				(justify left bottom)
			)
		)
		(property "Value" "C_1u_0402"
			(at 0 1.4 90)
			(layer "F.Fab")
			(effects
				(font
					(size 0.7 0.7)
					(thickness 0.15)
				)
				(justify left bottom)
			)
		)
		(property "Description" "SMD Multilayer Ceramic Capacitor, 1 µF, 10 V, 0402 [1005 Metric], ± 10%, X6S, C"
			(at 0 0 90)
			(layer "F.Fab")
			(hide yes)
			(effects
				(font
					(size 1.27 1.27)
					(thickness 0.15)
				)
			)
		)
		(property "Author" "Antmicro"
			(at 299.05 -83.552 0)
			(layer "F.Fab")
			(hide yes)
			(effects
				(font
					(size 1 1)
					(thickness 0.15)
				)
			)
		)
		(property "Dielectric" ""
			(at 299.05 -83.552 0)
			(layer "F.Fab")
			(hide yes)
			(effects
				(font
					(size 1 1)
					(thickness 0.15)
				)
			)
		)
		(property "License" "Apache-2.0"
			(at 299.05 -83.552 0)
			(layer "F.Fab")
			(hide yes)
			(effects
				(font
					(size 1 1)
					(thickness 0.15)
				)
			)
		)
		(property "MPN" "C1005X6S1A105K050BC"
			(at 299.05 -83.552 0)
			(layer "F.Fab")
			(hide yes)
			(effects
				(font
					(size 1 1)
					(thickness 0.15)
				)
			)
		)
		(property "Manufacturer" "TDK"
			(at 299.05 -83.552 0)
			(layer "F.Fab")
			(hide yes)
			(effects
				(font
					(size 1 1)
					(thickness 0.15)
				)
			)
		)
		(property "Val" "1u"
			(at 299.05 -83.552 0)
			(layer "F.Fab")
			(hide yes)
			(effects
				(font
					(size 1 1)
					(thickness 0.15)
				)
			)
		)
		(property "Voltage" ""
			(at 299.05 -83.552 0)
			(layer "F.Fab")
			(hide yes)
			(effects
				(font
					(size 1 1)
					(thickness 0.15)
				)
			)
		)
		(sheetname "USB PHY")
		(sheetfile "usb-phy.kicad_sch")
		(attr smd)
		(fp_rect
			(start -0.925 -0.47)
			(end 0.925 0.47)
			(stroke
				(width 0.05)
				(type default)
			)
			(fill no)
			(layer "F.CrtYd")
		)
		(fp_line
			(start 0.504 -0.25)
			(end 0.504 0.248)
			(stroke
				(width 0.15)
				(type solid)
			)
			(layer "F.Fab")
		)
		(fp_line
			(start -0.494 -0.25)
			(end 0.504 -0.25)
			(stroke
				(width 0.15)
				(type solid)
			)
			(layer "F.Fab")
		)
		(fp_line
			(start 0.504 0.248)
			(end -0.494 0.248)
			(stroke
				(width 0.15)
				(type solid)
			)
			(layer "F.Fab")
		)
		(fp_line
			(start -0.494 0.248)
			(end -0.494 -0.25)
			(stroke
				(width 0.15)
				(type solid)
			)
			(layer "F.Fab")
		)
		(pad "1" smd roundrect
			(at -0.48 0 90)
			(size 0.59 0.64)
			(layers "F.Cu" "F.Mask" "F.Paste")
			(roundrect_rratio 0.25)
			(net 1 "GND")
			(pintype "passive")
		)
		(pad "2" smd roundrect
			(at 0.48 0 90)
			(size 0.59 0.64)
			(layers "F.Cu" "F.Mask" "F.Paste")
			(roundrect_rratio 0.25)
			(net 24 "+3V3")
			(pintype "passive")
		)
	)
	(footprint "antmicro-footprints:C_0402_1005Metric"
		(layer "F.Cu")
		(at 230.4 147.4)
		(descr "Capacitor SMD 0402")
		(tags "capacitor SMD 0402")
		(property "Reference" "C252"
			(at -0.85 -0.5 0)
			(layer "F.SilkS")
			(effects
				(font
					(size 0.7 0.7)
					(thickness 0.15)
				)
				(justify left bottom)
			)
		)
		(property "Value" "C_22p_0402"
			(at 0 1.4 0)
			(layer "F.Fab")
			(effects
				(font
					(size 0.7 0.7)
					(thickness 0.15)
				)
				(justify left bottom)
			)
		)
		(property "Description" "SMD Multilayer Ceramic Capacitor, 22 pF, 50 V, 0402 [1005 Metric], ± 5%, C0G / NP0, CC Series"
			(at 0 0 0)
			(layer "F.Fab")
			(hide yes)
			(effects
				(font
					(size 1.27 1.27)
					(thickness 0.15)
				)
			)
		)
		(property "Author" "Antmicro"
			(at 0 0 0)
			(layer "F.Fab")
			(hide yes)
			(effects
				(font
					(size 1 1)
					(thickness 0.15)
				)
			)
		)
		(property "Dielectric" ""
			(at 0 0 0)
			(layer "F.Fab")
			(hide yes)
			(effects
				(font
					(size 1 1)
					(thickness 0.15)
				)
			)
		)
		(property "License" "Apache-2.0"
			(at 0 0 0)
			(layer "F.Fab")
			(hide yes)
			(effects
				(font
					(size 1 1)
					(thickness 0.15)
				)
			)
		)
		(property "MPN" "CC0402JRNPO9BN220"
			(at 0 0 0)
			(layer "F.Fab")
			(hide yes)
			(effects
				(font
					(size 1 1)
					(thickness 0.15)
				)
			)
		)
		(property "Manufacturer" "YAGEO"
			(at 0 0 0)
			(layer "F.Fab")
			(hide yes)
			(effects
				(font
					(size 1 1)
					(thickness 0.15)
				)
			)
		)
		(property "Val" "22p"
			(at 0 0 0)
			(layer "F.Fab")
			(hide yes)
			(effects
				(font
					(size 1 1)
					(thickness 0.15)
				)
			)
		)
		(property "Voltage" ""
			(at 0 0 0)
			(layer "F.Fab")
			(hide yes)
			(effects
				(font
					(size 1 1)
					(thickness 0.15)
				)
			)
		)
		(sheetname "HDMI + Ethernet")
		(sheetfile "hdmi-ethernet.kicad_sch")
		(attr smd)
		(fp_rect
			(start -0.925 -0.47)
			(end 0.925 0.47)
			(stroke
				(width 0.05)
				(type default)
			)
			(fill no)
			(layer "F.CrtYd")
		)
		(fp_line
			(start -0.494 -0.25)
			(end 0.504 -0.25)
			(stroke
				(width 0.15)
				(type solid)
			)
			(layer "F.Fab")
		)
		(fp_line
			(start -0.494 0.248)
			(end -0.494 -0.25)
			(stroke
				(width 0.15)
				(type solid)
			)
			(layer "F.Fab")
		)
		(fp_line
			(start 0.504 -0.25)
			(end 0.504 0.248)
			(stroke
				(width 0.15)
				(type solid)
			)
			(layer "F.Fab")
		)
		(fp_line
			(start 0.504 0.248)
			(end -0.494 0.248)
			(stroke
				(width 0.15)
				(type solid)
			)
			(layer "F.Fab")
		)
		(pad "1" smd roundrect
			(at -0.48 0)
			(size 0.59 0.64)
			(layers "F.Cu" "F.Mask" "F.Paste")
			(roundrect_rratio 0.25)
			(net 1 "GND")
			(pintype "passive")
		)
		(pad "2" smd roundrect
			(at 0.48 0)
			(size 0.59 0.64)
			(layers "F.Cu" "F.Mask" "F.Paste")
			(roundrect_rratio 0.25)
			(net 716 "/HDMI + Ethernet/ETH_XI")
			(pintype "passive")
		)
	)
	(footprint "antmicro-footprints:C_0402_1005Metric"
		(layer "F.Cu")
		(at 219.2 138.425 180)
		(descr "Capacitor SMD 0402")
		(tags "capacitor SMD 0402")
		(property "Reference" "C372"
			(at 3.65 -0.375 180)
			(layer "F.SilkS")
			(effects
				(font
					(size 0.7 0.7)
					(thickness 0.15)
				)
				(justify left bottom)
			)
		)
		(property "Value" "C_100n_0402"
			(at 0 1.4 180)
			(layer "F.Fab")
			(effects
				(font
					(size 0.7 0.7)
					(thickness 0.15)
				)
				(justify left bottom)
			)
		)
		(property "Description" "SMD Multilayer Ceramic Capacitor, 0.1 µF, 50 V, 0402 [1005 Metric], ± 10%, X5R, GRM Series"
			(at 0 0 180)
			(layer "F.Fab")
			(hide yes)
			(effects
				(font
					(size 1.27 1.27)
					(thickness 0.15)
				)
			)
		)
		(property "Author" "Antmicro"
			(at 438.4 276.85 0)
			(layer "F.Fab")
			(hide yes)
			(effects
				(font
					(size 1 1)
					(thickness 0.15)
				)
			)
		)
		(property "Dielectric" "X5R"
			(at 438.4 276.85 0)
			(layer "F.Fab")
			(hide yes)
			(effects
				(font
					(size 1 1)
					(thickness 0.15)
				)
			)
		)
		(property "License" "Apache-2.0"
			(at 438.4 276.85 0)
			(layer "F.Fab")
			(hide yes)
			(effects
				(font
					(size 1 1)
					(thickness 0.15)
				)
			)
		)
		(property "MPN" "GRM155R61H104KE14D"
			(at 438.4 276.85 0)
			(layer "F.Fab")
			(hide yes)
			(effects
				(font
					(size 1 1)
					(thickness 0.15)
				)
			)
		)
		(property "Manufacturer" "Murata"
			(at 438.4 276.85 0)
			(layer "F.Fab")
			(hide yes)
			(effects
				(font
					(size 1 1)
					(thickness 0.15)
				)
			)
		)
		(property "Val" "100n"
			(at 438.4 276.85 0)
			(layer "F.Fab")
			(hide yes)
			(effects
				(font
					(size 1 1)
					(thickness 0.15)
				)
			)
		)
		(property "Voltage" "50V"
			(at 438.4 276.85 0)
			(layer "F.Fab")
			(hide yes)
			(effects
				(font
					(size 1 1)
					(thickness 0.15)
				)
			)
		)
		(sheetname "Clocks")
		(sheetfile "clocks.kicad_sch")
		(attr smd)
		(fp_rect
			(start -0.925 -0.47)
			(end 0.925 0.47)
			(stroke
				(width 0.05)
				(type default)
			)
			(fill no)
			(layer "F.CrtYd")
		)
		(fp_line
			(start 0.504 0.248)
			(end -0.494 0.248)
			(stroke
				(width 0.15)
				(type solid)
			)
			(layer "F.Fab")
		)
		(fp_line
			(start 0.504 -0.25)
			(end 0.504 0.248)
			(stroke
				(width 0.15)
				(type solid)
			)
			(layer "F.Fab")
		)
		(fp_line
			(start -0.494 0.248)
			(end -0.494 -0.25)
			(stroke
				(width 0.15)
				(type solid)
			)
			(layer "F.Fab")
		)
		(fp_line
			(start -0.494 -0.25)
			(end 0.504 -0.25)
			(stroke
				(width 0.15)
				(type solid)
			)
			(layer "F.Fab")
		)
		(pad "1" smd roundrect
			(at -0.48 0 180)
			(size 0.59 0.64)
			(layers "F.Cu" "F.Mask" "F.Paste")
			(roundrect_rratio 0.25)
			(net 24 "+3V3")
			(pintype "passive")
		)
		(pad "2" smd roundrect
			(at 0.48 0 180)
			(size 0.59 0.64)
			(layers "F.Cu" "F.Mask" "F.Paste")
			(roundrect_rratio 0.25)
			(net 1 "GND")
			(pintype "passive")
		)
	)
	(footprint "antmicro-footprints:SW_DIP_SPSTx03_Slide_Copal_CVS-03xB_W5.9mm_P1mm"
		(layer "F.Cu")
		(at 203.101 74.033 90)
		(descr "SMD 3x-dip-switch SPST Copal_CVS-03xB, Slide, row spacing 5.9 mm (232 mils), body size  (see http://www.nidec-copal-electronics.com/e/catalog/switch/cvs.pdf)")
		(tags "SMD DIP Switch SPST Slide")
		(property "Reference" "SW1"
			(at -1.267 -3.001 90)
			(layer "F.SilkS")
			(effects
				(font
					(size 0.7 0.7)
					(thickness 0.15)
				)
				(justify left bottom)
			)
		)
		(property "Value" "CVS-03B"
			(at 0.248 4.799 90)
			(layer "F.Fab")
			(effects
				(font
					(size 0.7 0.7)
					(thickness 0.15)
				)
				(justify left bottom)
			)
		)
		(property "Description" "Slide switch"
			(at 0 0 90)
			(layer "F.Fab")
			(hide yes)
			(effects
				(font
					(size 1.27 1.27)
					(thickness 0.15)
				)
			)
		)
		(property "Author" "Antmicro"
			(at 277.134 -129.068 0)
			(layer "F.Fab")
			(hide yes)
			(effects
				(font
					(size 1 1)
					(thickness 0.15)
				)
			)
		)
		(property "License" "Apache-2.0"
			(at 277.134 -129.068 0)
			(layer "F.Fab")
			(hide yes)
			(effects
				(font
					(size 1 1)
					(thickness 0.15)
				)
			)
		)
		(property "MPN" "CVS-03B"
			(at 277.134 -129.068 0)
			(layer "F.Fab")
			(hide yes)
			(effects
				(font
					(size 1 1)
					(thickness 0.15)
				)
			)
		)
		(property "Manufacturer" "Nidec Components"
			(at 277.134 -129.068 0)
			(layer "F.Fab")
			(hide yes)
			(effects
				(font
					(size 1 1)
					(thickness 0.15)
				)
			)
		)
		(sheetname "FPGA Config")
		(sheetfile "fpga-config.kicad_sch")
		(attr smd)
		(fp_line
			(start -1.51 -2.411)
			(end 1.61 -2.411)
			(stroke
				(width 0.15)
				(type solid)
			)
			(layer "F.SilkS")
		)
		(fp_line
			(start -1.51 2.41)
			(end 1.61 2.41)
			(stroke
				(width 0.15)
				(type solid)
			)
			(layer "F.SilkS")
		)
		(fp_circle
			(center -3.33 -1.641)
			(end -3.281 -1.641)
			(stroke
				(width 0.15)
				(type solid)
			)
			(fill yes)
			(layer "F.SilkS")
		)
		(fp_rect
			(start -3.56 -2.5)
			(end 3.66 2.49)
			(stroke
				(width 0.05)
				(type solid)
			)
			(fill no)
			(layer "F.CrtYd")
		)
		(fp_line
			(start 2.398 -2)
			(end 2.398 1.999)
			(stroke
				(width 0.15)
				(type solid)
			)
			(layer "F.Fab")
		)
		(fp_line
			(start -1.301 -2)
			(end 2.398 -2)
			(stroke
				(width 0.15)
				(type solid)
			)
			(layer "F.Fab")
		)
		(fp_line
			(start 1.05 -1.25)
			(end -0.951 -1.25)
			(stroke
				(width 0.15)
				(type solid)
			)
			(layer "F.Fab")
		)
		(fp_line
			(start -0.285 -1.25)
			(end -0.285 -0.75)
			(stroke
				(width 0.15)
				(type solid)
			)
			(layer "F.Fab")
		)
		(fp_line
			(start -0.951 -1.25)
			(end -0.951 -0.75)
			(stroke
				(width 0.15)
				(type solid)
			)
			(layer "F.Fab")
		)
		(fp_line
			(start -0.951 -1.151)
			(end -0.285 -1.151)
			(stroke
				(width 0.15)
				(type solid)
			)
			(layer "F.Fab")
		)
		(fp_line
			(start -0.951 -1.051)
			(end -0.285 -1.051)
			(stroke
				(width 0.15)
				(type solid)
			)
			(layer "F.Fab")
		)
		(fp_line
			(start -2.301 -1)
			(end -1.301 -2)
			(stroke
				(width 0.15)
				(type solid)
			)
			(layer "F.Fab")
		)
		(fp_line
			(start -0.951 -0.952)
			(end -0.285 -0.952)
			(stroke
				(width 0.15)
				(type solid)
			)
			(layer "F.Fab")
		)
		(fp_line
			(start -0.951 -0.85)
			(end -0.285 -0.85)
			(stroke
				(width 0.15)
				(type solid)
			)
			(layer "F.Fab")
		)
		(fp_line
			(start 1.05 -0.75)
			(end 1.05 -1.25)
			(stroke
				(width 0.15)
				(type solid)
			)
			(layer "F.Fab")
		)
		(fp_line
			(start -0.951 -0.75)
			(end 1.05 -0.75)
			(stroke
				(width 0.15)
				(type solid)
			)
			(layer "F.Fab")
		)
		(fp_line
			(start 1.05 -0.25)
			(end -0.951 -0.25)
			(stroke
				(width 0.15)
				(type solid)
			)
			(layer "F.Fab")
		)
		(fp_line
			(start -0.285 -0.25)
			(end -0.285 0.247)
			(stroke
				(width 0.15)
				(type solid)
			)
			(layer "F.Fab")
		)
		(fp_line
			(start -0.951 -0.25)
			(end -0.951 0.247)
			(stroke
				(width 0.15)
				(type solid)
			)
			(layer "F.Fab")
		)
		(fp_line
			(start -0.951 -0.15)
			(end -0.285 -0.15)
			(stroke
				(width 0.15)
				(type solid)
			)
			(layer "F.Fab")
		)
		(fp_line
			(start -0.951 -0.053)
			(end -0.285 -0.053)
			(stroke
				(width 0.15)
				(type solid)
			)
			(layer "F.Fab")
		)
		(fp_line
			(start -0.951 0.05)
			(end -0.285 0.05)
			(stroke
				(width 0.15)
				(type solid)
			)
			(layer "F.Fab")
		)
		(fp_line
			(start -0.951 0.147)
			(end -0.285 0.147)
			(stroke
				(width 0.15)
				(type solid)
			)
			(layer "F.Fab")
		)
		(fp_line
			(start 1.05 0.247)
			(end 1.05 -0.25)
			(stroke
				(width 0.15)
				(type solid)
			)
			(layer "F.Fab")
		)
		(fp_line
			(start -0.951 0.247)
			(end 1.05 0.247)
			(stroke
				(width 0.15)
				(type solid)
			)
			(layer "F.Fab")
		)
		(fp_line
			(start 1.05 0.747)
			(end -0.951 0.747)
			(stroke
				(width 0.15)
				(type solid)
			)
			(layer "F.Fab")
		)
		(fp_line
			(start -0.285 0.747)
			(end -0.285 1.249)
			(stroke
				(width 0.15)
				(type solid)
			)
			(layer "F.Fab")
		)
		(fp_line
			(start -0.951 0.747)
			(end -0.951 1.249)
			(stroke
				(width 0.15)
				(type solid)
			)
			(layer "F.Fab")
		)
		(fp_line
			(start -0.951 0.847)
			(end -0.285 0.847)
			(stroke
				(width 0.15)
				(type solid)
			)
			(layer "F.Fab")
		)
		(fp_line
			(start -0.951 0.949)
			(end -0.285 0.949)
			(stroke
				(width 0.15)
				(type solid)
			)
			(layer "F.Fab")
		)
		(fp_line
			(start -0.951 1.05)
			(end -0.285 1.05)
			(stroke
				(width 0.15)
				(type solid)
			)
			(layer "F.Fab")
		)
		(fp_line
			(start -0.951 1.148)
			(end -0.285 1.148)
			(stroke
				(width 0.15)
				(type solid)
			)
			(layer "F.Fab")
		)
		(fp_line
			(start 1.05 1.249)
			(end 1.05 0.747)
			(stroke
				(width 0.15)
				(type solid)
			)
			(layer "F.Fab")
		)
		(fp_line
			(start -0.951 1.249)
			(end 1.05 1.249)
			(stroke
				(width 0.15)
				(type solid)
			)
			(layer "F.Fab")
		)
		(fp_line
			(start 2.398 1.999)
			(end -2.301 1.999)
			(stroke
				(width 0.15)
				(type solid)
			)
			(layer "F.Fab")
		)
		(fp_line
			(start -2.301 1.999)
			(end -2.301 -1)
			(stroke
				(width 0.15)
				(type solid)
			)
			(layer "F.Fab")
		)
		(pad "1" smd rect
			(at -2.899 -1 90)
			(size 1.2 0.5)
			(layers "F.Cu" "F.Mask" "F.Paste")
			(net 300 "/FPGA Config/MODE0")
			(pinfunction "1")
			(pintype "passive")
		)
		(pad "2" smd rect
			(at -2.899 0 90)
			(size 1.2 0.5)
			(layers "F.Cu" "F.Mask" "F.Paste")
			(net 299 "/FPGA Config/MODE1")
			(pinfunction "2")
			(pintype "passive")
		)
		(pad "3" smd rect
			(at -2.899 0.997 90)
			(size 1.2 0.5)
			(layers "F.Cu" "F.Mask" "F.Paste")
			(net 298 "/FPGA Config/MODE2")
			(pinfunction "3")
			(pintype "passive")
		)
		(pad "4" smd rect
			(at 2.999 0.997 90)
			(size 1.2 0.5)
			(layers "F.Cu" "F.Mask" "F.Paste")
			(net 1 "GND")
			(pinfunction "4")
			(pintype "passive")
		)
		(pad "5" smd rect
			(at 2.999 0 90)
			(size 1.2 0.5)
			(layers "F.Cu" "F.Mask" "F.Paste")
			(net 1 "GND")
			(pinfunction "5")
			(pintype "passive")
		)
		(pad "6" smd rect
			(at 2.999 -1 90)
			(size 1.2 0.5)
			(layers "F.Cu" "F.Mask" "F.Paste")
			(net 1 "GND")
			(pinfunction "6")
			(pintype "passive")
		)
		(pad "7" smd rect
			(at -2.101 -2 90)
			(size 0.7 0.7)
			(layers "F.Cu" "F.Mask" "F.Paste")
			(net 1 "GND")
			(pinfunction "7")
			(pintype "power_in")
		)
		(pad "7" smd rect
			(at -2.101 1.999 90)
			(size 0.7 0.7)
			(layers "F.Cu" "F.Mask" "F.Paste")
			(net 1 "GND")
			(pinfunction "7")
			(pintype "power_in")
		)
		(pad "7" smd rect
			(at 2.201 -2 90)
			(size 0.7 0.7)
			(layers "F.Cu" "F.Mask" "F.Paste")
			(net 1 "GND")
			(pinfunction "7")
			(pintype "power_in")
		)
		(pad "7" smd rect
			(at 2.201 1.999 90)
			(size 0.7 0.7)
			(layers "F.Cu" "F.Mask" "F.Paste")
			(net 1 "GND")
			(pinfunction "7")
			(pintype "power_in")
		)
	)
	(footprint "antmicro-footprints:R_0402_1005Metric"
		(layer "F.Cu")
		(at 210.9 165.4 90)
		(descr "Resistor SMD 0402")
		(tags "resistor SMD 0402")
		(property "Reference" "R69"
			(at -0.4 -5.25 90)
			(layer "F.SilkS")
			(effects
				(font
					(size 0.7 0.7)
					(thickness 0.15)
				)
				(justify left bottom)
			)
		)
		(property "Value" "R_10k_0402"
			(at 0 1.4 90)
			(layer "F.Fab")
			(effects
				(font
					(size 0.7 0.7)
					(thickness 0.15)
				)
				(justify left bottom)
			)
		)
		(property "Description" "SMD Chip Resistor, 10 kohm, ± 1%, 62.5 mW, 0402 [1005 Metric], Thick Film, General Purpose"
			(at 0 0 90)
			(layer "F.Fab")
			(hide yes)
			(effects
				(font
					(size 1.27 1.27)
					(thickness 0.15)
				)
			)
		)
		(property "Author" "Antmicro"
			(at 376.3 -45.5 0)
			(layer "F.Fab")
			(hide yes)
			(effects
				(font
					(size 1 1)
					(thickness 0.15)
				)
			)
		)
		(property "License" "Apache-2.0"
			(at 376.3 -45.5 0)
			(layer "F.Fab")
			(hide yes)
			(effects
				(font
					(size 1 1)
					(thickness 0.15)
				)
			)
		)
		(property "MPN" "CR0402-FX-1002GLF"
			(at 376.3 -45.5 0)
			(layer "F.Fab")
			(hide yes)
			(effects
				(font
					(size 1 1)
					(thickness 0.15)
				)
			)
		)
		(property "Manufacturer" "Bourns"
			(at 376.3 -45.5 0)
			(layer "F.Fab")
			(hide yes)
			(effects
				(font
					(size 1 1)
					(thickness 0.15)
				)
			)
		)
		(property "Tolerance" "1%"
			(at 376.3 -45.5 0)
			(layer "F.Fab")
			(hide yes)
			(effects
				(font
					(size 1 1)
					(thickness 0.15)
				)
			)
		)
		(property "Val" "10k"
			(at 376.3 -45.5 0)
			(layer "F.Fab")
			(hide yes)
			(effects
				(font
					(size 1 1)
					(thickness 0.15)
				)
			)
		)
		(sheetname "SPI Flash + SD Card")
		(sheetfile "spi-flash.kicad_sch")
		(attr smd)
		(fp_rect
			(start -0.925 -0.47)
			(end 0.925 0.47)
			(stroke
				(width 0.05)
				(type default)
			)
			(fill no)
			(layer "F.CrtYd")
		)
		(fp_rect
			(start -0.5 -0.25)
			(end 0.5 0.25)
			(stroke
				(width 0.15)
				(type solid)
			)
			(fill no)
			(layer "F.Fab")
		)
		(pad "1" smd roundrect
			(at -0.48 0 90)
			(size 0.59 0.64)
			(layers "F.Cu" "F.Mask" "F.Paste")
			(roundrect_rratio 0.25)
			(net 407 "/FPGA Bank 33 & 34/USR_FLASH_0.~{CS}")
			(pintype "passive")
		)
		(pad "2" smd roundrect
			(at 0.48 0 90)
			(size 0.59 0.64)
			(layers "F.Cu" "F.Mask" "F.Paste")
			(roundrect_rratio 0.25)
			(net 26 "+1V8")
			(pintype "passive")
		)
	)
	(footprint "antmicro-footprints:C_0603_1608Metric"
		(layer "F.Cu")
		(at 261.95 149.85 90)
		(descr "Capacitor SMD 0603")
		(tags "capacitor 0603")
		(property "Reference" "C222"
			(at -1.55 -0.75 90)
			(layer "F.SilkS")
			(effects
				(font
					(size 0.7 0.7)
					(thickness 0.15)
				)
				(justify left bottom)
			)
		)
		(property "Value" "C_10u_25V_0603"
			(at 0 1.6 90)
			(layer "F.Fab")
			(effects
				(font
					(size 0.7 0.7)
					(thickness 0.15)
				)
				(justify left bottom)
			)
		)
		(property "Description" "SMD Multilayer Ceramic Capacitor, 10 µF, 25 V, 0603 [1608 Metric], ± 20%, X5R, C"
			(at 0 0 90)
			(layer "F.Fab")
			(hide yes)
			(effects
				(font
					(size 1.27 1.27)
					(thickness 0.15)
				)
			)
		)
		(property "Author" "Antmicro"
			(at 411.8 -112.1 0)
			(layer "F.Fab")
			(hide yes)
			(effects
				(font
					(size 1 1)
					(thickness 0.15)
				)
			)
		)
		(property "Dielectric" ""
			(at 411.8 -112.1 0)
			(layer "F.Fab")
			(hide yes)
			(effects
				(font
					(size 1 1)
					(thickness 0.15)
				)
			)
		)
		(property "License" "Apache-2.0"
			(at 411.8 -112.1 0)
			(layer "F.Fab")
			(hide yes)
			(effects
				(font
					(size 1 1)
					(thickness 0.15)
				)
			)
		)
		(property "MPN" "C1608X5R1E106M080AC"
			(at 411.8 -112.1 0)
			(layer "F.Fab")
			(hide yes)
			(effects
				(font
					(size 1 1)
					(thickness 0.15)
				)
			)
		)
		(property "Manufacturer" "TDK"
			(at 411.8 -112.1 0)
			(layer "F.Fab")
			(hide yes)
			(effects
				(font
					(size 1 1)
					(thickness 0.15)
				)
			)
		)
		(property "Val" "10u"
			(at 411.8 -112.1 0)
			(layer "F.Fab")
			(hide yes)
			(effects
				(font
					(size 1 1)
					(thickness 0.15)
				)
			)
		)
		(property "Voltage" "25V"
			(at 411.8 -112.1 0)
			(layer "F.Fab")
			(hide yes)
			(effects
				(font
					(size 1 1)
					(thickness 0.15)
				)
			)
		)
		(sheetname "USB PHY")
		(sheetfile "usb-phy.kicad_sch")
		(attr smd)
		(fp_line
			(start -0.15 -0.4)
			(end 0.15 -0.4)
			(stroke
				(width 0.15)
				(type solid)
			)
			(layer "F.SilkS")
		)
		(fp_line
			(start -0.15 0.4)
			(end 0.15 0.4)
			(stroke
				(width 0.15)
				(type solid)
			)
			(layer "F.SilkS")
		)
		(fp_rect
			(start -1.25 -0.65)
			(end 1.25 0.65)
			(stroke
				(width 0.05)
				(type solid)
			)
			(fill no)
			(layer "F.CrtYd")
		)
		(fp_rect
			(start -0.8 -0.4)
			(end 0.8 0.4)
			(stroke
				(width 0.15)
				(type solid)
			)
			(fill no)
			(layer "F.Fab")
		)
		(pad "1" smd roundrect
			(at -0.7 0 90)
			(size 0.8 1)
			(layers "F.Cu" "F.Mask" "F.Paste")
			(roundrect_rratio 0.2)
			(net 1 "GND")
			(pintype "passive")
		)
		(pad "2" smd roundrect
			(at 0.7 0 90)
			(size 0.8 1)
			(layers "F.Cu" "F.Mask" "F.Paste")
			(roundrect_rratio 0.2)
			(net 704 "/Power supply/USB_DBG_PD.VBUS")
			(pintype "passive")
		)
	)
	(footprint "antmicro-footprints:R_0603_1608Metric"
		(layer "F.Cu")
		(at 161.6 153.3)
		(descr "Resistor SMD 0603")
		(tags "resistor SMD 0603")
		(property "Reference" "R330"
			(at -1.15 1.4 0)
			(layer "F.SilkS")
			(effects
				(font
					(size 0.7 0.7)
					(thickness 0.15)
				)
				(justify left bottom)
			)
		)
		(property "Value" "R_0R_22.4A_0603"
			(at 0 1.6 0)
			(layer "F.Fab")
			(effects
				(font
					(size 0.7 0.7)
					(thickness 0.15)
				)
				(justify left bottom)
			)
		)
		(property "Description" "SMD Chip Resistor"
			(at 0 0 0)
			(layer "F.Fab")
			(hide yes)
			(effects
				(font
					(size 1.27 1.27)
					(thickness 0.15)
				)
			)
		)
		(property "Author" "Antmicro"
			(at 0 0 0)
			(layer "F.Fab")
			(hide yes)
			(effects
				(font
					(size 1 1)
					(thickness 0.15)
				)
			)
		)
		(property "License" "Apache-2.0"
			(at 0 0 0)
			(layer "F.Fab")
			(hide yes)
			(effects
				(font
					(size 1 1)
					(thickness 0.15)
				)
			)
		)
		(property "MPN" "PMR03EZPJ000"
			(at 0 0 0)
			(layer "F.Fab")
			(hide yes)
			(effects
				(font
					(size 1 1)
					(thickness 0.15)
				)
			)
		)
		(property "Manufacturer" "ROHM Semiconductor"
			(at 0 0 0)
			(layer "F.Fab")
			(hide yes)
			(effects
				(font
					(size 1 1)
					(thickness 0.15)
				)
			)
		)
		(property "Max. Curr." "22.4A"
			(at 0 0 0)
			(layer "F.Fab")
			(hide yes)
			(effects
				(font
					(size 1 1)
					(thickness 0.15)
				)
			)
		)
		(property "Tolerance" "template_tolerance"
			(at 0 0 0)
			(layer "F.Fab")
			(hide yes)
			(effects
				(font
					(size 1 1)
					(thickness 0.15)
				)
			)
		)
		(property "Val" "0R"
			(at 0 0 0)
			(layer "F.Fab")
			(hide yes)
			(effects
				(font
					(size 1 1)
					(thickness 0.15)
				)
			)
		)
		(sheetname "DC-DC Converters")
		(sheetfile "dc-dc.kicad_sch")
		(attr smd)
		(fp_line
			(start -0.15 -0.4)
			(end 0.15 -0.4)
			(stroke
				(width 0.15)
				(type solid)
			)
			(layer "F.SilkS")
		)
		(fp_line
			(start -0.15 0.4)
			(end 0.15 0.4)
			(stroke
				(width 0.15)
				(type solid)
			)
			(layer "F.SilkS")
		)
		(fp_rect
			(start -1.25 -0.65)
			(end 1.25 0.65)
			(stroke
				(width 0.05)
				(type solid)
			)
			(fill no)
			(layer "F.CrtYd")
		)
		(fp_rect
			(start -0.8 -0.4)
			(end 0.8 0.4)
			(stroke
				(width 0.15)
				(type solid)
			)
			(fill no)
			(layer "F.Fab")
		)
		(pad "1" smd roundrect
			(at -0.7 0)
			(size 0.8 1)
			(layers "F.Cu" "F.Mask" "F.Paste")
			(roundrect_rratio 0.2)
			(net 750 "/DC-DC Converters/VDDR_VTT")
			(pintype "passive")
		)
		(pad "2" smd roundrect
			(at 0.7 0)
			(size 0.8 1)
			(layers "F.Cu" "F.Mask" "F.Paste")
			(roundrect_rratio 0.2)
			(net 7 "+0V675_VTT")
			(pintype "passive")
		)
	)
	(footprint "antmicro-footprints:FB_0603_1608Metric"
		(layer "F.Cu")
		(at 228.39 145.58)
		(property "Reference" "FB12"
			(at 1.26 0.27 0)
			(layer "F.SilkS")
			(effects
				(font
					(size 0.7 0.7)
					(thickness 0.15)
				)
				(justify left bottom)
			)
		)
		(property "Value" "FB_120Z_2A_Murata-BLM18PG_0603"
			(at 0 1.7 0)
			(layer "F.Fab")
			(effects
				(font
					(size 0.7 0.7)
					(thickness 0.15)
				)
				(justify left bottom)
			)
		)
		(property "Description" "Ferrite Bead, 0603 [1608 Metric], 120 ohm, 2 A, BLM18P, 0.05 ohm, ± 25%, DC power line"
			(at 0 0 0)
			(layer "F.Fab")
			(hide yes)
			(effects
				(font
					(size 1.27 1.27)
					(thickness 0.15)
				)
			)
		)
		(property "Author" "Antmicro"
			(at 0 0 0)
			(layer "F.Fab")
			(hide yes)
			(effects
				(font
					(size 1 1)
					(thickness 0.15)
				)
			)
		)
		(property "Current" ""
			(at 0 0 0)
			(layer "F.Fab")
			(hide yes)
			(effects
				(font
					(size 1 1)
					(thickness 0.15)
				)
			)
		)
		(property "License" "Apache-2.0"
			(at 0 0 0)
			(layer "F.Fab")
			(hide yes)
			(effects
				(font
					(size 1 1)
					(thickness 0.15)
				)
			)
		)
		(property "MPN" "BLM18PG121SN1D"
			(at 0 0 0)
			(layer "F.Fab")
			(hide yes)
			(effects
				(font
					(size 1 1)
					(thickness 0.15)
				)
			)
		)
		(property "Manufacturer" "Murata"
			(at 0 0 0)
			(layer "F.Fab")
			(hide yes)
			(effects
				(font
					(size 1 1)
					(thickness 0.15)
				)
			)
		)
		(property "Val" "120Z/2A"
			(at 0 0 0)
			(layer "F.Fab")
			(hide yes)
			(effects
				(font
					(size 1 1)
					(thickness 0.15)
				)
			)
		)
		(sheetname "Clocks")
		(sheetfile "clocks.kicad_sch")
		(attr smd)
		(fp_line
			(start -0.15 -0.4)
			(end 0.15 -0.4)
			(stroke
				(width 0.15)
				(type solid)
			)
			(layer "F.SilkS")
		)
		(fp_line
			(start -0.15 0.4)
			(end 0.15 0.4)
			(stroke
				(width 0.15)
				(type solid)
			)
			(layer "F.SilkS")
		)
		(fp_rect
			(start -1.25 -0.65)
			(end 1.25 0.65)
			(stroke
				(width 0.05)
				(type solid)
			)
			(fill no)
			(layer "F.CrtYd")
		)
		(fp_line
			(start -0.803 0.406)
			(end -0.803 -0.408)
			(stroke
				(width 0.15)
				(type solid)
			)
			(layer "F.Fab")
		)
		(fp_line
			(start 0.8 -0.408)
			(end -0.803 -0.408)
			(stroke
				(width 0.15)
				(type solid)
			)
			(layer "F.Fab")
		)
		(fp_line
			(start 0.8 -0.408)
			(end 0.8 0.406)
			(stroke
				(width 0.15)
				(type solid)
			)
			(layer "F.Fab")
		)
		(fp_line
			(start 0.8 0.406)
			(end -0.803 0.406)
			(stroke
				(width 0.15)
				(type solid)
			)
			(layer "F.Fab")
		)
		(pad "1" smd roundrect
			(at -0.7 0)
			(size 0.8 1)
			(layers "F.Cu" "F.Mask" "F.Paste")
			(roundrect_rratio 0.2)
			(net 1231 "Net-(C366-Pad2)")
			(pintype "passive")
		)
		(pad "2" smd roundrect
			(at 0.7 0)
			(size 0.8 1)
			(layers "F.Cu" "F.Mask" "F.Paste")
			(roundrect_rratio 0.2)
			(net 24 "+3V3")
			(pintype "passive")
		)
	)
	(footprint "antmicro-footprints:PinHeader_2x3_P2.54mm_SMD"
		(layer "F.Cu")
		(at 212.7 88.4)
		(property "Reference" "J20"
			(at 3.55 3.45 180)
			(layer "F.SilkS")
			(effects
				(font
					(size 0.7 0.7)
					(thickness 0.15)
				)
				(justify left bottom)
			)
		)
		(property "Value" "PinHeader_2x3_P2.54mm_SMD"
			(at 5.31 10.794 90)
			(layer "F.Fab")
			(effects
				(font
					(size 0.7 0.7)
					(thickness 0.15)
				)
				(justify left bottom)
			)
		)
		(property "Author" "Antmicro"
			(at 0 0 0)
			(layer "F.Fab")
			(hide yes)
			(effects
				(font
					(size 1 1)
					(thickness 0.15)
				)
			)
		)
		(property "License" "Apache-2.0"
			(at 0 0 0)
			(layer "F.Fab")
			(hide yes)
			(effects
				(font
					(size 1 1)
					(thickness 0.15)
				)
			)
		)
		(property "MPN" "15910060"
			(at 0 0 0)
			(layer "F.Fab")
			(hide yes)
			(effects
				(font
					(size 1 1)
					(thickness 0.15)
				)
			)
		)
		(property "Manufacturer" "Molex"
			(at 0 0 0)
			(layer "F.Fab")
			(hide yes)
			(effects
				(font
					(size 1 1)
					(thickness 0.15)
				)
			)
		)
		(sheetname "FPGA supply")
		(sheetfile "fpga-supply.kicad_sch")
		(attr smd)
		(fp_line
			(start -3.809 -2.555)
			(end -3.269 -2.555)
			(stroke
				(width 0.15)
				(type solid)
			)
			(layer "F.SilkS")
		)
		(fp_line
			(start -3.809 2.521)
			(end -3.809 -2.555)
			(stroke
				(width 0.15)
				(type solid)
			)
			(layer "F.SilkS")
		)
		(fp_line
			(start -3.809 2.521)
			(end -3.269 2.521)
			(stroke
				(width 0.15)
				(type solid)
			)
			(layer "F.SilkS")
		)
		(fp_line
			(start 3.81 -2.555)
			(end 3.27 -2.555)
			(stroke
				(width 0.15)
				(type solid)
			)
			(layer "F.SilkS")
		)
		(fp_line
			(start 3.81 -2.555)
			(end 3.81 2.521)
			(stroke
				(width 0.15)
				(type solid)
			)
			(layer "F.SilkS")
		)
		(fp_line
			(start 3.81 2.521)
			(end 3.27 2.521)
			(stroke
				(width 0.15)
				(type solid)
			)
			(layer "F.SilkS")
		)
		(fp_circle
			(center -3.45 2.95)
			(end -3.397 2.95)
			(stroke
				(width 0.15)
				(type solid)
			)
			(fill yes)
			(layer "F.SilkS")
		)
		(fp_rect
			(start -4.31 -4.103)
			(end 4.309 4.101)
			(stroke
				(width 0.05)
				(type solid)
			)
			(fill no)
			(layer "F.CrtYd")
		)
		(fp_line
			(start -3.81 3.29)
			(end -3.61 3.49)
			(stroke
				(width 0.15)
				(type solid)
			)
			(layer "F.Fab")
		)
		(fp_rect
			(start -3.81 -3.493)
			(end 3.809 3.491)
			(stroke
				(width 0.15)
				(type solid)
			)
			(fill no)
			(layer "F.Fab")
		)
		(pad "1" smd rect
			(at -2.539 2.2)
			(size 1.27 3.68)
			(layers "F.Cu" "F.Mask" "F.Paste")
			(net 3 "VCC_USR_B")
			(pintype "passive")
		)
		(pad "2" smd rect
			(at -2.539 -2.2 180)
			(size 1.27 3.68)
			(layers "F.Cu" "F.Mask" "F.Paste")
			(net 24 "+3V3")
			(pintype "passive")
		)
		(pad "3" smd rect
			(at 0 2.2)
			(size 1.27 3.68)
			(layers "F.Cu" "F.Mask" "F.Paste")
			(net 26 "+1V8")
			(pintype "passive")
		)
		(pad "4" smd rect
			(at 0 -2.2 180)
			(size 1.27 3.68)
			(layers "F.Cu" "F.Mask" "F.Paste")
			(net 3 "VCC_USR_B")
			(pintype "passive")
		)
		(pad "5" smd rect
			(at 2.539 2.2)
			(size 1.27 3.68)
			(layers "F.Cu" "F.Mask" "F.Paste")
			(net 3 "VCC_USR_B")
			(pintype "passive")
		)
		(pad "6" smd rect
			(at 2.539 -2.2 180)
			(size 1.27 3.68)
			(layers "F.Cu" "F.Mask" "F.Paste")
			(net 727 "+1V2")
			(pintype "passive")
		)
	)
	(footprint "antmicro-footprints:R_0402_1005Metric"
		(layer "F.Cu")
		(at 173.570001 106.476251)
		(descr "Resistor SMD 0402")
		(tags "resistor SMD 0402")
		(property "Reference" "R272"
			(at 0.929999 0.376249 0)
			(layer "F.SilkS")
			(effects
				(font
					(size 0.7 0.7)
					(thickness 0.15)
				)
				(justify left bottom)
			)
		)
		(property "Value" "R_33R_0402"
			(at 0 1.4 0)
			(layer "F.Fab")
			(effects
				(font
					(size 0.7 0.7)
					(thickness 0.15)
				)
				(justify left bottom)
			)
		)
		(property "Description" "SMD Chip Resistor, 33 ohm, ± 1%, 62.5 mW, 0402 [1005 Metric], Thick Film, General Purpose"
			(at 0 0 0)
			(layer "F.Fab")
			(hide yes)
			(effects
				(font
					(size 1.27 1.27)
					(thickness 0.15)
				)
			)
		)
		(property "Author" "Antmicro"
			(at 0 0 0)
			(layer "F.Fab")
			(hide yes)
			(effects
				(font
					(size 1 1)
					(thickness 0.15)
				)
			)
		)
		(property "License" "Apache-2.0"
			(at 0 0 0)
			(layer "F.Fab")
			(hide yes)
			(effects
				(font
					(size 1 1)
					(thickness 0.15)
				)
			)
		)
		(property "MPN" "CR0402-FX-33R0GLF"
			(at 0 0 0)
			(layer "F.Fab")
			(hide yes)
			(effects
				(font
					(size 1 1)
					(thickness 0.15)
				)
			)
		)
		(property "Manufacturer" "Bourns"
			(at 0 0 0)
			(layer "F.Fab")
			(hide yes)
			(effects
				(font
					(size 1 1)
					(thickness 0.15)
				)
			)
		)
		(property "Tolerance" "1%"
			(at 0 0 0)
			(layer "F.Fab")
			(hide yes)
			(effects
				(font
					(size 1 1)
					(thickness 0.15)
				)
			)
		)
		(property "Val" "33R"
			(at 0 0 0)
			(layer "F.Fab")
			(hide yes)
			(effects
				(font
					(size 1 1)
					(thickness 0.15)
				)
			)
		)
		(sheetname "FMC+ HSPC")
		(sheetfile "fmc-hspc.kicad_sch")
		(attr smd)
		(fp_rect
			(start -0.925 -0.47)
			(end 0.925 0.47)
			(stroke
				(width 0.05)
				(type default)
			)
			(fill no)
			(layer "F.CrtYd")
		)
		(fp_rect
			(start -0.5 -0.25)
			(end 0.5 0.25)
			(stroke
				(width 0.15)
				(type solid)
			)
			(fill no)
			(layer "F.Fab")
		)
		(pad "1" smd roundrect
			(at -0.48 0)
			(size 0.59 0.64)
			(layers "F.Cu" "F.Mask" "F.Paste")
			(roundrect_rratio 0.25)
			(net 478 "/FMC+ HSPC/GTR_REFCLK1_R_N")
			(pintype "passive")
		)
		(pad "2" smd roundrect
			(at 0.48 0)
			(size 0.59 0.64)
			(layers "F.Cu" "F.Mask" "F.Paste")
			(roundrect_rratio 0.25)
			(net 592 "/FMC+ HSPC/GTX115.REFCLK1_N")
			(pintype "passive")
		)
	)
	(footprint "antmicro-footprints:R_Array_4x0201_Panasonic_EXB18V"
		(layer "F.Cu")
		(at 249.4 122)
		(property "Reference" "R26"
			(at 1.15 -0.8 0)
			(layer "F.SilkS")
			(effects
				(font
					(size 0.7 0.7)
					(thickness 0.15)
				)
				(justify right bottom)
			)
		)
		(property "Value" "R_4x33R_0201_array"
			(at -1.1 1.8 0)
			(layer "F.Fab")
			(effects
				(font
					(size 0.7 0.7)
					(thickness 0.15)
				)
				(justify left bottom)
			)
		)
		(property "Description" "Fixed Network Resistor, 33 ohm, Isolated, 4 Resistors, 0502 [1406 Metric], Flat, ± 5%"
			(at 0 0 0)
			(layer "F.Fab")
			(hide yes)
			(effects
				(font
					(size 1.27 1.27)
					(thickness 0.15)
				)
			)
		)
		(property "Author" "Antmicro"
			(at 0 0 0)
			(layer "F.Fab")
			(hide yes)
			(effects
				(font
					(size 1 1)
					(thickness 0.15)
				)
			)
		)
		(property "License" "Apache-2.0"
			(at 0 0 0)
			(layer "F.Fab")
			(hide yes)
			(effects
				(font
					(size 1 1)
					(thickness 0.15)
				)
			)
		)
		(property "MPN" "EXB-18V330JX"
			(at 0 0 0)
			(layer "F.Fab")
			(hide yes)
			(effects
				(font
					(size 1 1)
					(thickness 0.15)
				)
			)
		)
		(property "Manufacturer" "Panasonic"
			(at 0 0 0)
			(layer "F.Fab")
			(hide yes)
			(effects
				(font
					(size 1 1)
					(thickness 0.15)
				)
			)
		)
		(property "Val" "R_4x33R_0201"
			(at 0 0 0)
			(layer "F.Fab")
			(hide yes)
			(effects
				(font
					(size 1 1)
					(thickness 0.15)
				)
			)
		)
		(sheetname "Supervisior MCU")
		(sheetfile "supervisor-mcu.kicad_sch")
		(attr smd)
		(fp_line
			(start -0.8 -0.45)
			(end -0.8 0.45)
			(stroke
				(width 0.12)
				(type solid)
			)
			(layer "F.SilkS")
		)
		(fp_line
			(start 0.8 -0.45)
			(end 0.8 0.45)
			(stroke
				(width 0.12)
				(type solid)
			)
			(layer "F.SilkS")
		)
		(fp_rect
			(start -0.898 -0.66)
			(end 0.898 0.65)
			(stroke
				(width 0.05)
				(type solid)
			)
			(fill no)
			(layer "F.CrtYd")
		)
		(pad "1" smd roundrect
			(at -0.6 0.298)
			(size 0.2 0.4)
			(layers "F.Cu" "F.Mask" "F.Paste")
			(roundrect_rratio 0.25)
			(net 111 "/Supervisior MCU/FAN_PWM")
			(pinfunction "R1.1")
			(pintype "passive")
		)
		(pad "2" smd roundrect
			(at -0.202 0.298)
			(size 0.2 0.4)
			(layers "F.Cu" "F.Mask" "F.Paste")
			(roundrect_rratio 0.25)
			(net 1073 "/Supervisior MCU/USB_A12")
			(pinfunction "R2.1")
			(pintype "passive")
		)
		(pad "3" smd roundrect
			(at 0.2 0.298)
			(size 0.2 0.4)
			(layers "F.Cu" "F.Mask" "F.Paste")
			(roundrect_rratio 0.25)
			(net 1072 "/Supervisior MCU/USB_A11")
			(pinfunction "R3.1")
			(pintype "passive")
		)
		(pad "4" smd roundrect
			(at 0.598 0.298)
			(size 0.2 0.4)
			(layers "F.Cu" "F.Mask" "F.Paste")
			(roundrect_rratio 0.25)
			(net 1071 "/Supervisior MCU/USB_A10")
			(pinfunction "R4.1")
			(pintype "passive")
		)
		(pad "5" smd roundrect
			(at 0.598 -0.3)
			(size 0.2 0.4)
			(layers "F.Cu" "F.Mask" "F.Paste")
			(roundrect_rratio 0.25)
			(net 1369 "/SUP_MCU.A10")
			(pinfunction "R4.2")
			(pintype "passive")
		)
		(pad "6" smd roundrect
			(at 0.2 -0.3)
			(size 0.2 0.4)
			(layers "F.Cu" "F.Mask" "F.Paste")
			(roundrect_rratio 0.25)
			(net 1370 "/SUP_MCU.A11")
			(pinfunction "R3.2")
			(pintype "passive")
		)
		(pad "7" smd roundrect
			(at -0.202 -0.3)
			(size 0.2 0.4)
			(layers "F.Cu" "F.Mask" "F.Paste")
			(roundrect_rratio 0.25)
			(net 1371 "/SUP_MCU.A12")
			(pinfunction "R2.2")
			(pintype "passive")
		)
		(pad "8" smd roundrect
			(at -0.6 -0.3)
			(size 0.2 0.4)
			(layers "F.Cu" "F.Mask" "F.Paste")
			(roundrect_rratio 0.25)
			(net 1350 "/SUP_MCU.FAN_PWM")
			(pinfunction "R1.2")
			(pintype "passive")
		)
	)
	(footprint "antmicro-footprints:R_0402_1005Metric"
		(layer "F.Cu")
		(at 218.4 151.8)
		(descr "Resistor SMD 0402")
		(tags "resistor SMD 0402")
		(property "Reference" "R232"
			(at -3.6 0.35 0)
			(layer "F.SilkS")
			(effects
				(font
					(size 0.7 0.7)
					(thickness 0.15)
				)
				(justify left bottom)
			)
		)
		(property "Value" "R_10R_0402"
			(at 0 1.4 0)
			(layer "F.Fab")
			(effects
				(font
					(size 0.7 0.7)
					(thickness 0.15)
				)
				(justify left bottom)
			)
		)
		(property "Description" "SMD Chip Resistor, 10 ohm, ± 1%, 62.5 mW, 0402 [1005 Metric], Thick Film, General Purpose"
			(at 0 0 0)
			(layer "F.Fab")
			(hide yes)
			(effects
				(font
					(size 1.27 1.27)
					(thickness 0.15)
				)
			)
		)
		(property "Author" "Antmicro"
			(at 0 0 0)
			(layer "F.Fab")
			(hide yes)
			(effects
				(font
					(size 1 1)
					(thickness 0.15)
				)
			)
		)
		(property "License" "Apache-2.0"
			(at 0 0 0)
			(layer "F.Fab")
			(hide yes)
			(effects
				(font
					(size 1 1)
					(thickness 0.15)
				)
			)
		)
		(property "MPN" "CR0402-FX-10R0GLF"
			(at 0 0 0)
			(layer "F.Fab")
			(hide yes)
			(effects
				(font
					(size 1 1)
					(thickness 0.15)
				)
			)
		)
		(property "Manufacturer" "Bourns"
			(at 0 0 0)
			(layer "F.Fab")
			(hide yes)
			(effects
				(font
					(size 1 1)
					(thickness 0.15)
				)
			)
		)
		(property "Tolerance" "1%"
			(at 0 0 0)
			(layer "F.Fab")
			(hide yes)
			(effects
				(font
					(size 1 1)
					(thickness 0.15)
				)
			)
		)
		(property "Val" "10R"
			(at 0 0 0)
			(layer "F.Fab")
			(hide yes)
			(effects
				(font
					(size 1 1)
					(thickness 0.15)
				)
			)
		)
		(sheetname "HDMI + Ethernet")
		(sheetfile "hdmi-ethernet.kicad_sch")
		(attr smd)
		(fp_rect
			(start -0.925 -0.47)
			(end 0.925 0.47)
			(stroke
				(width 0.05)
				(type default)
			)
			(fill no)
			(layer "F.CrtYd")
		)
		(fp_rect
			(start -0.5 -0.25)
			(end 0.5 0.25)
			(stroke
				(width 0.15)
				(type solid)
			)
			(fill no)
			(layer "F.Fab")
		)
		(pad "1" smd roundrect
			(at -0.48 0)
			(size 0.59 0.64)
			(layers "F.Cu" "F.Mask" "F.Paste")
			(roundrect_rratio 0.25)
			(net 513 "/FPGA Bank 18 & 32/ETH_RMII.TXD0")
			(pintype "passive")
		)
		(pad "2" smd roundrect
			(at 0.48 0)
			(size 0.59 0.64)
			(layers "F.Cu" "F.Mask" "F.Paste")
			(roundrect_rratio 0.25)
			(net 949 "/HDMI + Ethernet/ETH_PHY_TXDO")
			(pintype "passive")
		)
	)
	(footprint "antmicro-footprints:LED_0603_1608Metric_G"
		(layer "F.Cu")
		(at 266.6 133.9 180)
		(descr "LED SMD 0603 Green")
		(tags "LED SMD 0603 Green")
		(property "Reference" "D29"
			(at -1.1 0.65 0)
			(layer "F.SilkS")
			(effects
				(font
					(size 0.7 0.7)
					(thickness 0.15)
				)
				(justify right bottom)
			)
		)
		(property "Value" "LED_G_0603_KP-1608CGCK"
			(at 0 1.6 0)
			(layer "F.Fab")
			(effects
				(font
					(size 0.7 0.7)
					(thickness 0.15)
				)
				(justify right bottom)
			)
		)
		(property "Description" "LED, Green, SMD, 0603, 20 mA, 2.1 V, 570 nm"
			(at 0 0 180)
			(layer "F.Fab")
			(hide yes)
			(effects
				(font
					(size 1.27 1.27)
					(thickness 0.15)
				)
			)
		)
		(property "Author" "Antmicro"
			(at 533.2 267.8 0)
			(layer "F.Fab")
			(hide yes)
			(effects
				(font
					(size 1 1)
					(thickness 0.15)
				)
			)
		)
		(property "Color" "Green"
			(at 533.2 267.8 0)
			(layer "F.Fab")
			(hide yes)
			(effects
				(font
					(size 1 1)
					(thickness 0.15)
				)
			)
		)
		(property "License" "Apache-2.0"
			(at 533.2 267.8 0)
			(layer "F.Fab")
			(hide yes)
			(effects
				(font
					(size 1 1)
					(thickness 0.15)
				)
			)
		)
		(property "MPN" "KP-1608CGCK"
			(at 533.2 267.8 0)
			(layer "F.Fab")
			(hide yes)
			(effects
				(font
					(size 1 1)
					(thickness 0.15)
				)
			)
		)
		(property "Manufacturer" "Kingbright"
			(at 533.2 267.8 0)
			(layer "F.Fab")
			(hide yes)
			(effects
				(font
					(size 1 1)
					(thickness 0.15)
				)
			)
		)
		(sheetname "USB PHY")
		(sheetfile "usb-phy.kicad_sch")
		(attr smd)
		(fp_line
			(start 0.22 0.35)
			(end -0.22 0.35)
			(stroke
				(width 0.15)
				(type solid)
			)
			(layer "F.SilkS")
		)
		(fp_line
			(start 0.22 -0.35)
			(end -0.22 -0.35)
			(stroke
				(width 0.15)
				(type solid)
			)
			(layer "F.SilkS")
		)
		(fp_line
			(start 0.105328 0.201008)
			(end 0.105328 -0.198992)
			(stroke
				(width 0.1)
				(type solid)
			)
			(layer "F.SilkS")
		)
		(fp_line
			(start 0.105328 0.201008)
			(end -0.094672 0.001008)
			(stroke
				(width 0.1)
				(type solid)
			)
			(layer "F.SilkS")
		)
		(fp_line
			(start 0.105328 0.001008)
			(end 0.24 0.001)
			(stroke
				(width 0.1)
				(type solid)
			)
			(layer "F.SilkS")
		)
		(fp_line
			(start -0.094672 0.201008)
			(end -0.094672 -0.198992)
			(stroke
				(width 0.1)
				(type solid)
			)
			(layer "F.SilkS")
		)
		(fp_line
			(start -0.094672 0.001008)
			(end 0.105328 -0.198992)
			(stroke
				(width 0.1)
				(type solid)
			)
			(layer "F.SilkS")
		)
		(fp_line
			(start -0.094672 0.001008)
			(end -0.24 0.001008)
			(stroke
				(width 0.1)
				(type solid)
			)
			(layer "F.SilkS")
		)
		(fp_line
			(start -1.18 -0.319)
			(end -1.18 0.321)
			(stroke
				(width 0.15)
				(type solid)
			)
			(layer "F.SilkS")
		)
		(fp_rect
			(start 1.25 0.65)
			(end -1.25 -0.65)
			(stroke
				(width 0.05)
				(type solid)
			)
			(fill no)
			(layer "F.CrtYd")
		)
		(fp_line
			(start 0.599 0)
			(end 0.201 0)
			(stroke
				(width 0.15)
				(type solid)
			)
			(layer "F.Fab")
		)
		(fp_line
			(start 0.201 0.2)
			(end 0.201 0)
			(stroke
				(width 0.15)
				(type solid)
			)
			(layer "F.Fab")
		)
		(fp_line
			(start 0.201 0)
			(end 0.201 -0.202)
			(stroke
				(width 0.15)
				(type solid)
			)
			(layer "F.Fab")
		)
		(fp_line
			(start 0.201 -0.202)
			(end -0.101 0)
			(stroke
				(width 0.15)
				(type solid)
			)
			(layer "F.Fab")
		)
		(fp_line
			(start -0.101 0)
			(end 0.201 0.2)
			(stroke
				(width 0.15)
				(type solid)
			)
			(layer "F.Fab")
		)
		(fp_line
			(start -0.199 0.2)
			(end -0.199 0.1)
			(stroke
				(width 0.15)
				(type solid)
			)
			(layer "F.Fab")
		)
		(fp_line
			(start -0.199 0)
			(end -0.597 0)
			(stroke
				(width 0.15)
				(type solid)
			)
			(layer "F.Fab")
		)
		(fp_line
			(start -0.199 -0.202)
			(end -0.199 0.1)
			(stroke
				(width 0.15)
				(type solid)
			)
			(layer "F.Fab")
		)
		(fp_rect
			(start 0.848 0.4)
			(end -0.85 -0.402)
			(stroke
				(width 0.15)
				(type solid)
			)
			(fill no)
			(layer "F.Fab")
		)
		(pad "1" smd roundrect
			(at -0.7 0)
			(size 0.8 1)
			(layers "F.Cu" "F.Mask" "F.Paste")
			(roundrect_rratio 0.2)
			(net 1 "GND")
			(pinfunction "C")
			(pintype "passive")
		)
		(pad "2" smd roundrect
			(at 0.7 0)
			(size 0.8 1)
			(layers "F.Cu" "F.Mask" "F.Paste")
			(roundrect_rratio 0.2)
			(net 793 "Net-(D29-A)")
			(pinfunction "A")
			(pintype "passive")
		)
	)
	(footprint "antmicro-footprints:C_0402_1005Metric"
		(layer "F.Cu")
		(at 151.2 146.65 -90)
		(descr "Capacitor SMD 0402")
		(tags "capacitor SMD 0402")
		(property "Reference" "C346"
			(at -3.65 -0.4 270)
			(layer "F.SilkS")
			(effects
				(font
					(size 0.7 0.7)
					(thickness 0.15)
				)
				(justify right bottom)
			)
		)
		(property "Value" "C_1u_0402"
			(at 0 1.4 90)
			(layer "F.Fab")
			(effects
				(font
					(size 0.7 0.7)
					(thickness 0.15)
				)
				(justify right bottom)
			)
		)
		(property "Description" "SMD Multilayer Ceramic Capacitor, 1 µF, 10 V, 0402 [1005 Metric], ± 10%, X6S, C"
			(at 0 0 270)
			(layer "F.Fab")
			(hide yes)
			(effects
				(font
					(size 1.27 1.27)
					(thickness 0.15)
				)
			)
		)
		(property "Author" "Antmicro"
			(at 4.55 297.85 0)
			(layer "F.Fab")
			(hide yes)
			(effects
				(font
					(size 1 1)
					(thickness 0.15)
				)
			)
		)
		(property "Dielectric" ""
			(at 4.55 297.85 0)
			(layer "F.Fab")
			(hide yes)
			(effects
				(font
					(size 1 1)
					(thickness 0.15)
				)
			)
		)
		(property "License" "Apache-2.0"
			(at 4.55 297.85 0)
			(layer "F.Fab")
			(hide yes)
			(effects
				(font
					(size 1 1)
					(thickness 0.15)
				)
			)
		)
		(property "MPN" "C1005X6S1A105K050BC"
			(at 4.55 297.85 0)
			(layer "F.Fab")
			(hide yes)
			(effects
				(font
					(size 1 1)
					(thickness 0.15)
				)
			)
		)
		(property "Manufacturer" "TDK"
			(at 4.55 297.85 0)
			(layer "F.Fab")
			(hide yes)
			(effects
				(font
					(size 1 1)
					(thickness 0.15)
				)
			)
		)
		(property "Val" "1u"
			(at 4.55 297.85 0)
			(layer "F.Fab")
			(hide yes)
			(effects
				(font
					(size 1 1)
					(thickness 0.15)
				)
			)
		)
		(property "Voltage" ""
			(at 4.55 297.85 0)
			(layer "F.Fab")
			(hide yes)
			(effects
				(font
					(size 1 1)
					(thickness 0.15)
				)
			)
		)
		(sheetname "DC-DC Converters")
		(sheetfile "dc-dc.kicad_sch")
		(attr smd)
		(fp_rect
			(start -0.925 -0.47)
			(end 0.925 0.47)
			(stroke
				(width 0.05)
				(type default)
			)
			(fill no)
			(layer "F.CrtYd")
		)
		(fp_line
			(start -0.494 0.248)
			(end -0.494 -0.25)
			(stroke
				(width 0.15)
				(type solid)
			)
			(layer "F.Fab")
		)
		(fp_line
			(start 0.504 0.248)
			(end -0.494 0.248)
			(stroke
				(width 0.15)
				(type solid)
			)
			(layer "F.Fab")
		)
		(fp_line
			(start -0.494 -0.25)
			(end 0.504 -0.25)
			(stroke
				(width 0.15)
				(type solid)
			)
			(layer "F.Fab")
		)
		(fp_line
			(start 0.504 -0.25)
			(end 0.504 0.248)
			(stroke
				(width 0.15)
				(type solid)
			)
			(layer "F.Fab")
		)
		(pad "1" smd roundrect
			(at -0.48 0 270)
			(size 0.59 0.64)
			(layers "F.Cu" "F.Mask" "F.Paste")
			(roundrect_rratio 0.25)
			(net 1 "GND")
			(pintype "passive")
		)
		(pad "2" smd roundrect
			(at 0.48 0 270)
			(size 0.59 0.64)
			(layers "F.Cu" "F.Mask" "F.Paste")
			(roundrect_rratio 0.25)
			(net 742 "/DC-DC Converters/1V85_VIN")
			(pintype "passive")
		)
	)
	(footprint "antmicro-footprints:Conn_JST_SH_1x4_BM04B-SRSS-TB-LF-SN"
		(layer "F.Cu")
		(at 230.8 133.2 -90)
		(property "Reference" "J7"
			(at -2 1.9 90)
			(layer "F.SilkS")
			(effects
				(font
					(size 0.7 0.7)
					(thickness 0.15)
				)
				(justify right bottom)
			)
		)
		(property "Value" "JST_SH_1x4_BM04B-SRSS-TB-LF-SN"
			(at 0 3.1 90)
			(layer "F.Fab")
			(effects
				(font
					(size 0.7 0.7)
					(thickness 0.15)
				)
				(justify right bottom)
			)
		)
		(property "Description" "Pin Header, Top Entry, Wire-to-Board, 1 mm, 1 Rows, 4 Contacts, Surface Mount, SR"
			(at 0 0 270)
			(layer "F.Fab")
			(hide yes)
			(effects
				(font
					(size 1.27 1.27)
					(thickness 0.15)
				)
			)
		)
		(property "Author" "Antmicro"
			(at 97.6 364 0)
			(layer "F.Fab")
			(hide yes)
			(effects
				(font
					(size 1 1)
					(thickness 0.15)
				)
			)
		)
		(property "License" "Apache-2.0"
			(at 97.6 364 0)
			(layer "F.Fab")
			(hide yes)
			(effects
				(font
					(size 1 1)
					(thickness 0.15)
				)
			)
		)
		(property "MPN" "BM04B-SRSS-TB(LF)(SN) "
			(at 97.6 364 0)
			(layer "F.Fab")
			(hide yes)
			(effects
				(font
					(size 1 1)
					(thickness 0.15)
				)
			)
		)
		(property "Manufacturer" "JST Automotive Connectors"
			(at 97.6 364 0)
			(layer "F.Fab")
			(hide yes)
			(effects
				(font
					(size 1 1)
					(thickness 0.15)
				)
			)
		)
		(sheetname "User GPIO + LED + button + DIP switch")
		(sheetfile "user-gpio.kicad_sch")
		(attr smd)
		(fp_line
			(start -1.125 2.999)
			(end -1.125 2.201)
			(stroke
				(width 0.15)
				(type solid)
			)
			(layer "F.SilkS")
		)
		(fp_line
			(start -0.251 2.999)
			(end -1.125 2.999)
			(stroke
				(width 0.15)
				(type solid)
			)
			(layer "F.SilkS")
		)
		(fp_line
			(start 1.774 -1.7)
			(end 1.774 1.702)
			(stroke
				(width 0.15)
				(type solid)
			)
			(layer "F.SilkS")
		)
		(fp_line
			(start -1.125 -2.999)
			(end -1.125 -2.201)
			(stroke
				(width 0.15)
				(type solid)
			)
			(layer "F.SilkS")
		)
		(fp_line
			(start -0.251 -2.999)
			(end -1.125 -2.999)
			(stroke
				(width 0.15)
				(type solid)
			)
			(layer "F.SilkS")
		)
		(fp_circle
			(center -1.6 -2.1)
			(end -1.55 -2.1)
			(stroke
				(width 0.15)
				(type solid)
			)
			(fill yes)
			(layer "F.SilkS")
		)
		(fp_rect
			(start -2.05 -3.95)
			(end 2.05 3.95)
			(stroke
				(width 0.05)
				(type solid)
			)
			(fill no)
			(layer "F.CrtYd")
		)
		(fp_rect
			(start -1.8 -3)
			(end 1.8 3)
			(stroke
				(width 0.15)
				(type solid)
			)
			(fill no)
			(layer "F.Fab")
		)
		(pad "1" smd roundrect
			(at -1.45 -1.5 180)
			(size 0.6 1.55)
			(layers "F.Cu" "F.Mask" "F.Paste")
			(roundrect_rratio 0.25)
			(net 1 "GND")
			(pinfunction "Pin_1")
			(pintype "passive")
		)
		(pad "2" smd roundrect
			(at -1.45 -0.5 180)
			(size 0.6 1.55)
			(layers "F.Cu" "F.Mask" "F.Paste")
			(roundrect_rratio 0.25)
			(net 703 "+5V")
			(pinfunction "Pin_2")
			(pintype "passive")
		)
		(pad "3" smd roundrect
			(at -1.45 0.5 180)
			(size 0.6 1.55)
			(layers "F.Cu" "F.Mask" "F.Paste")
			(roundrect_rratio 0.25)
			(net 30 "unconnected-(J7-Pin_3-Pad3)")
			(pinfunction "Pin_3")
			(pintype "passive+no_connect")
		)
		(pad "4" smd roundrect
			(at -1.45 1.5 180)
			(size 0.6 1.55)
			(layers "F.Cu" "F.Mask" "F.Paste")
			(roundrect_rratio 0.25)
			(net 801 "/User GPIO + LED + button + DIP switch/FAN_PWM_PIN")
			(pinfunction "Pin_4")
			(pintype "passive")
		)
		(pad "MP" smd roundrect
			(at 1.075 -2.8 180)
			(size 1.2 1.8)
			(layers "F.Cu" "F.Mask" "F.Paste")
			(roundrect_rratio 0.25)
			(net 1 "GND")
			(pinfunction "MP")
			(pintype "passive")
		)
		(pad "MP" smd roundrect
			(at 1.075 2.8 180)
			(size 1.2 1.8)
			(layers "F.Cu" "F.Mask" "F.Paste")
			(roundrect_rratio 0.25)
			(net 1 "GND")
			(pinfunction "MP")
			(pintype "passive")
		)
	)
	(footprint "antmicro-footprints:C_1206_3216Metric"
		(layer "F.Cu")
		(at 193.71 177.039 -90)
		(descr "Capacitor SMD 1206")
		(tags "capacitor SMD 1206")
		(property "Reference" "C201"
			(at -4.689 -2.14 225)
			(layer "F.SilkS")
			(effects
				(font
					(size 0.7 0.7)
					(thickness 0.15)
				)
				(justify right bottom)
			)
		)
		(property "Value" "C_47u_16V_1206"
			(at 0 2.1 90)
			(layer "F.Fab")
			(effects
				(font
					(size 0.7 0.7)
					(thickness 0.15)
				)
				(justify right bottom)
			)
		)
		(property "Description" "SMD Multilayer Ceramic Capacitor, 47 µF, 16 V, 1206 [3216 Metric], ± 20%, X5R, C"
			(at 0 0 270)
			(layer "F.Fab")
			(hide yes)
			(effects
				(font
					(size 1.27 1.27)
					(thickness 0.15)
				)
			)
		)
		(property "Author" "Antmicro"
			(at 16.671 370.749 0)
			(layer "F.Fab")
			(hide yes)
			(effects
				(font
					(size 1 1)
					(thickness 0.15)
				)
			)
		)
		(property "Dielectric" "X5R"
			(at 16.671 370.749 0)
			(layer "F.Fab")
			(hide yes)
			(effects
				(font
					(size 1 1)
					(thickness 0.15)
				)
			)
		)
		(property "License" "Apache-2.0"
			(at 16.671 370.749 0)
			(layer "F.Fab")
			(hide yes)
			(effects
				(font
					(size 1 1)
					(thickness 0.15)
				)
			)
		)
		(property "MPN" "C3216X5R1C476M160AB"
			(at 16.671 370.749 0)
			(layer "F.Fab")
			(hide yes)
			(effects
				(font
					(size 1 1)
					(thickness 0.15)
				)
			)
		)
		(property "Manufacturer" "TDK"
			(at 16.671 370.749 0)
			(layer "F.Fab")
			(hide yes)
			(effects
				(font
					(size 1 1)
					(thickness 0.15)
				)
			)
		)
		(property "Val" "47u"
			(at 16.671 370.749 0)
			(layer "F.Fab")
			(hide yes)
			(effects
				(font
					(size 1 1)
					(thickness 0.15)
				)
			)
		)
		(property "Voltage" "16V"
			(at 16.671 370.749 0)
			(layer "F.Fab")
			(hide yes)
			(effects
				(font
					(size 1 1)
					(thickness 0.15)
				)
			)
		)
		(sheetname "Power supply")
		(sheetfile "power-supply.kicad_sch")
		(attr smd)
		(fp_line
			(start 0.8 0.901)
			(end -0.8 0.901)
			(stroke
				(width 0.15)
				(type solid)
			)
			(layer "F.SilkS")
		)
		(fp_line
			(start 0.8 -0.899)
			(end -0.8 -0.899)
			(stroke
				(width 0.15)
				(type solid)
			)
			(layer "F.SilkS")
		)
		(fp_rect
			(start -2.325 -1.15)
			(end 2.325 1.15)
			(stroke
				(width 0.05)
				(type default)
			)
			(fill no)
			(layer "F.CrtYd")
		)
		(fp_rect
			(start -1.6 -0.799)
			(end 1.6 0.801)
			(stroke
				(width 0.15)
				(type solid)
			)
			(fill no)
			(layer "F.Fab")
		)
		(pad "1" smd roundrect
			(at -1.5 0.001 270)
			(size 1.15 1.8)
			(layers "F.Cu" "F.Mask" "F.Paste")
			(roundrect_rratio 0.25)
			(net 1 "GND")
			(pintype "passive")
		)
		(pad "2" smd roundrect
			(at 1.5 0.001 270)
			(size 1.15 1.8)
			(layers "F.Cu" "F.Mask" "F.Paste")
			(roundrect_rratio 0.25)
			(net 956 "/DC-DC Converters/POE_DC")
			(pintype "passive")
		)
	)
	(footprint "antmicro-footprints:R_0402_1005Metric"
		(layer "F.Cu")
		(at 178.8 77.745 -90)
		(descr "Resistor SMD 0402")
		(tags "resistor SMD 0402")
		(property "Reference" "R7"
			(at 2.355 -0.4 270)
			(layer "F.SilkS")
			(effects
				(font
					(size 0.7 0.7)
					(thickness 0.15)
				)
				(justify left bottom)
			)
		)
		(property "Value" "R_10k_0402"
			(at 0 1.4 270)
			(layer "F.Fab")
			(effects
				(font
					(size 0.7 0.7)
					(thickness 0.15)
				)
				(justify left bottom)
			)
		)
		(property "Description" "SMD Chip Resistor, 10 kohm, ± 1%, 62.5 mW, 0402 [1005 Metric], Thick Film, General Purpose"
			(at 0 0 270)
			(layer "F.Fab")
			(hide yes)
			(effects
				(font
					(size 1.27 1.27)
					(thickness 0.15)
				)
			)
		)
		(property "Author" "Antmicro"
			(at 101.055 256.545 0)
			(layer "F.Fab")
			(hide yes)
			(effects
				(font
					(size 1 1)
					(thickness 0.15)
				)
			)
		)
		(property "License" "Apache-2.0"
			(at 101.055 256.545 0)
			(layer "F.Fab")
			(hide yes)
			(effects
				(font
					(size 1 1)
					(thickness 0.15)
				)
			)
		)
		(property "MPN" "CR0402-FX-1002GLF"
			(at 101.055 256.545 0)
			(layer "F.Fab")
			(hide yes)
			(effects
				(font
					(size 1 1)
					(thickness 0.15)
				)
			)
		)
		(property "Manufacturer" "Bourns"
			(at 101.055 256.545 0)
			(layer "F.Fab")
			(hide yes)
			(effects
				(font
					(size 1 1)
					(thickness 0.15)
				)
			)
		)
		(property "Tolerance" "1%"
			(at 101.055 256.545 0)
			(layer "F.Fab")
			(hide yes)
			(effects
				(font
					(size 1 1)
					(thickness 0.15)
				)
			)
		)
		(property "Val" "10k"
			(at 101.055 256.545 0)
			(layer "F.Fab")
			(hide yes)
			(effects
				(font
					(size 1 1)
					(thickness 0.15)
				)
			)
		)
		(sheetname "FPGA Config")
		(sheetfile "fpga-config.kicad_sch")
		(attr smd)
		(fp_rect
			(start -0.925 -0.47)
			(end 0.925 0.47)
			(stroke
				(width 0.05)
				(type default)
			)
			(fill no)
			(layer "F.CrtYd")
		)
		(fp_rect
			(start -0.5 -0.25)
			(end 0.5 0.25)
			(stroke
				(width 0.15)
				(type solid)
			)
			(fill no)
			(layer "F.Fab")
		)
		(pad "1" smd roundrect
			(at -0.48 0 270)
			(size 0.59 0.64)
			(layers "F.Cu" "F.Mask" "F.Paste")
			(roundrect_rratio 0.25)
			(net 301 "/FPGA Config/PROGRAM_B")
			(pintype "passive")
		)
		(pad "2" smd roundrect
			(at 0.48 0 270)
			(size 0.59 0.64)
			(layers "F.Cu" "F.Mask" "F.Paste")
			(roundrect_rratio 0.25)
			(net 24 "+3V3")
			(pintype "passive")
		)
	)
	(footprint "antmicro-footprints:C_0402_1005Metric"
		(layer "F.Cu")
		(at 229.25 142.75 180)
		(descr "Capacitor SMD 0402")
		(tags "capacitor SMD 0402")
		(property "Reference" "C366"
			(at -3.65 -0.35 0)
			(layer "F.SilkS")
			(effects
				(font
					(size 0.7 0.7)
					(thickness 0.15)
				)
				(justify right bottom)
			)
		)
		(property "Value" "C_10u_0402"
			(at 0 1.4 0)
			(layer "F.Fab")
			(effects
				(font
					(size 0.7 0.7)
					(thickness 0.15)
				)
				(justify right bottom)
			)
		)
		(property "Description" "SMD Multilayer Ceramic Capacitor, 10 µF, 6.3 V, 0402 [1005 Metric], ± 20%, X5R, CC Series"
			(at 0 0 180)
			(layer "F.Fab")
			(hide yes)
			(effects
				(font
					(size 1.27 1.27)
					(thickness 0.15)
				)
			)
		)
		(property "Author" "Antmicro"
			(at 458.5 285.5 0)
			(layer "F.Fab")
			(hide yes)
			(effects
				(font
					(size 1 1)
					(thickness 0.15)
				)
			)
		)
		(property "Dielectric" ""
			(at 458.5 285.5 0)
			(layer "F.Fab")
			(hide yes)
			(effects
				(font
					(size 1 1)
					(thickness 0.15)
				)
			)
		)
		(property "License" "Apache-2.0"
			(at 458.5 285.5 0)
			(layer "F.Fab")
			(hide yes)
			(effects
				(font
					(size 1 1)
					(thickness 0.15)
				)
			)
		)
		(property "MPN" "CC0402MRX5R5BB106"
			(at 458.5 285.5 0)
			(layer "F.Fab")
			(hide yes)
			(effects
				(font
					(size 1 1)
					(thickness 0.15)
				)
			)
		)
		(property "Manufacturer" "YAGEO"
			(at 458.5 285.5 0)
			(layer "F.Fab")
			(hide yes)
			(effects
				(font
					(size 1 1)
					(thickness 0.15)
				)
			)
		)
		(property "Val" "10u"
			(at 458.5 285.5 0)
			(layer "F.Fab")
			(hide yes)
			(effects
				(font
					(size 1 1)
					(thickness 0.15)
				)
			)
		)
		(property "Voltage" ""
			(at 458.5 285.5 0)
			(layer "F.Fab")
			(hide yes)
			(effects
				(font
					(size 1 1)
					(thickness 0.15)
				)
			)
		)
		(sheetname "Clocks")
		(sheetfile "clocks.kicad_sch")
		(attr smd)
		(fp_rect
			(start -0.925 -0.47)
			(end 0.925 0.47)
			(stroke
				(width 0.05)
				(type default)
			)
			(fill no)
			(layer "F.CrtYd")
		)
		(fp_line
			(start 0.504 0.248)
			(end -0.494 0.248)
			(stroke
				(width 0.15)
				(type solid)
			)
			(layer "F.Fab")
		)
		(fp_line
			(start 0.504 -0.25)
			(end 0.504 0.248)
			(stroke
				(width 0.15)
				(type solid)
			)
			(layer "F.Fab")
		)
		(fp_line
			(start -0.494 0.248)
			(end -0.494 -0.25)
			(stroke
				(width 0.15)
				(type solid)
			)
			(layer "F.Fab")
		)
		(fp_line
			(start -0.494 -0.25)
			(end 0.504 -0.25)
			(stroke
				(width 0.15)
				(type solid)
			)
			(layer "F.Fab")
		)
		(pad "1" smd roundrect
			(at -0.48 0 180)
			(size 0.59 0.64)
			(layers "F.Cu" "F.Mask" "F.Paste")
			(roundrect_rratio 0.25)
			(net 1 "GND")
			(pintype "passive")
		)
		(pad "2" smd roundrect
			(at 0.48 0 180)
			(size 0.59 0.64)
			(layers "F.Cu" "F.Mask" "F.Paste")
			(roundrect_rratio 0.25)
			(net 1231 "Net-(C366-Pad2)")
			(pintype "passive")
		)
	)
	(footprint "antmicro-footprints:C_0402_1005Metric"
		(layer "F.Cu")
		(at 256.345 137.835 180)
		(descr "Capacitor SMD 0402")
		(tags "capacitor SMD 0402")
		(property "Reference" "C236"
			(at -2.2 4.8 0)
			(layer "F.SilkS")
			(effects
				(font
					(size 0.7 0.7)
					(thickness 0.15)
				)
				(justify right bottom)
			)
		)
		(property "Value" "C_10u_0402"
			(at 0 1.4 0)
			(layer "F.Fab")
			(effects
				(font
					(size 0.7 0.7)
					(thickness 0.15)
				)
				(justify right bottom)
			)
		)
		(property "Description" "SMD Multilayer Ceramic Capacitor, 10 µF, 6.3 V, 0402 [1005 Metric], ± 20%, X5R, CC Series"
			(at 0 0 180)
			(layer "F.Fab")
			(hide yes)
			(effects
				(font
					(size 1.27 1.27)
					(thickness 0.15)
				)
			)
		)
		(property "Author" "Antmicro"
			(at 512.69 275.67 0)
			(layer "F.Fab")
			(hide yes)
			(effects
				(font
					(size 1 1)
					(thickness 0.15)
				)
			)
		)
		(property "Dielectric" ""
			(at 512.69 275.67 0)
			(layer "F.Fab")
			(hide yes)
			(effects
				(font
					(size 1 1)
					(thickness 0.15)
				)
			)
		)
		(property "License" "Apache-2.0"
			(at 512.69 275.67 0)
			(layer "F.Fab")
			(hide yes)
			(effects
				(font
					(size 1 1)
					(thickness 0.15)
				)
			)
		)
		(property "MPN" "CC0402MRX5R5BB106"
			(at 512.69 275.67 0)
			(layer "F.Fab")
			(hide yes)
			(effects
				(font
					(size 1 1)
					(thickness 0.15)
				)
			)
		)
		(property "Manufacturer" "YAGEO"
			(at 512.69 275.67 0)
			(layer "F.Fab")
			(hide yes)
			(effects
				(font
					(size 1 1)
					(thickness 0.15)
				)
			)
		)
		(property "Val" "10u"
			(at 512.69 275.67 0)
			(layer "F.Fab")
			(hide yes)
			(effects
				(font
					(size 1 1)
					(thickness 0.15)
				)
			)
		)
		(property "Voltage" ""
			(at 512.69 275.67 0)
			(layer "F.Fab")
			(hide yes)
			(effects
				(font
					(size 1 1)
					(thickness 0.15)
				)
			)
		)
		(sheetname "USB PHY")
		(sheetfile "usb-phy.kicad_sch")
		(attr smd)
		(fp_rect
			(start -0.925 -0.47)
			(end 0.925 0.47)
			(stroke
				(width 0.05)
				(type default)
			)
			(fill no)
			(layer "F.CrtYd")
		)
		(fp_line
			(start 0.504 0.248)
			(end -0.494 0.248)
			(stroke
				(width 0.15)
				(type solid)
			)
			(layer "F.Fab")
		)
		(fp_line
			(start 0.504 -0.25)
			(end 0.504 0.248)
			(stroke
				(width 0.15)
				(type solid)
			)
			(layer "F.Fab")
		)
		(fp_line
			(start -0.494 0.248)
			(end -0.494 -0.25)
			(stroke
				(width 0.15)
				(type solid)
			)
			(layer "F.Fab")
		)
		(fp_line
			(start -0.494 -0.25)
			(end 0.504 -0.25)
			(stroke
				(width 0.15)
				(type solid)
			)
			(layer "F.Fab")
		)
		(pad "1" smd roundrect
			(at -0.48 0 180)
			(size 0.59 0.64)
			(layers "F.Cu" "F.Mask" "F.Paste")
			(roundrect_rratio 0.25)
			(net 1 "GND")
			(pintype "passive")
		)
		(pad "2" smd roundrect
			(at 0.48 0 180)
			(size 0.59 0.64)
			(layers "F.Cu" "F.Mask" "F.Paste")
			(roundrect_rratio 0.25)
			(net 714 "/USB PHY/FTDI_VPHY")
			(pintype "passive")
		)
	)
	(footprint "antmicro-footprints:C_0402_1005Metric"
		(layer "F.Cu")
		(at 220.6 153.6)
		(descr "Capacitor SMD 0402")
		(tags "capacitor SMD 0402")
		(property "Reference" "C267"
			(at -4.75 0.45 0)
			(layer "F.SilkS")
			(effects
				(font
					(size 0.7 0.7)
					(thickness 0.15)
				)
				(justify left bottom)
			)
		)
		(property "Value" "C_100n_0402"
			(at 0 1.169 0)
			(layer "F.Fab")
			(effects
				(font
					(size 0.7 0.7)
					(thickness 0.15)
				)
				(justify left bottom)
			)
		)
		(property "Description" "SMD Multilayer Ceramic Capacitor, 0.1 µF, 50 V, 0402 [1005 Metric], ± 10%, X5R, GRM Series"
			(at 0 0 0)
			(layer "F.Fab")
			(hide yes)
			(effects
				(font
					(size 1.27 1.27)
					(thickness 0.15)
				)
			)
		)
		(property "Author" "Antmicro"
			(at 0 0 0)
			(layer "F.Fab")
			(hide yes)
			(effects
				(font
					(size 1 1)
					(thickness 0.15)
				)
			)
		)
		(property "Dielectric" "X5R"
			(at 0 0 0)
			(layer "F.Fab")
			(hide yes)
			(effects
				(font
					(size 1 1)
					(thickness 0.15)
				)
			)
		)
		(property "License" "Apache-2.0"
			(at 0 0 0)
			(layer "F.Fab")
			(hide yes)
			(effects
				(font
					(size 1 1)
					(thickness 0.15)
				)
			)
		)
		(property "MPN" "GRM155R61H104KE14D"
			(at 0 0 0)
			(layer "F.Fab")
			(hide yes)
			(effects
				(font
					(size 1 1)
					(thickness 0.15)
				)
			)
		)
		(property "Manufacturer" "Murata"
			(at 0 0 0)
			(layer "F.Fab")
			(hide yes)
			(effects
				(font
					(size 1 1)
					(thickness 0.15)
				)
			)
		)
		(property "Val" "100n"
			(at 0 0 0)
			(layer "F.Fab")
			(hide yes)
			(effects
				(font
					(size 1 1)
					(thickness 0.15)
				)
			)
		)
		(property "Voltage" "50V"
			(at 0 0 0)
			(layer "F.Fab")
			(hide yes)
			(effects
				(font
					(size 1 1)
					(thickness 0.15)
				)
			)
		)
		(sheetname "HDMI + Ethernet")
		(sheetfile "hdmi-ethernet.kicad_sch")
		(attr smd)
		(fp_rect
			(start -0.925 -0.47)
			(end 0.925 0.47)
			(stroke
				(width 0.05)
				(type default)
			)
			(fill no)
			(layer "F.CrtYd")
		)
		(fp_line
			(start -0.494 -0.25)
			(end 0.504 -0.25)
			(stroke
				(width 0.15)
				(type solid)
			)
			(layer "F.Fab")
		)
		(fp_line
			(start -0.494 0.248)
			(end -0.494 -0.25)
			(stroke
				(width 0.15)
				(type solid)
			)
			(layer "F.Fab")
		)
		(fp_line
			(start 0.504 -0.25)
			(end 0.504 0.248)
			(stroke
				(width 0.15)
				(type solid)
			)
			(layer "F.Fab")
		)
		(fp_line
			(start 0.504 0.248)
			(end -0.494 0.248)
			(stroke
				(width 0.15)
				(type solid)
			)
			(layer "F.Fab")
		)
		(pad "1" smd roundrect
			(at -0.48 0)
			(size 0.59 0.64)
			(layers "F.Cu" "F.Mask" "F.Paste")
			(roundrect_rratio 0.25)
			(net 1 "GND")
			(pintype "passive")
		)
		(pad "2" smd roundrect
			(at 0.48 0)
			(size 0.59 0.64)
			(layers "F.Cu" "F.Mask" "F.Paste")
			(roundrect_rratio 0.25)
			(net 721 "/HDMI + Ethernet/ETH_3V3")
			(pintype "passive")
		)
	)
	(footprint "antmicro-footprints:QFN-24-1EP_4x4mm_P0.5_EP2.1x2.1mm"
		(layer "F.Cu")
		(at 228.4 163.43 180)
		(property "Reference" "U6"
			(at 3.7 -2.39 180)
			(layer "F.SilkS")
			(effects
				(font
					(size 0.7 0.7)
					(thickness 0.15)
				)
				(justify left bottom)
			)
		)
		(property "Value" "STUSB4500_QFN"
			(at 9.858 4.248 180)
			(layer "F.Fab")
			(effects
				(font
					(size 0.7 0.7)
					(thickness 0.15)
				)
				(justify left bottom)
			)
		)
		(property "Description" "USB Controller USB 2.0 I2C Interface 24-QFN (4x4)"
			(at 0 0 180)
			(layer "F.Fab")
			(hide yes)
			(effects
				(font
					(size 1.27 1.27)
					(thickness 0.15)
				)
			)
		)
		(property "Author" "Antmicro"
			(at 456.8 326.86 0)
			(layer "F.Fab")
			(hide yes)
			(effects
				(font
					(size 1 1)
					(thickness 0.15)
				)
			)
		)
		(property "License" "Apache-2.0"
			(at 456.8 326.86 0)
			(layer "F.Fab")
			(hide yes)
			(effects
				(font
					(size 1 1)
					(thickness 0.15)
				)
			)
		)
		(property "MPN" "STUSB4500QTR"
			(at 456.8 326.86 0)
			(layer "F.Fab")
			(hide yes)
			(effects
				(font
					(size 1 1)
					(thickness 0.15)
				)
			)
		)
		(property "Manufacturer" "STMicroelectronics"
			(at 456.8 326.86 0)
			(layer "F.Fab")
			(hide yes)
			(effects
				(font
					(size 1 1)
					(thickness 0.15)
				)
			)
		)
		(sheetname "Power supply")
		(sheetfile "power-supply.kicad_sch")
		(attr smd)
		(fp_line
			(start 2.108 2.108)
			(end 2.108 1.634)
			(stroke
				(width 0.15)
				(type solid)
			)
			(layer "F.SilkS")
		)
		(fp_line
			(start 2.108 -2.11)
			(end 2.108 -1.635)
			(stroke
				(width 0.15)
				(type solid)
			)
			(layer "F.SilkS")
		)
		(fp_line
			(start 1.634 2.108)
			(end 2.108 2.108)
			(stroke
				(width 0.15)
				(type solid)
			)
			(layer "F.SilkS")
		)
		(fp_line
			(start 1.634 -2.11)
			(end 2.108 -2.11)
			(stroke
				(width 0.15)
				(type solid)
			)
			(layer "F.SilkS")
		)
		(fp_line
			(start -1.635 2.108)
			(end -2.11 2.108)
			(stroke
				(width 0.15)
				(type solid)
			)
			(layer "F.SilkS")
		)
		(fp_line
			(start -1.635 -2.11)
			(end -2.11 -2.11)
			(stroke
				(width 0.15)
				(type solid)
			)
			(layer "F.SilkS")
		)
		(fp_line
			(start -2.11 2.108)
			(end -2.11 1.634)
			(stroke
				(width 0.15)
				(type solid)
			)
			(layer "F.SilkS")
		)
		(fp_line
			(start -2.11 -1.636)
			(end -2.11 -2.11)
			(stroke
				(width 0.15)
				(type solid)
			)
			(layer "F.SilkS")
		)
		(fp_circle
			(center -2.3 -2.3)
			(end -2.25 -2.3)
			(stroke
				(width 0.15)
				(type solid)
			)
			(fill yes)
			(layer "F.SilkS")
		)
		(fp_rect
			(start -2.503 -2.503)
			(end 2.5 2.5)
			(stroke
				(width 0.05)
				(type solid)
			)
			(fill no)
			(layer "F.CrtYd")
		)
		(fp_line
			(start 1.999 1.999)
			(end -2 1.999)
			(stroke
				(width 0.15)
				(type solid)
			)
			(layer "F.Fab")
		)
		(fp_line
			(start 1.999 -2)
			(end 1.999 1.999)
			(stroke
				(width 0.15)
				(type solid)
			)
			(layer "F.Fab")
		)
		(fp_line
			(start -1 -2)
			(end 1.999 -2)
			(stroke
				(width 0.15)
				(type solid)
			)
			(layer "F.Fab")
		)
		(fp_line
			(start -2 1.999)
			(end -2 -1)
			(stroke
				(width 0.15)
				(type solid)
			)
			(layer "F.Fab")
		)
		(fp_line
			(start -2 -1)
			(end -1 -2)
			(stroke
				(width 0.15)
				(type solid)
			)
			(layer "F.Fab")
		)
		(pad "" smd roundrect
			(at -0.5 -0.5 180)
			(size 0.8 0.8)
			(layers "F.Paste")
			(roundrect_rratio 0.238095)
		)
		(pad "" smd roundrect
			(at -0.5 0.5 180)
			(size 0.8 0.8)
			(layers "F.Paste")
			(roundrect_rratio 0.238095)
		)
		(pad "" smd roundrect
			(at 0.5 -0.5 180)
			(size 0.8 0.8)
			(layers "F.Paste")
			(roundrect_rratio 0.238095)
		)
		(pad "" smd roundrect
			(at 0.5 0.5 180)
			(size 0.8 0.8)
			(layers "F.Paste")
			(roundrect_rratio 0.238095)
		)
		(pad "1" smd roundrect
			(at -1.938 -1.25 180)
			(size 0.825 0.25)
			(layers "F.Cu" "F.Mask" "F.Paste")
			(roundrect_rratio 0.25)
			(net 837 "/Power supply/USB_DBG_PD.CC1")
			(pinfunction "CC1DB")
			(pintype "bidirectional")
		)
		(pad "2" smd roundrect
			(at -1.938 -0.75 180)
			(size 0.825 0.25)
			(layers "F.Cu" "F.Mask" "F.Paste")
			(roundrect_rratio 0.25)
			(net 837 "/Power supply/USB_DBG_PD.CC1")
			(pinfunction "CC1")
			(pintype "bidirectional")
		)
		(pad "3" smd roundrect
			(at -1.938 -0.25 180)
			(size 0.825 0.25)
			(layers "F.Cu" "F.Mask" "F.Paste")
			(roundrect_rratio 0.25)
			(net 1140 "unconnected-(U6-NC-Pad3)")
			(pinfunction "NC")
			(pintype "no_connect")
		)
		(pad "4" smd roundrect
			(at -1.938 0.248 180)
			(size 0.825 0.25)
			(layers "F.Cu" "F.Mask" "F.Paste")
			(roundrect_rratio 0.25)
			(net 840 "/Power supply/USB_DBG_PD.CC2")
			(pinfunction "CC2")
			(pintype "bidirectional")
		)
		(pad "5" smd roundrect
			(at -1.938 0.748 180)
			(size 0.825 0.25)
			(layers "F.Cu" "F.Mask" "F.Paste")
			(roundrect_rratio 0.25)
			(net 840 "/Power supply/USB_DBG_PD.CC2")
			(pinfunction "CC2DB")
			(pintype "bidirectional")
		)
		(pad "6" smd roundrect
			(at -1.938 1.249 180)
			(size 0.825 0.25)
			(layers "F.Cu" "F.Mask" "F.Paste")
			(roundrect_rratio 0.25)
			(net 983 "/Power supply/PD_CTRL.RESET")
			(pinfunction "RESET")
			(pintype "input")
		)
		(pad "7" smd roundrect
			(at -1.25 1.937 180)
			(size 0.25 0.825)
			(layers "F.Cu" "F.Mask" "F.Paste")
			(roundrect_rratio 0.25)
			(net 1338 "/I2C.SCL")
			(pinfunction "SCL")
			(pintype "input")
		)
		(pad "8" smd roundrect
			(at -0.75 1.937 180)
			(size 0.25 0.825)
			(layers "F.Cu" "F.Mask" "F.Paste")
			(roundrect_rratio 0.25)
			(net 1336 "/I2C.SDA")
			(pinfunction "SDA")
			(pintype "bidirectional")
		)
		(pad "9" smd roundrect
			(at -0.25 1.937 180)
			(size 0.25 0.825)
			(layers "F.Cu" "F.Mask" "F.Paste")
			(roundrect_rratio 0.25)
			(net 888 "/Power supply/PDBUS_DISCH")
			(pinfunction "DISCH")
			(pintype "bidirectional")
		)
		(pad "10" smd roundrect
			(at 0.248 1.937 180)
			(size 0.25 0.825)
			(layers "F.Cu" "F.Mask" "F.Paste")
			(roundrect_rratio 0.25)
			(net 1 "GND")
			(pinfunction "GND")
			(pintype "power_in")
		)
		(pad "11" smd roundrect
			(at 0.748 1.937 180)
			(size 0.25 0.825)
			(layers "F.Cu" "F.Mask" "F.Paste")
			(roundrect_rratio 0.25)
			(net 1141 "unconnected-(U6-ATTACH-Pad11)")
			(pinfunction "ATTACH")
			(pintype "output+no_connect")
		)
		(pad "12" smd roundrect
			(at 1.249 1.937 180)
			(size 0.25 0.825)
			(layers "F.Cu" "F.Mask" "F.Paste")
			(roundrect_rratio 0.25)
			(net 1 "GND")
			(pinfunction "ADDR0")
			(pintype "input")
		)
		(pad "13" smd roundrect
			(at 1.937 1.249 180)
			(size 0.825 0.25)
			(layers "F.Cu" "F.Mask" "F.Paste")
			(roundrect_rratio 0.25)
			(net 1 "GND")
			(pinfunction "ADDR1")
			(pintype "input")
		)
		(pad "14" smd roundrect
			(at 1.937 0.748 180)
			(size 0.825 0.25)
			(layers "F.Cu" "F.Mask" "F.Paste")
			(roundrect_rratio 0.25)
			(net 771 "/Power supply/PD_PWR_OK3")
			(pinfunction "POWER_OK3")
			(pintype "output")
		)
		(pad "15" smd roundrect
			(at 1.937 0.248 180)
			(size 0.825 0.25)
			(layers "F.Cu" "F.Mask" "F.Paste")
			(roundrect_rratio 0.25)
			(net 1142 "unconnected-(U6-GPIO-Pad15)")
			(pinfunction "GPIO")
			(pintype "output+no_connect")
		)
		(pad "16" smd roundrect
			(at 1.937 -0.25 180)
			(size 0.825 0.25)
			(layers "F.Cu" "F.Mask" "F.Paste")
			(roundrect_rratio 0.25)
			(net 362 "Net-(U6-VBUS_EN_SNK)")
			(pinfunction "VBUS_EN_SNK")
			(pintype "output")
		)
		(pad "17" smd roundrect
			(at 1.937 -0.75 180)
			(size 0.825 0.25)
			(layers "F.Cu" "F.Mask" "F.Paste")
			(roundrect_rratio 0.25)
			(net 1146 "unconnected-(U6-A_B_SIDE-Pad17)")
			(pinfunction "A_B_SIDE")
			(pintype "output+no_connect")
		)
		(pad "18" smd roundrect
			(at 1.937 -1.25 180)
			(size 0.825 0.25)
			(layers "F.Cu" "F.Mask" "F.Paste")
			(roundrect_rratio 0.25)
			(net 880 "/Power supply/VBUS_DIS")
			(pinfunction "VBUS_VS_DISCH")
			(pintype "input")
		)
		(pad "19" smd roundrect
			(at 1.249 -1.938 180)
			(size 0.25 0.825)
			(layers "F.Cu" "F.Mask" "F.Paste")
			(roundrect_rratio 0.25)
			(net 1147 "unconnected-(U6-~{ALERT}-Pad19)")
			(pinfunction "~{ALERT}")
			(pintype "output+no_connect")
		)
		(pad "20" smd roundrect
			(at 0.748 -1.938 180)
			(size 0.25 0.825)
			(layers "F.Cu" "F.Mask" "F.Paste")
			(roundrect_rratio 0.25)
			(net 769 "/Power supply/PD_PWR_OK2")
			(pinfunction "POWER_OK2")
			(pintype "output")
		)
		(pad "21" smd roundrect
			(at 0.248 -1.938 180)
			(size 0.25 0.825)
			(layers "F.Cu" "F.Mask" "F.Paste")
			(roundrect_rratio 0.25)
			(net 143 "/Power supply/VREG_1V2")
			(pinfunction "VREG_1V2")
			(pintype "output")
		)
		(pad "22" smd roundrect
			(at -0.25 -1.938 180)
			(size 0.25 0.825)
			(layers "F.Cu" "F.Mask" "F.Paste")
			(roundrect_rratio 0.25)
			(net 1 "GND")
			(pinfunction "VSYS")
			(pintype "power_in")
		)
		(pad "23" smd roundrect
			(at -0.75 -1.938 180)
			(size 0.25 0.825)
			(layers "F.Cu" "F.Mask" "F.Paste")
			(roundrect_rratio 0.25)
			(net 267 "/Power supply/VREG_2V7")
			(pinfunction "VREG_2V7")
			(pintype "output")
		)
		(pad "24" smd roundrect
			(at -1.25 -1.938 180)
			(size 0.25 0.825)
			(layers "F.Cu" "F.Mask" "F.Paste")
			(roundrect_rratio 0.25)
			(net 5 "/Power supply/PD_VBUS")
			(pinfunction "VDD")
			(pintype "power_in")
		)
		(pad "25" smd rect
			(at 0 0 180)
			(size 2.1 2.1)
			(layers "F.Cu" "F.Mask")
			(net 1 "GND")
			(pinfunction "EP")
			(pintype "power_in")
		)
	)
	(footprint "antmicro-footprints:R_0402_1005Metric"
		(layer "F.Cu")
		(at 235.915 122.5 180)
		(descr "Resistor SMD 0402")
		(tags "resistor SMD 0402")
		(property "Reference" "R76"
			(at -0.735 -0.35 180)
			(layer "F.SilkS")
			(effects
				(font
					(size 0.7 0.7)
					(thickness 0.15)
				)
				(justify left bottom)
			)
		)
		(property "Value" "R_0R_0402"
			(at 0 1.4 180)
			(layer "F.Fab")
			(effects
				(font
					(size 0.7 0.7)
					(thickness 0.15)
				)
				(justify left bottom)
			)
		)
		(property "Description" "SMD Chip Resistor, Jumper, 0 ohm, 100 mW, 0402 [1005 Metric], Thick Film, General Purpose"
			(at 0 0 180)
			(layer "F.Fab")
			(hide yes)
			(effects
				(font
					(size 1.27 1.27)
					(thickness 0.15)
				)
			)
		)
		(property "Author" "Antmicro"
			(at 471.83 245 0)
			(layer "F.Fab")
			(hide yes)
			(effects
				(font
					(size 1 1)
					(thickness 0.15)
				)
			)
		)
		(property "Current" "1A"
			(at 471.83 245 0)
			(layer "F.Fab")
			(hide yes)
			(effects
				(font
					(size 1 1)
					(thickness 0.15)
				)
			)
		)
		(property "License" "Apache-2.0"
			(at 471.83 245 0)
			(layer "F.Fab")
			(hide yes)
			(effects
				(font
					(size 1 1)
					(thickness 0.15)
				)
			)
		)
		(property "MPN" "ERJ2GE0R00X"
			(at 471.83 245 0)
			(layer "F.Fab")
			(hide yes)
			(effects
				(font
					(size 1 1)
					(thickness 0.15)
				)
			)
		)
		(property "Manufacturer" "Panasonic"
			(at 471.83 245 0)
			(layer "F.Fab")
			(hide yes)
			(effects
				(font
					(size 1 1)
					(thickness 0.15)
				)
			)
		)
		(property "Tolerance" ""
			(at 471.83 245 0)
			(layer "F.Fab")
			(hide yes)
			(effects
				(font
					(size 1 1)
					(thickness 0.15)
				)
			)
		)
		(property "Val" "0R"
			(at 471.83 245 0)
			(layer "F.Fab")
			(hide yes)
			(effects
				(font
					(size 1 1)
					(thickness 0.15)
				)
			)
		)
		(sheetname "SPI Flash + SD Card")
		(sheetfile "spi-flash.kicad_sch")
		(attr smd)
		(fp_rect
			(start -0.925 -0.47)
			(end 0.925 0.47)
			(stroke
				(width 0.05)
				(type default)
			)
			(fill no)
			(layer "F.CrtYd")
		)
		(fp_rect
			(start -0.5 -0.25)
			(end 0.5 0.25)
			(stroke
				(width 0.15)
				(type solid)
			)
			(fill no)
			(layer "F.Fab")
		)
		(pad "1" smd roundrect
			(at -0.48 0 180)
			(size 0.59 0.64)
			(layers "F.Cu" "F.Mask" "F.Paste")
			(roundrect_rratio 0.25)
			(net 38 "/FPGA Bank 14 & 15/SYSTEM_FLASH.DQ0")
			(pintype "passive")
		)
		(pad "2" smd roundrect
			(at 0.48 0 180)
			(size 0.59 0.64)
			(layers "F.Cu" "F.Mask" "F.Paste")
			(roundrect_rratio 0.25)
			(net 896 "/SPI Flash + SD Card/SYSTEM_FLASH_DQ0")
			(pintype "passive")
		)
	)
	(footprint "antmicro-footprints:R_0402_1005Metric"
		(layer "F.Cu")
		(at 235.9 112.6 180)
		(descr "Resistor SMD 0402")
		(tags "resistor SMD 0402")
		(property "Reference" "R96"
			(at -0.8 -0.375 180)
			(layer "F.SilkS")
			(effects
				(font
					(size 0.7 0.7)
					(thickness 0.15)
				)
				(justify left bottom)
			)
		)
		(property "Value" "R_100R_0402"
			(at 0 1.4 180)
			(layer "F.Fab")
			(effects
				(font
					(size 0.7 0.7)
					(thickness 0.15)
				)
				(justify left bottom)
			)
		)
		(property "Description" "SMD Chip Resistor, 100 ohm, ± 1%, 62.5 mW, 0402 [1005 Metric], Thick Film, General Purpose"
			(at 0 0 180)
			(layer "F.Fab")
			(hide yes)
			(effects
				(font
					(size 1.27 1.27)
					(thickness 0.15)
				)
			)
		)
		(property "Author" "Antmicro"
			(at 471.8 225.2 0)
			(layer "F.Fab")
			(hide yes)
			(effects
				(font
					(size 1 1)
					(thickness 0.15)
				)
			)
		)
		(property "DNP" "DNP"
			(at 471.8 225.2 0)
			(layer "F.Fab")
			(hide yes)
			(effects
				(font
					(size 1 1)
					(thickness 0.15)
				)
			)
		)
		(property "License" "Apache-2.0"
			(at 471.8 225.2 0)
			(layer "F.Fab")
			(hide yes)
			(effects
				(font
					(size 1 1)
					(thickness 0.15)
				)
			)
		)
		(property "MPN" "CR0402-FX-1000GLF"
			(at 471.8 225.2 0)
			(layer "F.Fab")
			(hide yes)
			(effects
				(font
					(size 1 1)
					(thickness 0.15)
				)
			)
		)
		(property "Manufacturer" "Bourns"
			(at 471.8 225.2 0)
			(layer "F.Fab")
			(hide yes)
			(effects
				(font
					(size 1 1)
					(thickness 0.15)
				)
			)
		)
		(property "Tolerance" "1%"
			(at 471.8 225.2 0)
			(layer "F.Fab")
			(hide yes)
			(effects
				(font
					(size 1 1)
					(thickness 0.15)
				)
			)
		)
		(property "Val" "100R"
			(at 471.8 225.2 0)
			(layer "F.Fab")
			(hide yes)
			(effects
				(font
					(size 1 1)
					(thickness 0.15)
				)
			)
		)
		(property "dnp" ""
			(at 471.8 225.2 0)
			(layer "F.Fab")
			(hide yes)
			(effects
				(font
					(size 1 1)
					(thickness 0.15)
				)
			)
		)
		(property "exclude_from_bom" ""
			(at 471.8 225.2 0)
			(layer "F.Fab")
			(hide yes)
			(effects
				(font
					(size 1 1)
					(thickness 0.15)
				)
			)
		)
		(sheetname "SPI Flash + SD Card")
		(sheetfile "spi-flash.kicad_sch")
		(attr smd exclude_from_bom)
		(fp_rect
			(start -0.925 -0.47)
			(end 0.925 0.47)
			(stroke
				(width 0.05)
				(type default)
			)
			(fill no)
			(layer "F.CrtYd")
		)
		(fp_rect
			(start -0.5 -0.25)
			(end 0.5 0.25)
			(stroke
				(width 0.15)
				(type solid)
			)
			(fill no)
			(layer "F.Fab")
		)
		(pad "1" smd roundrect
			(at -0.48 0 180)
			(size 0.59 0.64)
			(layers "F.Cu" "F.Mask" "F.Paste")
			(roundrect_rratio 0.25)
			(net 427 "/FPGA Bank 16 & 17/USR_FLASH_1.CLK")
			(pintype "passive")
		)
		(pad "2" smd roundrect
			(at 0.48 0 180)
			(size 0.59 0.64)
			(layers "F.Cu" "F.Mask" "F.Paste")
			(roundrect_rratio 0.25)
			(net 3 "VCC_USR_B")
			(pintype "passive")
		)
	)
	(footprint "antmicro-footprints:R_0402_1005Metric"
		(layer "F.Cu")
		(at 236 139 180)
		(descr "Resistor SMD 0402")
		(tags "resistor SMD 0402")
		(property "Reference" "R188"
			(at 1.9 -2.35 180)
			(layer "F.SilkS")
			(effects
				(font
					(size 0.7 0.7)
					(thickness 0.15)
				)
				(justify left bottom)
			)
		)
		(property "Value" "R_0R_0402"
			(at 0 1.4 180)
			(layer "F.Fab")
			(effects
				(font
					(size 0.7 0.7)
					(thickness 0.15)
				)
				(justify left bottom)
			)
		)
		(property "Description" "SMD Chip Resistor, Jumper, 0 ohm, 100 mW, 0402 [1005 Metric], Thick Film, General Purpose"
			(at 0 0 180)
			(layer "F.Fab")
			(hide yes)
			(effects
				(font
					(size 1.27 1.27)
					(thickness 0.15)
				)
			)
		)
		(property "Author" "Antmicro"
			(at 472 278 0)
			(layer "F.Fab")
			(hide yes)
			(effects
				(font
					(size 1 1)
					(thickness 0.15)
				)
			)
		)
		(property "Current" "1A"
			(at 472 278 0)
			(layer "F.Fab")
			(hide yes)
			(effects
				(font
					(size 1 1)
					(thickness 0.15)
				)
			)
		)
		(property "License" "Apache-2.0"
			(at 472 278 0)
			(layer "F.Fab")
			(hide yes)
			(effects
				(font
					(size 1 1)
					(thickness 0.15)
				)
			)
		)
		(property "MPN" "ERJ2GE0R00X"
			(at 472 278 0)
			(layer "F.Fab")
			(hide yes)
			(effects
				(font
					(size 1 1)
					(thickness 0.15)
				)
			)
		)
		(property "Manufacturer" "Panasonic"
			(at 472 278 0)
			(layer "F.Fab")
			(hide yes)
			(effects
				(font
					(size 1 1)
					(thickness 0.15)
				)
			)
		)
		(property "Tolerance" ""
			(at 472 278 0)
			(layer "F.Fab")
			(hide yes)
			(effects
				(font
					(size 1 1)
					(thickness 0.15)
				)
			)
		)
		(property "Val" "0R"
			(at 472 278 0)
			(layer "F.Fab")
			(hide yes)
			(effects
				(font
					(size 1 1)
					(thickness 0.15)
				)
			)
		)
		(sheetname "USB PHY")
		(sheetfile "usb-phy.kicad_sch")
		(attr smd)
		(fp_rect
			(start -0.925 -0.47)
			(end 0.925 0.47)
			(stroke
				(width 0.05)
				(type default)
			)
			(fill no)
			(layer "F.CrtYd")
		)
		(fp_rect
			(start -0.5 -0.25)
			(end 0.5 0.25)
			(stroke
				(width 0.15)
				(type solid)
			)
			(fill no)
			(layer "F.Fab")
		)
		(pad "1" smd roundrect
			(at -0.48 0 180)
			(size 0.59 0.64)
			(layers "F.Cu" "F.Mask" "F.Paste")
			(roundrect_rratio 0.25)
			(net 941 "/USB PHY/FTDI_SCL")
			(pintype "passive")
		)
		(pad "2" smd roundrect
			(at 0.48 0 180)
			(size 0.59 0.64)
			(layers "F.Cu" "F.Mask" "F.Paste")
			(roundrect_rratio 0.25)
			(net 1338 "/I2C.SCL")
			(pintype "passive")
		)
	)
	(footprint "antmicro-footprints:R_0402_1005Metric"
		(layer "F.Cu")
		(at 261.7 130.7)
		(descr "Resistor SMD 0402")
		(tags "resistor SMD 0402")
		(property "Reference" "R190"
			(at -1.4 1.55 180)
			(layer "F.SilkS")
			(effects
				(font
					(size 0.7 0.7)
					(thickness 0.15)
				)
				(justify left bottom)
			)
		)
		(property "Value" "R_10k_0402"
			(at 0 1.4 0)
			(layer "F.Fab")
			(effects
				(font
					(size 0.7 0.7)
					(thickness 0.15)
				)
				(justify left bottom)
			)
		)
		(property "Description" "SMD Chip Resistor, 10 kohm, ± 1%, 62.5 mW, 0402 [1005 Metric], Thick Film, General Purpose"
			(at 0 0 0)
			(layer "F.Fab")
			(hide yes)
			(effects
				(font
					(size 1.27 1.27)
					(thickness 0.15)
				)
			)
		)
		(property "Author" "Antmicro"
			(at 0 0 0)
			(layer "F.Fab")
			(hide yes)
			(effects
				(font
					(size 1 1)
					(thickness 0.15)
				)
			)
		)
		(property "License" "Apache-2.0"
			(at 0 0 0)
			(layer "F.Fab")
			(hide yes)
			(effects
				(font
					(size 1 1)
					(thickness 0.15)
				)
			)
		)
		(property "MPN" "CR0402-FX-1002GLF"
			(at 0 0 0)
			(layer "F.Fab")
			(hide yes)
			(effects
				(font
					(size 1 1)
					(thickness 0.15)
				)
			)
		)
		(property "Manufacturer" "Bourns"
			(at 0 0 0)
			(layer "F.Fab")
			(hide yes)
			(effects
				(font
					(size 1 1)
					(thickness 0.15)
				)
			)
		)
		(property "Tolerance" "1%"
			(at 0 0 0)
			(layer "F.Fab")
			(hide yes)
			(effects
				(font
					(size 1 1)
					(thickness 0.15)
				)
			)
		)
		(property "Val" "10k"
			(at 0 0 0)
			(layer "F.Fab")
			(hide yes)
			(effects
				(font
					(size 1 1)
					(thickness 0.15)
				)
			)
		)
		(sheetname "USB PHY")
		(sheetfile "usb-phy.kicad_sch")
		(attr smd)
		(fp_rect
			(start -0.925 -0.47)
			(end 0.925 0.47)
			(stroke
				(width 0.05)
				(type default)
			)
			(fill no)
			(layer "F.CrtYd")
		)
		(fp_rect
			(start -0.5 -0.25)
			(end 0.5 0.25)
			(stroke
				(width 0.15)
				(type solid)
			)
			(fill no)
			(layer "F.Fab")
		)
		(pad "1" smd roundrect
			(at -0.48 0)
			(size 0.59 0.64)
			(layers "F.Cu" "F.Mask" "F.Paste")
			(roundrect_rratio 0.25)
			(net 497 "/FPGA Bank 12 & 13/USB_USER.VDET")
			(pintype "passive")
		)
		(pad "2" smd roundrect
			(at 0.48 0)
			(size 0.59 0.64)
			(layers "F.Cu" "F.Mask" "F.Paste")
			(roundrect_rratio 0.25)
			(net 715 "/USB PHY/USB_USR_VBUS")
			(pintype "passive")
		)
	)
	(footprint "antmicro-footprints:LED_0603_1608Metric_G"
		(layer "F.Cu")
		(at 261.5 93.4)
		(descr "LED SMD 0603 Green")
		(tags "LED SMD 0603 Green")
		(property "Reference" "D22"
			(at -1 1.55 0)
			(layer "F.SilkS")
			(effects
				(font
					(size 0.7 0.7)
					(thickness 0.15)
				)
				(justify left bottom)
			)
		)
		(property "Value" "LED_G_0603_KP-1608CGCK"
			(at 0 1.6 0)
			(layer "F.Fab")
			(effects
				(font
					(size 0.7 0.7)
					(thickness 0.15)
				)
				(justify left bottom)
			)
		)
		(property "Description" "LED, Green, SMD, 0603, 20 mA, 2.1 V, 570 nm"
			(at 0 0 0)
			(layer "F.Fab")
			(hide yes)
			(effects
				(font
					(size 1.27 1.27)
					(thickness 0.15)
				)
			)
		)
		(property "Author" "Antmicro"
			(at 0 0 0)
			(layer "F.Fab")
			(hide yes)
			(effects
				(font
					(size 1 1)
					(thickness 0.15)
				)
			)
		)
		(property "Color" "Green"
			(at 0 0 0)
			(layer "F.Fab")
			(hide yes)
			(effects
				(font
					(size 1 1)
					(thickness 0.15)
				)
			)
		)
		(property "License" "Apache-2.0"
			(at 0 0 0)
			(layer "F.Fab")
			(hide yes)
			(effects
				(font
					(size 1 1)
					(thickness 0.15)
				)
			)
		)
		(property "MPN" "KP-1608CGCK"
			(at 0 0 0)
			(layer "F.Fab")
			(hide yes)
			(effects
				(font
					(size 1 1)
					(thickness 0.15)
				)
			)
		)
		(property "Manufacturer" "Kingbright"
			(at 0 0 0)
			(layer "F.Fab")
			(hide yes)
			(effects
				(font
					(size 1 1)
					(thickness 0.15)
				)
			)
		)
		(sheetname "User GPIO + LED + button + DIP switch")
		(sheetfile "user-gpio.kicad_sch")
		(attr smd)
		(fp_line
			(start -1.18 -0.319)
			(end -1.18 0.321)
			(stroke
				(width 0.15)
				(type solid)
			)
			(layer "F.SilkS")
		)
		(fp_line
			(start -0.094672 0.001008)
			(end -0.24 0.001008)
			(stroke
				(width 0.1)
				(type solid)
			)
			(layer "F.SilkS")
		)
		(fp_line
			(start -0.094672 0.001008)
			(end 0.105328 -0.198992)
			(stroke
				(width 0.1)
				(type solid)
			)
			(layer "F.SilkS")
		)
		(fp_line
			(start -0.094672 0.201008)
			(end -0.094672 -0.198992)
			(stroke
				(width 0.1)
				(type solid)
			)
			(layer "F.SilkS")
		)
		(fp_line
			(start 0.105328 0.001008)
			(end 0.24 0.001)
			(stroke
				(width 0.1)
				(type solid)
			)
			(layer "F.SilkS")
		)
		(fp_line
			(start 0.105328 0.201008)
			(end -0.094672 0.001008)
			(stroke
				(width 0.1)
				(type solid)
			)
			(layer "F.SilkS")
		)
		(fp_line
			(start 0.105328 0.201008)
			(end 0.105328 -0.198992)
			(stroke
				(width 0.1)
				(type solid)
			)
			(layer "F.SilkS")
		)
		(fp_line
			(start 0.22 -0.35)
			(end -0.22 -0.35)
			(stroke
				(width 0.15)
				(type solid)
			)
			(layer "F.SilkS")
		)
		(fp_line
			(start 0.22 0.35)
			(end -0.22 0.35)
			(stroke
				(width 0.15)
				(type solid)
			)
			(layer "F.SilkS")
		)
		(fp_rect
			(start 1.25 0.65)
			(end -1.25 -0.65)
			(stroke
				(width 0.05)
				(type solid)
			)
			(fill no)
			(layer "F.CrtYd")
		)
		(fp_line
			(start -0.199 -0.202)
			(end -0.199 0.1)
			(stroke
				(width 0.15)
				(type solid)
			)
			(layer "F.Fab")
		)
		(fp_line
			(start -0.199 0)
			(end -0.597 0)
			(stroke
				(width 0.15)
				(type solid)
			)
			(layer "F.Fab")
		)
		(fp_line
			(start -0.199 0.2)
			(end -0.199 0.1)
			(stroke
				(width 0.15)
				(type solid)
			)
			(layer "F.Fab")
		)
		(fp_line
			(start -0.101 0)
			(end 0.201 0.2)
			(stroke
				(width 0.15)
				(type solid)
			)
			(layer "F.Fab")
		)
		(fp_line
			(start 0.201 -0.202)
			(end -0.101 0)
			(stroke
				(width 0.15)
				(type solid)
			)
			(layer "F.Fab")
		)
		(fp_line
			(start 0.201 0)
			(end 0.201 -0.202)
			(stroke
				(width 0.15)
				(type solid)
			)
			(layer "F.Fab")
		)
		(fp_line
			(start 0.201 0.2)
			(end 0.201 0)
			(stroke
				(width 0.15)
				(type solid)
			)
			(layer "F.Fab")
		)
		(fp_line
			(start 0.599 0)
			(end 0.201 0)
			(stroke
				(width 0.15)
				(type solid)
			)
			(layer "F.Fab")
		)
		(fp_rect
			(start 0.848 0.4)
			(end -0.85 -0.402)
			(stroke
				(width 0.15)
				(type solid)
			)
			(fill no)
			(layer "F.Fab")
		)
		(pad "1" smd roundrect
			(at -0.7 0 180)
			(size 0.8 1)
			(layers "F.Cu" "F.Mask" "F.Paste")
			(roundrect_rratio 0.2)
			(net 27 "Net-(D22-C)")
			(pinfunction "C")
			(pintype "passive")
		)
		(pad "2" smd roundrect
			(at 0.7 0 180)
			(size 0.8 1)
			(layers "F.Cu" "F.Mask" "F.Paste")
			(roundrect_rratio 0.2)
			(net 783 "Net-(D22-A)")
			(pinfunction "A")
			(pintype "passive")
		)
	)
	(footprint "antmicro-footprints:C_0402_1005Metric"
		(layer "F.Cu")
		(at 199.253752 99.3615 90)
		(descr "Capacitor SMD 0402")
		(tags "capacitor SMD 0402")
		(property "Reference" "C290"
			(at -9.3385 5.546248 90)
			(layer "F.SilkS")
			(effects
				(font
					(size 0.7 0.7)
					(thickness 0.15)
				)
				(justify left bottom)
			)
		)
		(property "Value" "C_100n_0402"
			(at 0 1.169 90)
			(layer "F.Fab")
			(effects
				(font
					(size 0.7 0.7)
					(thickness 0.15)
				)
				(justify left bottom)
			)
		)
		(property "Description" "SMD Multilayer Ceramic Capacitor, 0.1 µF, 50 V, 0402 [1005 Metric], ± 10%, X5R, GRM Series"
			(at 0 0 90)
			(layer "F.Fab")
			(hide yes)
			(effects
				(font
					(size 1.27 1.27)
					(thickness 0.15)
				)
			)
		)
		(property "Author" "Antmicro"
			(at 298.615252 -99.892252 0)
			(layer "F.Fab")
			(hide yes)
			(effects
				(font
					(size 1 1)
					(thickness 0.15)
				)
			)
		)
		(property "Dielectric" "X5R"
			(at 298.615252 -99.892252 0)
			(layer "F.Fab")
			(hide yes)
			(effects
				(font
					(size 1 1)
					(thickness 0.15)
				)
			)
		)
		(property "License" "Apache-2.0"
			(at 298.615252 -99.892252 0)
			(layer "F.Fab")
			(hide yes)
			(effects
				(font
					(size 1 1)
					(thickness 0.15)
				)
			)
		)
		(property "MPN" "GRM155R61H104KE14D"
			(at 298.615252 -99.892252 0)
			(layer "F.Fab")
			(hide yes)
			(effects
				(font
					(size 1 1)
					(thickness 0.15)
				)
			)
		)
		(property "Manufacturer" "Murata"
			(at 298.615252 -99.892252 0)
			(layer "F.Fab")
			(hide yes)
			(effects
				(font
					(size 1 1)
					(thickness 0.15)
				)
			)
		)
		(property "Val" "100n"
			(at 298.615252 -99.892252 0)
			(layer "F.Fab")
			(hide yes)
			(effects
				(font
					(size 1 1)
					(thickness 0.15)
				)
			)
		)
		(property "Voltage" "50V"
			(at 298.615252 -99.892252 0)
			(layer "F.Fab")
			(hide yes)
			(effects
				(font
					(size 1 1)
					(thickness 0.15)
				)
			)
		)
		(sheetname "HDMI + Ethernet")
		(sheetfile "hdmi-ethernet.kicad_sch")
		(attr smd)
		(fp_rect
			(start -0.925 -0.47)
			(end 0.925 0.47)
			(stroke
				(width 0.05)
				(type default)
			)
			(fill no)
			(layer "F.CrtYd")
		)
		(fp_line
			(start 0.504 -0.25)
			(end 0.504 0.248)
			(stroke
				(width 0.15)
				(type solid)
			)
			(layer "F.Fab")
		)
		(fp_line
			(start -0.494 -0.25)
			(end 0.504 -0.25)
			(stroke
				(width 0.15)
				(type solid)
			)
			(layer "F.Fab")
		)
		(fp_line
			(start 0.504 0.248)
			(end -0.494 0.248)
			(stroke
				(width 0.15)
				(type solid)
			)
			(layer "F.Fab")
		)
		(fp_line
			(start -0.494 0.248)
			(end -0.494 -0.25)
			(stroke
				(width 0.15)
				(type solid)
			)
			(layer "F.Fab")
		)
		(pad "1" smd roundrect
			(at -0.48 0 90)
			(size 0.59 0.64)
			(layers "F.Cu" "F.Mask" "F.Paste")
			(roundrect_rratio 0.25)
			(net 1 "GND")
			(pintype "passive")
		)
		(pad "2" smd roundrect
			(at 0.48 0 90)
			(size 0.59 0.64)
			(layers "F.Cu" "F.Mask" "F.Paste")
			(roundrect_rratio 0.25)
			(net 727 "+1V2")
			(pintype "passive")
		)
	)
	(footprint "antmicro-footprints:C_0402_1005Metric"
		(layer "F.Cu")
		(at 173.570001 122.382501 180)
		(descr "Capacitor SMD 0402")
		(tags "capacitor SMD 0402")
		(property "Reference" "C313"
			(at -3.729999 -0.369999 0)
			(layer "F.SilkS")
			(effects
				(font
					(size 0.7 0.7)
					(thickness 0.15)
				)
				(justify right bottom)
			)
		)
		(property "Value" "C_100n_0402"
			(at 0 1.4 0)
			(layer "F.Fab")
			(effects
				(font
					(size 0.7 0.7)
					(thickness 0.15)
				)
				(justify right bottom)
			)
		)
		(property "Description" "SMD Multilayer Ceramic Capacitor, 0.1 µF, 50 V, 0402 [1005 Metric], ± 10%, X5R, GRM Series"
			(at 0 0 180)
			(layer "F.Fab")
			(hide yes)
			(effects
				(font
					(size 1.27 1.27)
					(thickness 0.15)
				)
			)
		)
		(property "Author" "Antmicro"
			(at 347.140002 244.765002 0)
			(layer "F.Fab")
			(hide yes)
			(effects
				(font
					(size 1 1)
					(thickness 0.15)
				)
			)
		)
		(property "Dielectric" "X5R"
			(at 347.140002 244.765002 0)
			(layer "F.Fab")
			(hide yes)
			(effects
				(font
					(size 1 1)
					(thickness 0.15)
				)
			)
		)
		(property "License" "Apache-2.0"
			(at 347.140002 244.765002 0)
			(layer "F.Fab")
			(hide yes)
			(effects
				(font
					(size 1 1)
					(thickness 0.15)
				)
			)
		)
		(property "MPN" "GRM155R61H104KE14D"
			(at 347.140002 244.765002 0)
			(layer "F.Fab")
			(hide yes)
			(effects
				(font
					(size 1 1)
					(thickness 0.15)
				)
			)
		)
		(property "Manufacturer" "Murata"
			(at 347.140002 244.765002 0)
			(layer "F.Fab")
			(hide yes)
			(effects
				(font
					(size 1 1)
					(thickness 0.15)
				)
			)
		)
		(property "Val" "100n"
			(at 347.140002 244.765002 0)
			(layer "F.Fab")
			(hide yes)
			(effects
				(font
					(size 1 1)
					(thickness 0.15)
				)
			)
		)
		(property "Voltage" "50V"
			(at 347.140002 244.765002 0)
			(layer "F.Fab")
			(hide yes)
			(effects
				(font
					(size 1 1)
					(thickness 0.15)
				)
			)
		)
		(sheetname "FMC+ HSPC")
		(sheetfile "fmc-hspc.kicad_sch")
		(attr smd)
		(fp_rect
			(start -0.925 -0.47)
			(end 0.925 0.47)
			(stroke
				(width 0.05)
				(type default)
			)
			(fill no)
			(layer "F.CrtYd")
		)
		(fp_line
			(start 0.504 0.248)
			(end -0.494 0.248)
			(stroke
				(width 0.15)
				(type solid)
			)
			(layer "F.Fab")
		)
		(fp_line
			(start 0.504 -0.25)
			(end 0.504 0.248)
			(stroke
				(width 0.15)
				(type solid)
			)
			(layer "F.Fab")
		)
		(fp_line
			(start -0.494 0.248)
			(end -0.494 -0.25)
			(stroke
				(width 0.15)
				(type solid)
			)
			(layer "F.Fab")
		)
		(fp_line
			(start -0.494 -0.25)
			(end 0.504 -0.25)
			(stroke
				(width 0.15)
				(type solid)
			)
			(layer "F.Fab")
		)
		(pad "1" smd roundrect
			(at -0.48 0 180)
			(size 0.59 0.64)
			(layers "F.Cu" "F.Mask" "F.Paste")
			(roundrect_rratio 0.25)
			(net 124 "/FMC+ HSPC/GTX115.TX0_N")
			(pintype "passive")
		)
		(pad "2" smd roundrect
			(at 0.48 0 180)
			(size 0.59 0.64)
			(layers "F.Cu" "F.Mask" "F.Paste")
			(roundrect_rratio 0.25)
			(net 123 "/FMC+ HSPC/GTX_TX7_C_N")
			(pintype "passive")
		)
	)
	(footprint "antmicro-footprints:C_0402_1005Metric"
		(layer "F.Cu")
		(at 196.1 166.249 180)
		(descr "Capacitor SMD 0402")
		(tags "capacitor SMD 0402")
		(property "Reference" "C354"
			(at -3.7 -0.151 0)
			(layer "F.SilkS")
			(effects
				(font
					(size 0.7 0.7)
					(thickness 0.15)
				)
				(justify right bottom)
			)
		)
		(property "Value" "C_22n_0402"
			(at 0 1.4 0)
			(layer "F.Fab")
			(effects
				(font
					(size 0.7 0.7)
					(thickness 0.15)
				)
				(justify right bottom)
			)
		)
		(property "Description" "SMD Multilayer Ceramic Capacitors, 0.022 µF, 50 V, 20%, 0402 [1005 Metric], X7R"
			(at 0 0 180)
			(layer "F.Fab")
			(hide yes)
			(effects
				(font
					(size 1.27 1.27)
					(thickness 0.15)
				)
			)
		)
		(property "Author" "Antmicro"
			(at 392.2 332.498 0)
			(layer "F.Fab")
			(hide yes)
			(effects
				(font
					(size 1 1)
					(thickness 0.15)
				)
			)
		)
		(property "Dielectric" ""
			(at 392.2 332.498 0)
			(layer "F.Fab")
			(hide yes)
			(effects
				(font
					(size 1 1)
					(thickness 0.15)
				)
			)
		)
		(property "License" "Apache-2.0"
			(at 392.2 332.498 0)
			(layer "F.Fab")
			(hide yes)
			(effects
				(font
					(size 1 1)
					(thickness 0.15)
				)
			)
		)
		(property "MPN" "GCM155R71H223MA55D"
			(at 392.2 332.498 0)
			(layer "F.Fab")
			(hide yes)
			(effects
				(font
					(size 1 1)
					(thickness 0.15)
				)
			)
		)
		(property "Manufacturer" "Murata"
			(at 392.2 332.498 0)
			(layer "F.Fab")
			(hide yes)
			(effects
				(font
					(size 1 1)
					(thickness 0.15)
				)
			)
		)
		(property "Val" "22n"
			(at 392.2 332.498 0)
			(layer "F.Fab")
			(hide yes)
			(effects
				(font
					(size 1 1)
					(thickness 0.15)
				)
			)
		)
		(property "Voltage" ""
			(at 392.2 332.498 0)
			(layer "F.Fab")
			(hide yes)
			(effects
				(font
					(size 1 1)
					(thickness 0.15)
				)
			)
		)
		(sheetname "DC-DC Converters")
		(sheetfile "dc-dc.kicad_sch")
		(attr smd)
		(fp_rect
			(start -0.925 -0.47)
			(end 0.925 0.47)
			(stroke
				(width 0.05)
				(type default)
			)
			(fill no)
			(layer "F.CrtYd")
		)
		(fp_line
			(start 0.504 0.248)
			(end -0.494 0.248)
			(stroke
				(width 0.15)
				(type solid)
			)
			(layer "F.Fab")
		)
		(fp_line
			(start 0.504 -0.25)
			(end 0.504 0.248)
			(stroke
				(width 0.15)
				(type solid)
			)
			(layer "F.Fab")
		)
		(fp_line
			(start -0.494 0.248)
			(end -0.494 -0.25)
			(stroke
				(width 0.15)
				(type solid)
			)
			(layer "F.Fab")
		)
		(fp_line
			(start -0.494 -0.25)
			(end 0.504 -0.25)
			(stroke
				(width 0.15)
				(type solid)
			)
			(layer "F.Fab")
		)
		(pad "1" smd roundrect
			(at -0.48 0 180)
			(size 0.59 0.64)
			(layers "F.Cu" "F.Mask" "F.Paste")
			(roundrect_rratio 0.25)
			(net 1 "GND")
			(pintype "passive")
		)
		(pad "2" smd roundrect
			(at 0.48 0 180)
			(size 0.59 0.64)
			(layers "F.Cu" "F.Mask" "F.Paste")
			(roundrect_rratio 0.25)
			(net 749 "/DC-DC Converters/1V0_SS")
			(pintype "passive")
		)
	)
	(footprint "antmicro-footprints:R_0402_1005Metric"
		(layer "F.Cu")
		(at 210.91 154.68 -90)
		(descr "Resistor SMD 0402")
		(tags "resistor SMD 0402")
		(property "Reference" "R65"
			(at -0.96 0.35 270)
			(layer "F.SilkS")
			(effects
				(font
					(size 0.7 0.7)
					(thickness 0.15)
				)
				(justify left bottom)
			)
		)
		(property "Value" "R_10k_0402"
			(at 0 1.4 270)
			(layer "F.Fab")
			(effects
				(font
					(size 0.7 0.7)
					(thickness 0.15)
				)
				(justify left bottom)
			)
		)
		(property "Description" "SMD Chip Resistor, 10 kohm, ± 1%, 62.5 mW, 0402 [1005 Metric], Thick Film, General Purpose"
			(at 0 0 270)
			(layer "F.Fab")
			(hide yes)
			(effects
				(font
					(size 1.27 1.27)
					(thickness 0.15)
				)
			)
		)
		(property "Author" "Antmicro"
			(at 56.23 365.59 0)
			(layer "F.Fab")
			(hide yes)
			(effects
				(font
					(size 1 1)
					(thickness 0.15)
				)
			)
		)
		(property "License" "Apache-2.0"
			(at 56.23 365.59 0)
			(layer "F.Fab")
			(hide yes)
			(effects
				(font
					(size 1 1)
					(thickness 0.15)
				)
			)
		)
		(property "MPN" "CR0402-FX-1002GLF"
			(at 56.23 365.59 0)
			(layer "F.Fab")
			(hide yes)
			(effects
				(font
					(size 1 1)
					(thickness 0.15)
				)
			)
		)
		(property "Manufacturer" "Bourns"
			(at 56.23 365.59 0)
			(layer "F.Fab")
			(hide yes)
			(effects
				(font
					(size 1 1)
					(thickness 0.15)
				)
			)
		)
		(property "Tolerance" "1%"
			(at 56.23 365.59 0)
			(layer "F.Fab")
			(hide yes)
			(effects
				(font
					(size 1 1)
					(thickness 0.15)
				)
			)
		)
		(property "Val" "10k"
			(at 56.23 365.59 0)
			(layer "F.Fab")
			(hide yes)
			(effects
				(font
					(size 1 1)
					(thickness 0.15)
				)
			)
		)
		(sheetname "SPI Flash + SD Card")
		(sheetfile "spi-flash.kicad_sch")
		(attr smd)
		(fp_rect
			(start -0.925 -0.47)
			(end 0.925 0.47)
			(stroke
				(width 0.05)
				(type default)
			)
			(fill no)
			(layer "F.CrtYd")
		)
		(fp_rect
			(start -0.5 -0.25)
			(end 0.5 0.25)
			(stroke
				(width 0.15)
				(type solid)
			)
			(fill no)
			(layer "F.Fab")
		)
		(pad "1" smd roundrect
			(at -0.48 0 270)
			(size 0.59 0.64)
			(layers "F.Cu" "F.Mask" "F.Paste")
			(roundrect_rratio 0.25)
			(net 402 "/FPGA Bank 33 & 34/USR_FLASH_0.DQ3")
			(pintype "passive")
		)
		(pad "2" smd roundrect
			(at 0.48 0 270)
			(size 0.59 0.64)
			(layers "F.Cu" "F.Mask" "F.Paste")
			(roundrect_rratio 0.25)
			(net 26 "+1V8")
			(pintype "passive")
		)
	)
	(footprint "antmicro-footprints:R_0402_1005Metric"
		(layer "F.Cu")
		(at 235.9 115.55 180)
		(descr "Resistor SMD 0402")
		(tags "resistor SMD 0402")
		(property "Reference" "R101"
			(at -0.8 -0.35 180)
			(layer "F.SilkS")
			(effects
				(font
					(size 0.7 0.7)
					(thickness 0.15)
				)
				(justify left bottom)
			)
		)
		(property "Value" "R_0R_0402"
			(at 0 1.4 180)
			(layer "F.Fab")
			(effects
				(font
					(size 0.7 0.7)
					(thickness 0.15)
				)
				(justify left bottom)
			)
		)
		(property "Description" "SMD Chip Resistor, Jumper, 0 ohm, 100 mW, 0402 [1005 Metric], Thick Film, General Purpose"
			(at 0 0 180)
			(layer "F.Fab")
			(hide yes)
			(effects
				(font
					(size 1.27 1.27)
					(thickness 0.15)
				)
			)
		)
		(property "Author" "Antmicro"
			(at 471.8 231.1 0)
			(layer "F.Fab")
			(hide yes)
			(effects
				(font
					(size 1 1)
					(thickness 0.15)
				)
			)
		)
		(property "Current" "1A"
			(at 471.8 231.1 0)
			(layer "F.Fab")
			(hide yes)
			(effects
				(font
					(size 1 1)
					(thickness 0.15)
				)
			)
		)
		(property "License" "Apache-2.0"
			(at 471.8 231.1 0)
			(layer "F.Fab")
			(hide yes)
			(effects
				(font
					(size 1 1)
					(thickness 0.15)
				)
			)
		)
		(property "MPN" "ERJ2GE0R00X"
			(at 471.8 231.1 0)
			(layer "F.Fab")
			(hide yes)
			(effects
				(font
					(size 1 1)
					(thickness 0.15)
				)
			)
		)
		(property "Manufacturer" "Panasonic"
			(at 471.8 231.1 0)
			(layer "F.Fab")
			(hide yes)
			(effects
				(font
					(size 1 1)
					(thickness 0.15)
				)
			)
		)
		(property "Tolerance" ""
			(at 471.8 231.1 0)
			(layer "F.Fab")
			(hide yes)
			(effects
				(font
					(size 1 1)
					(thickness 0.15)
				)
			)
		)
		(property "Val" "0R"
			(at 471.8 231.1 0)
			(layer "F.Fab")
			(hide yes)
			(effects
				(font
					(size 1 1)
					(thickness 0.15)
				)
			)
		)
		(sheetname "SPI Flash + SD Card")
		(sheetfile "spi-flash.kicad_sch")
		(attr smd)
		(fp_rect
			(start -0.925 -0.47)
			(end 0.925 0.47)
			(stroke
				(width 0.05)
				(type default)
			)
			(fill no)
			(layer "F.CrtYd")
		)
		(fp_rect
			(start -0.5 -0.25)
			(end 0.5 0.25)
			(stroke
				(width 0.15)
				(type solid)
			)
			(fill no)
			(layer "F.Fab")
		)
		(pad "1" smd roundrect
			(at -0.48 0 180)
			(size 0.59 0.64)
			(layers "F.Cu" "F.Mask" "F.Paste")
			(roundrect_rratio 0.25)
			(net 429 "/FPGA Bank 16 & 17/USR_FLASH_1.DQ0")
			(pintype "passive")
		)
		(pad "2" smd roundrect
			(at 0.48 0 180)
			(size 0.59 0.64)
			(layers "F.Cu" "F.Mask" "F.Paste")
			(roundrect_rratio 0.25)
			(net 908 "/SPI Flash + SD Card/USR_FLASH_1_DQ0")
			(pintype "passive")
		)
	)
	(footprint "antmicro-footprints:PinHeader_2x3_P2.54mm_SMD"
		(layer "F.Cu")
		(at 212.7 96.9)
		(property "Reference" "J19"
			(at 3.6 3.45 180)
			(layer "F.SilkS")
			(effects
				(font
					(size 0.7 0.7)
					(thickness 0.15)
				)
				(justify left bottom)
			)
		)
		(property "Value" "PinHeader_2x3_P2.54mm_SMD"
			(at 5.31 10.794 90)
			(layer "F.Fab")
			(effects
				(font
					(size 0.7 0.7)
					(thickness 0.15)
				)
				(justify left bottom)
			)
		)
		(property "Author" "Antmicro"
			(at 0 0 0)
			(layer "F.Fab")
			(hide yes)
			(effects
				(font
					(size 1 1)
					(thickness 0.15)
				)
			)
		)
		(property "License" "Apache-2.0"
			(at 0 0 0)
			(layer "F.Fab")
			(hide yes)
			(effects
				(font
					(size 1 1)
					(thickness 0.15)
				)
			)
		)
		(property "MPN" "15910060"
			(at 0 0 0)
			(layer "F.Fab")
			(hide yes)
			(effects
				(font
					(size 1 1)
					(thickness 0.15)
				)
			)
		)
		(property "Manufacturer" "Molex"
			(at 0 0 0)
			(layer "F.Fab")
			(hide yes)
			(effects
				(font
					(size 1 1)
					(thickness 0.15)
				)
			)
		)
		(sheetname "FPGA supply")
		(sheetfile "fpga-supply.kicad_sch")
		(attr smd)
		(fp_line
			(start -3.809 -2.555)
			(end -3.269 -2.555)
			(stroke
				(width 0.15)
				(type solid)
			)
			(layer "F.SilkS")
		)
		(fp_line
			(start -3.809 2.521)
			(end -3.809 -2.555)
			(stroke
				(width 0.15)
				(type solid)
			)
			(layer "F.SilkS")
		)
		(fp_line
			(start -3.809 2.521)
			(end -3.269 2.521)
			(stroke
				(width 0.15)
				(type solid)
			)
			(layer "F.SilkS")
		)
		(fp_line
			(start 3.81 -2.555)
			(end 3.27 -2.555)
			(stroke
				(width 0.15)
				(type solid)
			)
			(layer "F.SilkS")
		)
		(fp_line
			(start 3.81 -2.555)
			(end 3.81 2.521)
			(stroke
				(width 0.15)
				(type solid)
			)
			(layer "F.SilkS")
		)
		(fp_line
			(start 3.81 2.521)
			(end 3.27 2.521)
			(stroke
				(width 0.15)
				(type solid)
			)
			(layer "F.SilkS")
		)
		(fp_circle
			(center -3.45 2.95)
			(end -3.397 2.95)
			(stroke
				(width 0.15)
				(type solid)
			)
			(fill yes)
			(layer "F.SilkS")
		)
		(fp_rect
			(start -4.31 -4.103)
			(end 4.309 4.101)
			(stroke
				(width 0.05)
				(type solid)
			)
			(fill no)
			(layer "F.CrtYd")
		)
		(fp_line
			(start -3.81 3.29)
			(end -3.61 3.49)
			(stroke
				(width 0.15)
				(type solid)
			)
			(layer "F.Fab")
		)
		(fp_rect
			(start -3.81 -3.493)
			(end 3.809 3.491)
			(stroke
				(width 0.15)
				(type solid)
			)
			(fill no)
			(layer "F.Fab")
		)
		(pad "1" smd rect
			(at -2.539 2.2)
			(size 1.27 3.68)
			(layers "F.Cu" "F.Mask" "F.Paste")
			(net 2 "VCC_USR_A")
			(pintype "passive")
		)
		(pad "2" smd rect
			(at -2.539 -2.2 180)
			(size 1.27 3.68)
			(layers "F.Cu" "F.Mask" "F.Paste")
			(net 24 "+3V3")
			(pintype "passive")
		)
		(pad "3" smd rect
			(at 0 2.2)
			(size 1.27 3.68)
			(layers "F.Cu" "F.Mask" "F.Paste")
			(net 26 "+1V8")
			(pintype "passive")
		)
		(pad "4" smd rect
			(at 0 -2.2 180)
			(size 1.27 3.68)
			(layers "F.Cu" "F.Mask" "F.Paste")
			(net 2 "VCC_USR_A")
			(pintype "passive")
		)
		(pad "5" smd rect
			(at 2.539 2.2)
			(size 1.27 3.68)
			(layers "F.Cu" "F.Mask" "F.Paste")
			(net 2 "VCC_USR_A")
			(pintype "passive")
		)
		(pad "6" smd rect
			(at 2.539 -2.2 180)
			(size 1.27 3.68)
			(layers "F.Cu" "F.Mask" "F.Paste")
			(net 727 "+1V2")
			(pintype "passive")
		)
	)
	(footprint "antmicro-footprints:TSSOP-20_W4.4mm"
		(layer "F.Cu")
		(at 224.2 139.3 90)
		(descr "http://www.ti.com/lit/ds/symlink/txb0108.pdf")
		(property "Reference" "U42"
			(at -4.25 -1.1 180)
			(layer "F.SilkS")
			(effects
				(font
					(size 0.7 0.7)
					(thickness 0.15)
				)
				(justify left bottom)
			)
		)
		(property "Value" "CDCE906PWR"
			(at -5.33 4.57 90)
			(layer "F.Fab")
			(effects
				(font
					(size 0.7 0.7)
					(thickness 0.15)
				)
				(justify left bottom)
			)
		)
		(property "Description" "Clock generator/frequency synthesizer (PLL)"
			(at 0 0 90)
			(layer "F.Fab")
			(hide yes)
			(effects
				(font
					(size 1.27 1.27)
					(thickness 0.15)
				)
			)
		)
		(property "Author" "Antmicro"
			(at 363.5 -84.9 0)
			(layer "F.Fab")
			(hide yes)
			(effects
				(font
					(size 1 1)
					(thickness 0.15)
				)
			)
		)
		(property "License" "Apache-2.0"
			(at 363.5 -84.9 0)
			(layer "F.Fab")
			(hide yes)
			(effects
				(font
					(size 1 1)
					(thickness 0.15)
				)
			)
		)
		(property "MPN" "CDCE906PWR"
			(at 363.5 -84.9 0)
			(layer "F.Fab")
			(hide yes)
			(effects
				(font
					(size 1 1)
					(thickness 0.15)
				)
			)
		)
		(property "Manufacturer" "Texas Instruments"
			(at 363.5 -84.9 0)
			(layer "F.Fab")
			(hide yes)
			(effects
				(font
					(size 1 1)
					(thickness 0.15)
				)
			)
		)
		(sheetname "Clocks")
		(sheetfile "clocks.kicad_sch")
		(attr smd)
		(fp_line
			(start 3.499 -2.4)
			(end 3.499 -2.101)
			(stroke
				(width 0.15)
				(type solid)
			)
			(layer "F.SilkS")
		)
		(fp_line
			(start 3.2 -2.4)
			(end 3.499 -2.4)
			(stroke
				(width 0.15)
				(type solid)
			)
			(layer "F.SilkS")
		)
		(fp_line
			(start -3.202 -2.4)
			(end -3.5 -2.4)
			(stroke
				(width 0.15)
				(type solid)
			)
			(layer "F.SilkS")
		)
		(fp_line
			(start -3.5 -2.4)
			(end -3.5 -2.101)
			(stroke
				(width 0.15)
				(type solid)
			)
			(layer "F.SilkS")
		)
		(fp_line
			(start -3.49 1.825)
			(end -3.49 2.215)
			(stroke
				(width 0.15)
				(type solid)
			)
			(layer "F.SilkS")
		)
		(fp_line
			(start -3.49 2.215)
			(end -3.28 2.425)
			(stroke
				(width 0.15)
				(type solid)
			)
			(layer "F.SilkS")
		)
		(fp_line
			(start 3.499 2.398)
			(end 3.499 2.1)
			(stroke
				(width 0.15)
				(type solid)
			)
			(layer "F.SilkS")
		)
		(fp_line
			(start 3.499 2.398)
			(end 3.2 2.398)
			(stroke
				(width 0.15)
				(type solid)
			)
			(layer "F.SilkS")
		)
		(fp_line
			(start -3.28 2.815)
			(end -3.28 2.425)
			(stroke
				(width 0.15)
				(type solid)
			)
			(layer "F.SilkS")
		)
		(fp_circle
			(center -3.41 3.34)
			(end -3.36 3.34)
			(stroke
				(width 0.15)
				(type solid)
			)
			(fill yes)
			(layer "F.SilkS")
		)
		(fp_rect
			(start -3.75 -3.709)
			(end 3.749 3.706)
			(stroke
				(width 0.05)
				(type solid)
			)
			(fill no)
			(layer "F.CrtYd")
		)
		(fp_line
			(start 3.249 -2.202)
			(end 3.249 2.2)
			(stroke
				(width 0.15)
				(type solid)
			)
			(layer "F.Fab")
		)
		(fp_line
			(start -3.25 -2.202)
			(end 3.249 -2.202)
			(stroke
				(width 0.15)
				(type solid)
			)
			(layer "F.Fab")
		)
		(fp_line
			(start -3.25 -2.202)
			(end -3.25 1.729)
			(stroke
				(width 0.15)
				(type solid)
			)
			(layer "F.Fab")
		)
		(fp_line
			(start -3.242 1.739)
			(end -2.742 2.2)
			(stroke
				(width 0.15)
				(type solid)
			)
			(layer "F.Fab")
		)
		(fp_line
			(start 3.249 2.2)
			(end -2.73 2.2)
			(stroke
				(width 0.15)
				(type solid)
			)
			(layer "F.Fab")
		)
		(pad "1" smd rect
			(at -2.926 2.797 90)
			(size 0.3 1.6)
			(layers "F.Cu" "F.Mask" "F.Paste")
			(net 1387 "/SUP_MCU.PG_3V3")
			(pinfunction "S0/A0/CLK_SEL")
			(pintype "input")
			(solder_mask_margin 0.07)
		)
		(pad "2" smd rect
			(at -2.275 2.797 90)
			(size 0.3 1.6)
			(layers "F.Cu" "F.Mask" "F.Paste")
			(net 1407 "unconnected-(U42-S1{slash}A1-Pad2)")
			(pinfunction "S1/A1")
			(pintype "input+no_connect")
			(solder_mask_margin 0.07)
		)
		(pad "3" smd rect
			(at -1.625 2.797 90)
			(size 0.3 1.6)
			(layers "F.Cu" "F.Mask" "F.Paste")
			(net 1231 "Net-(C366-Pad2)")
			(pinfunction "VCC")
			(pintype "power_in")
			(solder_mask_margin 0.07)
		)
		(pad "4" smd rect
			(at -0.975 2.797 90)
			(size 0.3 1.6)
			(layers "F.Cu" "F.Mask" "F.Paste")
			(net 1 "GND")
			(pinfunction "GND")
			(pintype "passive")
			(solder_mask_margin 0.07)
		)
		(pad "5" smd rect
			(at -0.328 2.797 90)
			(size 0.3 1.6)
			(layers "F.Cu" "F.Mask" "F.Paste")
			(net 752 "/Clocks/PLL_XI")
			(pinfunction "CLK_IN0")
			(pintype "input")
			(solder_mask_margin 0.07)
		)
		(pad "6" smd rect
			(at 0.325 2.797 90)
			(size 0.3 1.6)
			(layers "F.Cu" "F.Mask" "F.Paste")
			(net 753 "/Clocks/PLL_XO")
			(pinfunction "CLK_IN1")
			(pintype "input")
			(solder_mask_margin 0.07)
		)
		(pad "7" smd rect
			(at 0.972 2.797 90)
			(size 0.3 1.6)
			(layers "F.Cu" "F.Mask" "F.Paste")
			(net 1231 "Net-(C366-Pad2)")
			(pinfunction "VCC")
			(pintype "passive")
			(solder_mask_margin 0.07)
		)
		(pad "8" smd rect
			(at 1.624 2.797 90)
			(size 0.3 1.6)
			(layers "F.Cu" "F.Mask" "F.Paste")
			(net 1 "GND")
			(pinfunction "GND")
			(pintype "passive")
			(solder_mask_margin 0.07)
		)
		(pad "9" smd rect
			(at 2.273 2.797 90)
			(size 0.3 1.6)
			(layers "F.Cu" "F.Mask" "F.Paste")
			(net 1336 "/I2C.SDA")
			(pinfunction "SDA")
			(pintype "bidirectional")
			(solder_mask_margin 0.07)
		)
		(pad "10" smd rect
			(at 2.922 2.797 90)
			(size 0.3 1.6)
			(layers "F.Cu" "F.Mask" "F.Paste")
			(net 1338 "/I2C.SCL")
			(pinfunction "SCK")
			(pintype "bidirectional")
			(solder_mask_margin 0.07)
		)
		(pad "11" smd rect
			(at 2.922 -2.801 90)
			(size 0.3 1.6)
			(layers "F.Cu" "F.Mask" "F.Paste")
			(net 971 "/Clocks/PLL_Y0")
			(pinfunction "Y0")
			(pintype "tri_state")
			(solder_mask_margin 0.07)
		)
		(pad "12" smd rect
			(at 2.273 -2.801 90)
			(size 0.3 1.6)
			(layers "F.Cu" "F.Mask" "F.Paste")
			(net 972 "/Clocks/PLL_Y1")
			(pinfunction "Y1")
			(pintype "tri_state")
			(solder_mask_margin 0.07)
		)
		(pad "13" smd rect
			(at 1.624 -2.801 90)
			(size 0.3 1.6)
			(layers "F.Cu" "F.Mask" "F.Paste")
			(net 1 "GND")
			(pinfunction "GND")
			(pintype "passive")
			(solder_mask_margin 0.07)
		)
		(pad "14" smd rect
			(at 0.972 -2.801 90)
			(size 0.3 1.6)
			(layers "F.Cu" "F.Mask" "F.Paste")
			(net 24 "+3V3")
			(pinfunction "VCCOUT1")
			(pintype "power_in")
			(solder_mask_margin 0.07)
		)
		(pad "15" smd rect
			(at 0.325 -2.801 90)
			(size 0.3 1.6)
			(layers "F.Cu" "F.Mask" "F.Paste")
			(net 1408 "unconnected-(U42-Y2-Pad15)")
			(pinfunction "Y2")
			(pintype "tri_state+no_connect")
			(solder_mask_margin 0.07)
		)
		(pad "16" smd rect
			(at -0.328 -2.801 90)
			(size 0.3 1.6)
			(layers "F.Cu" "F.Mask" "F.Paste")
			(net 1409 "unconnected-(U42-Y3-Pad16)")
			(pinfunction "Y3")
			(pintype "tri_state+no_connect")
			(solder_mask_margin 0.07)
		)
		(pad "17" smd rect
			(at -0.975 -2.801 90)
			(size 0.3 1.6)
			(layers "F.Cu" "F.Mask" "F.Paste")
			(net 1 "GND")
			(pinfunction "GND")
			(pintype "passive")
			(solder_mask_margin 0.07)
		)
		(pad "18" smd rect
			(at -1.625 -2.801 90)
			(size 0.3 1.6)
			(layers "F.Cu" "F.Mask" "F.Paste")
			(net 24 "+3V3")
			(pinfunction "VCCOUT2")
			(pintype "power_in")
			(solder_mask_margin 0.07)
		)
		(pad "19" smd rect
			(at -2.275 -2.801 90)
			(size 0.3 1.6)
			(layers "F.Cu" "F.Mask" "F.Paste")
			(net 973 "/Clocks/PLL_Y4")
			(pinfunction "Y4")
			(pintype "tri_state")
			(solder_mask_margin 0.07)
		)
		(pad "20" smd rect
			(at -2.926 -2.801 90)
			(size 0.3 1.6)
			(layers "F.Cu" "F.Mask" "F.Paste")
			(net 1410 "unconnected-(U42-Y5-Pad20)")
			(pinfunction "Y5")
			(pintype "tri_state+no_connect")
			(solder_mask_margin 0.07)
		)
	)
	(footprint "antmicro-footprints:C_0603_1608Metric"
		(layer "F.Cu")
		(at 160.55 165.55)
		(descr "Capacitor SMD 0603")
		(tags "capacitor 0603")
		(property "Reference" "C323"
			(at 0.95 0.4 0)
			(layer "F.SilkS")
			(effects
				(font
					(size 0.7 0.7)
					(thickness 0.15)
				)
				(justify left bottom)
			)
		)
		(property "Value" "C_22u_0603"
			(at 0 1.6 0)
			(layer "F.Fab")
			(effects
				(font
					(size 0.7 0.7)
					(thickness 0.15)
				)
				(justify left bottom)
			)
		)
		(property "Description" "SMD Multilayer Ceramic Capacitor, 22 µF, 6.3 V, 0603 [1608 Metric], ± 20%, X5R, GRM Series"
			(at 0 0 0)
			(layer "F.Fab")
			(hide yes)
			(effects
				(font
					(size 1.27 1.27)
					(thickness 0.15)
				)
			)
		)
		(property "Author" "Antmicro"
			(at 0 0 0)
			(layer "F.Fab")
			(hide yes)
			(effects
				(font
					(size 1 1)
					(thickness 0.15)
				)
			)
		)
		(property "Dielectric" ""
			(at 0 0 0)
			(layer "F.Fab")
			(hide yes)
			(effects
				(font
					(size 1 1)
					(thickness 0.15)
				)
			)
		)
		(property "License" "Apache-2.0"
			(at 0 0 0)
			(layer "F.Fab")
			(hide yes)
			(effects
				(font
					(size 1 1)
					(thickness 0.15)
				)
			)
		)
		(property "MPN" "GRM188R60J226MEA0D"
			(at 0 0 0)
			(layer "F.Fab")
			(hide yes)
			(effects
				(font
					(size 1 1)
					(thickness 0.15)
				)
			)
		)
		(property "Manufacturer" "Murata"
			(at 0 0 0)
			(layer "F.Fab")
			(hide yes)
			(effects
				(font
					(size 1 1)
					(thickness 0.15)
				)
			)
		)
		(property "Val" "22u"
			(at 0 0 0)
			(layer "F.Fab")
			(hide yes)
			(effects
				(font
					(size 1 1)
					(thickness 0.15)
				)
			)
		)
		(property "Voltage" ""
			(at 0 0 0)
			(layer "F.Fab")
			(hide yes)
			(effects
				(font
					(size 1 1)
					(thickness 0.15)
				)
			)
		)
		(sheetname "DC-DC Converters")
		(sheetfile "dc-dc.kicad_sch")
		(attr smd)
		(fp_line
			(start -0.15 -0.4)
			(end 0.15 -0.4)
			(stroke
				(width 0.15)
				(type solid)
			)
			(layer "F.SilkS")
		)
		(fp_line
			(start -0.15 0.4)
			(end 0.15 0.4)
			(stroke
				(width 0.15)
				(type solid)
			)
			(layer "F.SilkS")
		)
		(fp_rect
			(start -1.25 -0.65)
			(end 1.25 0.65)
			(stroke
				(width 0.05)
				(type solid)
			)
			(fill no)
			(layer "F.CrtYd")
		)
		(fp_rect
			(start -0.8 -0.4)
			(end 0.8 0.4)
			(stroke
				(width 0.15)
				(type solid)
			)
			(fill no)
			(layer "F.Fab")
		)
		(pad "1" smd roundrect
			(at -0.7 0)
			(size 0.8 1)
			(layers "F.Cu" "F.Mask" "F.Paste")
			(roundrect_rratio 0.2)
			(net 1 "GND")
			(pintype "passive")
		)
		(pad "2" smd roundrect
			(at 0.7 0)
			(size 0.8 1)
			(layers "F.Cu" "F.Mask" "F.Paste")
			(roundrect_rratio 0.2)
			(net 734 "/DC-DC Converters/1V8_local")
			(pintype "passive")
		)
	)
	(footprint "antmicro-footprints:TSOT23-6"
		(layer "F.Cu")
		(at 252.999 98.5 180)
		(property "Reference" "U30"
			(at -2.951 1.15 90)
			(layer "F.SilkS")
			(effects
				(font
					(size 0.7 0.7)
					(thickness 0.15)
				)
				(justify right bottom)
			)
		)
		(property "Value" "AP22615A_TSOT26"
			(at 0 2.6 0)
			(layer "F.Fab")
			(effects
				(font
					(size 0.7 0.7)
					(thickness 0.15)
				)
				(justify right bottom)
			)
		)
		(property "Description" "Power Load Distribution Switch, High Side, Active High, 1 Output, 5.5 V, 3.6 A, 0.04 ohm, TSOT-26-6"
			(at 0 0 180)
			(layer "F.Fab")
			(hide yes)
			(effects
				(font
					(size 1.27 1.27)
					(thickness 0.15)
				)
			)
		)
		(property "Author" "Antmicro"
			(at 505.998 197 0)
			(layer "F.Fab")
			(hide yes)
			(effects
				(font
					(size 1 1)
					(thickness 0.15)
				)
			)
		)
		(property "License" "Apache-2.0"
			(at 505.998 197 0)
			(layer "F.Fab")
			(hide yes)
			(effects
				(font
					(size 1 1)
					(thickness 0.15)
				)
			)
		)
		(property "MPN" "AP22615AWU-7"
			(at 505.998 197 0)
			(layer "F.Fab")
			(hide yes)
			(effects
				(font
					(size 1 1)
					(thickness 0.15)
				)
			)
		)
		(property "Manufacturer" "Diodes Incorporated"
			(at 505.998 197 0)
			(layer "F.Fab")
			(hide yes)
			(effects
				(font
					(size 1 1)
					(thickness 0.15)
				)
			)
		)
		(sheetname "USB PHY")
		(sheetfile "usb-phy.kicad_sch")
		(attr smd)
		(fp_line
			(start 1 1.55)
			(end 1 1.4)
			(stroke
				(width 0.15)
				(type solid)
			)
			(layer "F.SilkS")
		)
		(fp_line
			(start 1 1.55)
			(end -1 1.55)
			(stroke
				(width 0.15)
				(type solid)
			)
			(layer "F.SilkS")
		)
		(fp_line
			(start 1 -1.497)
			(end 1 -1.375)
			(stroke
				(width 0.15)
				(type solid)
			)
			(layer "F.SilkS")
		)
		(fp_line
			(start 1 -1.497)
			(end -1 -1.5)
			(stroke
				(width 0.15)
				(type solid)
			)
			(layer "F.SilkS")
		)
		(fp_line
			(start -1 1.55)
			(end -1 1.4)
			(stroke
				(width 0.15)
				(type solid)
			)
			(layer "F.SilkS")
		)
		(fp_line
			(start -1 -1.5)
			(end -1 -1.375)
			(stroke
				(width 0.15)
				(type solid)
			)
			(layer "F.SilkS")
		)
		(fp_circle
			(center -1.44 -1.5)
			(end -1.39 -1.5)
			(stroke
				(width 0.15)
				(type solid)
			)
			(fill yes)
			(layer "F.SilkS")
		)
		(fp_rect
			(start 1.93 -1.7)
			(end -1.93 1.7)
			(stroke
				(width 0.05)
				(type solid)
			)
			(fill no)
			(layer "F.CrtYd")
		)
		(fp_line
			(start -0.45 -1.521)
			(end -0.876 -1.096)
			(stroke
				(width 0.15)
				(type solid)
			)
			(layer "F.Fab")
		)
		(fp_rect
			(start 0.875 1.528)
			(end -0.875 -1.525)
			(stroke
				(width 0.15)
				(type solid)
			)
			(fill no)
			(layer "F.Fab")
		)
		(pad "1" smd rect
			(at -1.301 -0.947 90)
			(size 0.7 1.2)
			(layers "F.Cu" "F.Mask" "F.Paste")
			(net 705 "/USB PHY/USB_HOST_VBUS")
			(pinfunction "OUT")
			(pintype "power_out")
		)
		(pad "2" smd rect
			(at -1.301 0.004 90)
			(size 0.7 1.2)
			(layers "F.Cu" "F.Mask" "F.Paste")
			(net 1 "GND")
			(pinfunction "GND")
			(pintype "power_in")
		)
		(pad "3" smd rect
			(at -1.301 0.954 90)
			(size 0.7 1.2)
			(layers "F.Cu" "F.Mask" "F.Paste")
			(net 637 "/USB PHY/USB_HOST_VBUS_FLG")
			(pinfunction "FLG")
			(pintype "output")
		)
		(pad "4" smd rect
			(at 1.299 0.954 90)
			(size 0.7 1.2)
			(layers "F.Cu" "F.Mask" "F.Paste")
			(net 583 "/USB PHY/USB_HOST_VBUS_EN")
			(pinfunction "EN")
			(pintype "input")
		)
		(pad "5" smd rect
			(at 1.299 0.004 90)
			(size 0.7 1.2)
			(layers "F.Cu" "F.Mask" "F.Paste")
			(net 382 "Net-(U30-ISET)")
			(pinfunction "ISET")
			(pintype "passive")
		)
		(pad "6" smd rect
			(at 1.299 -0.947 90)
			(size 0.7 1.2)
			(layers "F.Cu" "F.Mask" "F.Paste")
			(net 703 "+5V")
			(pinfunction "IN")
			(pintype "power_in")
		)
	)
	(footprint "antmicro-footprints:C_0402_1005Metric"
		(layer "F.Cu")
		(at 220.8 158.95 180)
		(descr "Capacitor SMD 0402")
		(tags "capacitor SMD 0402")
		(property "Reference" "C165"
			(at 0.75 0.55 0)
			(layer "F.SilkS")
			(effects
				(font
					(size 0.7 0.7)
					(thickness 0.15)
				)
				(justify right bottom)
			)
		)
		(property "Value" "C_2n2_0402"
			(at 0 1.4 0)
			(layer "F.Fab")
			(effects
				(font
					(size 0.7 0.7)
					(thickness 0.15)
				)
				(justify right bottom)
			)
		)
		(property "Description" "SMD Multilayer Ceramic Capacitor, 2200 pF, 50 V, 0402 [1005 Metric], ± 5%, X7R, C Series KEMET"
			(at 0 0 180)
			(layer "F.Fab")
			(hide yes)
			(effects
				(font
					(size 1.27 1.27)
					(thickness 0.15)
				)
			)
		)
		(property "Author" "Antmicro"
			(at 441.6 317.9 0)
			(layer "F.Fab")
			(hide yes)
			(effects
				(font
					(size 1 1)
					(thickness 0.15)
				)
			)
		)
		(property "Dielectric" ""
			(at 441.6 317.9 0)
			(layer "F.Fab")
			(hide yes)
			(effects
				(font
					(size 1 1)
					(thickness 0.15)
				)
			)
		)
		(property "License" "Apache-2.0"
			(at 441.6 317.9 0)
			(layer "F.Fab")
			(hide yes)
			(effects
				(font
					(size 1 1)
					(thickness 0.15)
				)
			)
		)
		(property "MPN" "C0402C222J5RACTU"
			(at 441.6 317.9 0)
			(layer "F.Fab")
			(hide yes)
			(effects
				(font
					(size 1 1)
					(thickness 0.15)
				)
			)
		)
		(property "Manufacturer" "KEMET"
			(at 441.6 317.9 0)
			(layer "F.Fab")
			(hide yes)
			(effects
				(font
					(size 1 1)
					(thickness 0.15)
				)
			)
		)
		(property "Val" "2n2"
			(at 441.6 317.9 0)
			(layer "F.Fab")
			(hide yes)
			(effects
				(font
					(size 1 1)
					(thickness 0.15)
				)
			)
		)
		(property "Voltage" ""
			(at 441.6 317.9 0)
			(layer "F.Fab")
			(hide yes)
			(effects
				(font
					(size 1 1)
					(thickness 0.15)
				)
			)
		)
		(sheetname "FPGA Config")
		(sheetfile "fpga-config.kicad_sch")
		(attr smd)
		(fp_rect
			(start -0.925 -0.47)
			(end 0.925 0.47)
			(stroke
				(width 0.05)
				(type default)
			)
			(fill no)
			(layer "F.CrtYd")
		)
		(fp_line
			(start 0.504 0.248)
			(end -0.494 0.248)
			(stroke
				(width 0.15)
				(type solid)
			)
			(layer "F.Fab")
		)
		(fp_line
			(start 0.504 -0.25)
			(end 0.504 0.248)
			(stroke
				(width 0.15)
				(type solid)
			)
			(layer "F.Fab")
		)
		(fp_line
			(start -0.494 0.248)
			(end -0.494 -0.25)
			(stroke
				(width 0.15)
				(type solid)
			)
			(layer "F.Fab")
		)
		(fp_line
			(start -0.494 -0.25)
			(end 0.504 -0.25)
			(stroke
				(width 0.15)
				(type solid)
			)
			(layer "F.Fab")
		)
		(pad "1" smd roundrect
			(at -0.48 0 180)
			(size 0.59 0.64)
			(layers "F.Cu" "F.Mask" "F.Paste")
			(roundrect_rratio 0.25)
			(net 9 "/FPGA Config/FPGA_CFG_DXN")
			(pintype "passive")
		)
		(pad "2" smd roundrect
			(at 0.48 0 180)
			(size 0.59 0.64)
			(layers "F.Cu" "F.Mask" "F.Paste")
			(roundrect_rratio 0.25)
			(net 10 "/FPGA Config/FPGA_CFG_DXP")
			(pintype "passive")
		)
	)
	(footprint "antmicro-footprints:C_0603_1608Metric"
		(layer "F.Cu")
		(at 195.6 155.349)
		(descr "Capacitor SMD 0603")
		(tags "capacitor 0603")
		(property "Reference" "C360"
			(at -3.85 0.351 0)
			(layer "F.SilkS")
			(effects
				(font
					(size 0.7 0.7)
					(thickness 0.15)
				)
				(justify left bottom)
			)
		)
		(property "Value" "C_22u_0603"
			(at 0 1.6 0)
			(layer "F.Fab")
			(effects
				(font
					(size 0.7 0.7)
					(thickness 0.15)
				)
				(justify left bottom)
			)
		)
		(property "Description" "SMD Multilayer Ceramic Capacitor, 22 µF, 6.3 V, 0603 [1608 Metric], ± 20%, X5R, GRM Series"
			(at 0 0 0)
			(layer "F.Fab")
			(hide yes)
			(effects
				(font
					(size 1.27 1.27)
					(thickness 0.15)
				)
			)
		)
		(property "Author" "Antmicro"
			(at 0 0 0)
			(layer "F.Fab")
			(hide yes)
			(effects
				(font
					(size 1 1)
					(thickness 0.15)
				)
			)
		)
		(property "Dielectric" ""
			(at 0 0 0)
			(layer "F.Fab")
			(hide yes)
			(effects
				(font
					(size 1 1)
					(thickness 0.15)
				)
			)
		)
		(property "License" "Apache-2.0"
			(at 0 0 0)
			(layer "F.Fab")
			(hide yes)
			(effects
				(font
					(size 1 1)
					(thickness 0.15)
				)
			)
		)
		(property "MPN" "GRM188R60J226MEA0D"
			(at 0 0 0)
			(layer "F.Fab")
			(hide yes)
			(effects
				(font
					(size 1 1)
					(thickness 0.15)
				)
			)
		)
		(property "Manufacturer" "Murata"
			(at 0 0 0)
			(layer "F.Fab")
			(hide yes)
			(effects
				(font
					(size 1 1)
					(thickness 0.15)
				)
			)
		)
		(property "Val" "22u"
			(at 0 0 0)
			(layer "F.Fab")
			(hide yes)
			(effects
				(font
					(size 1 1)
					(thickness 0.15)
				)
			)
		)
		(property "Voltage" ""
			(at 0 0 0)
			(layer "F.Fab")
			(hide yes)
			(effects
				(font
					(size 1 1)
					(thickness 0.15)
				)
			)
		)
		(sheetname "DC-DC Converters")
		(sheetfile "dc-dc.kicad_sch")
		(attr smd)
		(fp_line
			(start -0.15 -0.4)
			(end 0.15 -0.4)
			(stroke
				(width 0.15)
				(type solid)
			)
			(layer "F.SilkS")
		)
		(fp_line
			(start -0.15 0.4)
			(end 0.15 0.4)
			(stroke
				(width 0.15)
				(type solid)
			)
			(layer "F.SilkS")
		)
		(fp_rect
			(start -1.25 -0.65)
			(end 1.25 0.65)
			(stroke
				(width 0.05)
				(type solid)
			)
			(fill no)
			(layer "F.CrtYd")
		)
		(fp_rect
			(start -0.8 -0.4)
			(end 0.8 0.4)
			(stroke
				(width 0.15)
				(type solid)
			)
			(fill no)
			(layer "F.Fab")
		)
		(pad "1" smd roundrect
			(at -0.7 0)
			(size 0.8 1)
			(layers "F.Cu" "F.Mask" "F.Paste")
			(roundrect_rratio 0.2)
			(net 1 "GND")
			(pintype "passive")
		)
		(pad "2" smd roundrect
			(at 0.7 0)
			(size 0.8 1)
			(layers "F.Cu" "F.Mask" "F.Paste")
			(roundrect_rratio 0.2)
			(net 751 "/DC-DC Converters/1V0_REG")
			(pintype "passive")
		)
	)
	(footprint "antmicro-footprints:SW_KMR211NGLFS_SMD"
		(layer "F.Cu")
		(at 266.8 88.6 180)
		(property "Reference" "S4"
			(at 0.7 -2.6 180)
			(layer "F.SilkS")
			(effects
				(font
					(size 0.7 0.7)
					(thickness 0.15)
				)
				(justify left bottom)
			)
		)
		(property "Value" "SW_KMR211NGLFS_SMD"
			(at -3 3 180)
			(layer "F.Fab")
			(effects
				(font
					(size 0.7 0.7)
					(thickness 0.15)
				)
				(justify left bottom)
			)
		)
		(property "Description" "Tactile Switch, KMR 2 Series, Top Actuated, Surface Mount, Oval Button, 120 gf, 50mA at 32VDC"
			(at 0 0 180)
			(layer "F.Fab")
			(hide yes)
			(effects
				(font
					(size 1.27 1.27)
					(thickness 0.15)
				)
			)
		)
		(property "Author" "Antmicro"
			(at 533.6 177.2 0)
			(layer "F.Fab")
			(hide yes)
			(effects
				(font
					(size 1 1)
					(thickness 0.15)
				)
			)
		)
		(property "License" "Apache-2.0"
			(at 533.6 177.2 0)
			(layer "F.Fab")
			(hide yes)
			(effects
				(font
					(size 1 1)
					(thickness 0.15)
				)
			)
		)
		(property "MPN" "KMR211NGLFS"
			(at 533.6 177.2 0)
			(layer "F.Fab")
			(hide yes)
			(effects
				(font
					(size 1 1)
					(thickness 0.15)
				)
			)
		)
		(property "Manufacturer" "C&K"
			(at 533.6 177.2 0)
			(layer "F.Fab")
			(hide yes)
			(effects
				(font
					(size 1 1)
					(thickness 0.15)
				)
			)
		)
		(sheetname "User GPIO + LED + button + DIP switch")
		(sheetfile "user-gpio.kicad_sch")
		(attr smd)
		(fp_line
			(start 2.101 1.601)
			(end 2.101 1.48)
			(stroke
				(width 0.15)
				(type solid)
			)
			(layer "F.SilkS")
		)
		(fp_line
			(start 2.101 1.601)
			(end -2.1 1.601)
			(stroke
				(width 0.15)
				(type solid)
			)
			(layer "F.SilkS")
		)
		(fp_line
			(start 2.101 -1.58)
			(end 2.101 -1.459)
			(stroke
				(width 0.15)
				(type solid)
			)
			(layer "F.SilkS")
		)
		(fp_line
			(start 2.101 -1.6)
			(end -2.1 -1.6)
			(stroke
				(width 0.15)
				(type solid)
			)
			(layer "F.SilkS")
		)
		(fp_line
			(start -2.1 1.601)
			(end -2.1 1.48)
			(stroke
				(width 0.15)
				(type solid)
			)
			(layer "F.SilkS")
		)
		(fp_line
			(start -2.1 -1.6)
			(end -2.1 -1.499)
			(stroke
				(width 0.15)
				(type solid)
			)
			(layer "F.SilkS")
		)
		(fp_rect
			(start 2.751 1.75)
			(end -2.748 -1.749)
			(stroke
				(width 0.05)
				(type solid)
			)
			(fill no)
			(layer "F.CrtYd")
		)
		(fp_line
			(start 2.101 1.601)
			(end 2.101 -1.6)
			(stroke
				(width 0.15)
				(type solid)
			)
			(layer "F.Fab")
		)
		(fp_line
			(start 2.101 -1.6)
			(end -2.1 -1.6)
			(stroke
				(width 0.15)
				(type solid)
			)
			(layer "F.Fab")
		)
		(fp_line
			(start 0.25 0.802)
			(end -0.248 0.802)
			(stroke
				(width 0.15)
				(type solid)
			)
			(layer "F.Fab")
		)
		(fp_line
			(start -0.248 -0.8)
			(end 0.25 -0.8)
			(stroke
				(width 0.15)
				(type solid)
			)
			(layer "F.Fab")
		)
		(fp_line
			(start -2.1 1.601)
			(end 2.101 1.601)
			(stroke
				(width 0.15)
				(type solid)
			)
			(layer "F.Fab")
		)
		(fp_line
			(start -2.1 -1.6)
			(end -2.1 1.601)
			(stroke
				(width 0.15)
				(type solid)
			)
			(layer "F.Fab")
		)
		(fp_arc
			(start 0.25 -0.8)
			(mid 1.051001 0.001)
			(end 0.25 0.802)
			(stroke
				(width 0.15)
				(type solid)
			)
			(layer "F.Fab")
		)
		(fp_arc
			(start -0.248 0.802)
			(mid -1.050001 0.001)
			(end -0.248 -0.8)
			(stroke
				(width 0.15)
				(type solid)
			)
			(layer "F.Fab")
		)
		(pad "1" smd rect
			(at -2.048 -0.8)
			(size 0.9 1)
			(layers "F.Cu" "F.Mask" "F.Paste")
			(net 1233 "/USER_IO.BUTTON2")
			(pinfunction "1")
			(pintype "passive")
		)
		(pad "2" smd rect
			(at 2.05 -0.8)
			(size 0.9 1)
			(layers "F.Cu" "F.Mask" "F.Paste")
			(net 1233 "/USER_IO.BUTTON2")
			(pinfunction "2")
			(pintype "passive")
		)
		(pad "3" smd rect
			(at -2.048 0.802)
			(size 0.9 1)
			(layers "F.Cu" "F.Mask" "F.Paste")
			(net 1 "GND")
			(pinfunction "3")
			(pintype "passive")
		)
		(pad "4" smd rect
			(at 2.05 0.802)
			(size 0.9 1)
			(layers "F.Cu" "F.Mask" "F.Paste")
			(net 1 "GND")
			(pinfunction "4")
			(pintype "passive")
		)
	)
	(footprint "antmicro-footprints:SOT-23-5"
		(layer "F.Cu")
		(at 258.4 142.9 90)
		(property "Reference" "U15"
			(at -1.1 2.75 90)
			(layer "F.SilkS")
			(effects
				(font
					(size 0.7 0.7)
					(thickness 0.15)
				)
				(justify left bottom)
			)
		)
		(property "Value" "NCP718BSN330T1G"
			(at 0.002 2.799 90)
			(layer "F.Fab")
			(effects
				(font
					(size 0.7 0.7)
					(thickness 0.15)
				)
				(justify left bottom)
			)
		)
		(property "Description" "Linear Voltage Regulator IC Positive Fixed 1 Output 300mA TSOT-23-5"
			(at 0 0 90)
			(layer "F.Fab")
			(hide yes)
			(effects
				(font
					(size 1.27 1.27)
					(thickness 0.15)
				)
			)
		)
		(property "Author" "Antmicro"
			(at 401.3 -115.5 0)
			(layer "F.Fab")
			(hide yes)
			(effects
				(font
					(size 1 1)
					(thickness 0.15)
				)
			)
		)
		(property "License" "Apache-2.0"
			(at 401.3 -115.5 0)
			(layer "F.Fab")
			(hide yes)
			(effects
				(font
					(size 1 1)
					(thickness 0.15)
				)
			)
		)
		(property "MPN" "NCP718BSN330T1G"
			(at 401.3 -115.5 0)
			(layer "F.Fab")
			(hide yes)
			(effects
				(font
					(size 1 1)
					(thickness 0.15)
				)
			)
		)
		(property "Manufacturer" "ON Semiconductor"
			(at 401.3 -115.5 0)
			(layer "F.Fab")
			(hide yes)
			(effects
				(font
					(size 1 1)
					(thickness 0.15)
				)
			)
		)
		(sheetname "USB PHY")
		(sheetfile "usb-phy.kicad_sch")
		(attr smd)
		(fp_line
			(start 0.8 -1.6)
			(end 0.5 -1.6)
			(stroke
				(width 0.15)
				(type solid)
			)
			(layer "F.SilkS")
		)
		(fp_line
			(start -0.8 -1.6)
			(end -0.5 -1.6)
			(stroke
				(width 0.15)
				(type solid)
			)
			(layer "F.SilkS")
		)
		(fp_line
			(start -0.8 -1.6)
			(end -0.8 -1.3)
			(stroke
				(width 0.15)
				(type solid)
			)
			(layer "F.SilkS")
		)
		(fp_line
			(start 0.8 -1.3)
			(end 0.8 -1.6)
			(stroke
				(width 0.15)
				(type solid)
			)
			(layer "F.SilkS")
		)
		(fp_line
			(start 0.8 0.55)
			(end 0.8 -0.55)
			(stroke
				(width 0.15)
				(type solid)
			)
			(layer "F.SilkS")
		)
		(fp_line
			(start 0.8 1.3)
			(end 0.8 1.599)
			(stroke
				(width 0.15)
				(type solid)
			)
			(layer "F.SilkS")
		)
		(fp_line
			(start 0.8 1.599)
			(end 0.549 1.599)
			(stroke
				(width 0.15)
				(type solid)
			)
			(layer "F.SilkS")
		)
		(fp_line
			(start -0.55 1.6)
			(end -0.85 1.6)
			(stroke
				(width 0.15)
				(type solid)
			)
			(layer "F.SilkS")
		)
		(fp_line
			(start -0.85 1.6)
			(end -0.85 1.301)
			(stroke
				(width 0.15)
				(type solid)
			)
			(layer "F.SilkS")
		)
		(fp_circle
			(center -1.25 -1.5)
			(end -1.2 -1.5)
			(stroke
				(width 0.15)
				(type solid)
			)
			(fill yes)
			(layer "F.SilkS")
		)
		(fp_rect
			(start 1.9 -1.76)
			(end -1.9 1.75)
			(stroke
				(width 0.05)
				(type solid)
			)
			(fill no)
			(layer "F.CrtYd")
		)
		(fp_line
			(start -0.398 -1.526)
			(end -0.874 -1.05)
			(stroke
				(width 0.15)
				(type solid)
			)
			(layer "F.Fab")
		)
		(fp_rect
			(start 0.874 1.523)
			(end -0.873 -1.525)
			(stroke
				(width 0.15)
				(type solid)
			)
			(fill no)
			(layer "F.Fab")
		)
		(pad "1" smd rect
			(at -1.351 -0.951)
			(size 0.55 1)
			(layers "F.Cu" "F.Mask" "F.Paste")
			(net 704 "/Power supply/USB_DBG_PD.VBUS")
			(pinfunction "VIN")
			(pintype "passive")
		)
		(pad "2" smd rect
			(at -1.351 0)
			(size 0.55 1)
			(layers "F.Cu" "F.Mask" "F.Paste")
			(net 1 "GND")
			(pinfunction "GND")
			(pintype "passive")
		)
		(pad "3" smd rect
			(at -1.351 0.949)
			(size 0.55 1)
			(layers "F.Cu" "F.Mask" "F.Paste")
			(net 704 "/Power supply/USB_DBG_PD.VBUS")
			(pinfunction "EN")
			(pintype "passive")
		)
		(pad "4" smd rect
			(at 1.35 0.949)
			(size 0.55 1)
			(layers "F.Cu" "F.Mask" "F.Paste")
			(net 1159 "unconnected-(U15-NC-Pad4)")
			(pinfunction "NC")
			(pintype "no_connect")
		)
		(pad "5" smd rect
			(at 1.35 -0.951)
			(size 0.55 1)
			(layers "F.Cu" "F.Mask" "F.Paste")
			(net 707 "/USB PHY/FTDI_3V3")
			(pinfunction "VOUT")
			(pintype "passive")
		)
	)
	(footprint "antmicro-footprints:TSOT23-6"
		(layer "F.Cu")
		(at 245.199 116.404 180)
		(property "Reference" "U43"
			(at -2.901 1.054 90)
			(layer "F.SilkS")
			(effects
				(font
					(size 0.7 0.7)
					(thickness 0.15)
				)
				(justify right bottom)
			)
		)
		(property "Value" "AP22615A_TSOT26"
			(at 0 2.6 0)
			(layer "F.Fab")
			(effects
				(font
					(size 0.7 0.7)
					(thickness 0.15)
				)
				(justify right bottom)
			)
		)
		(property "Description" "Power Load Distribution Switch, High Side, Active High, 1 Output, 5.5 V, 3.6 A, 0.04 ohm, TSOT-26-6"
			(at 0 0 180)
			(layer "F.Fab")
			(hide yes)
			(effects
				(font
					(size 1.27 1.27)
					(thickness 0.15)
				)
			)
		)
		(property "Author" "Antmicro"
			(at 490.398 232.808 0)
			(layer "F.Fab")
			(hide yes)
			(effects
				(font
					(size 1 1)
					(thickness 0.15)
				)
			)
		)
		(property "License" "Apache-2.0"
			(at 490.398 232.808 0)
			(layer "F.Fab")
			(hide yes)
			(effects
				(font
					(size 1 1)
					(thickness 0.15)
				)
			)
		)
		(property "MPN" "AP22615AWU-7"
			(at 490.398 232.808 0)
			(layer "F.Fab")
			(hide yes)
			(effects
				(font
					(size 1 1)
					(thickness 0.15)
				)
			)
		)
		(property "Manufacturer" "Diodes Incorporated"
			(at 490.398 232.808 0)
			(layer "F.Fab")
			(hide yes)
			(effects
				(font
					(size 1 1)
					(thickness 0.15)
				)
			)
		)
		(sheetname "USB PHY")
		(sheetfile "usb-phy.kicad_sch")
		(attr smd)
		(fp_line
			(start 1 1.55)
			(end 1 1.4)
			(stroke
				(width 0.15)
				(type solid)
			)
			(layer "F.SilkS")
		)
		(fp_line
			(start 1 1.55)
			(end -1 1.55)
			(stroke
				(width 0.15)
				(type solid)
			)
			(layer "F.SilkS")
		)
		(fp_line
			(start 1 -1.497)
			(end 1 -1.375)
			(stroke
				(width 0.15)
				(type solid)
			)
			(layer "F.SilkS")
		)
		(fp_line
			(start 1 -1.497)
			(end -1 -1.5)
			(stroke
				(width 0.15)
				(type solid)
			)
			(layer "F.SilkS")
		)
		(fp_line
			(start -1 1.55)
			(end -1 1.4)
			(stroke
				(width 0.15)
				(type solid)
			)
			(layer "F.SilkS")
		)
		(fp_line
			(start -1 -1.5)
			(end -1 -1.375)
			(stroke
				(width 0.15)
				(type solid)
			)
			(layer "F.SilkS")
		)
		(fp_circle
			(center -1.44 -1.5)
			(end -1.39 -1.5)
			(stroke
				(width 0.15)
				(type solid)
			)
			(fill yes)
			(layer "F.SilkS")
		)
		(fp_rect
			(start 1.93 -1.7)
			(end -1.93 1.7)
			(stroke
				(width 0.05)
				(type solid)
			)
			(fill no)
			(layer "F.CrtYd")
		)
		(fp_line
			(start -0.45 -1.521)
			(end -0.876 -1.096)
			(stroke
				(width 0.15)
				(type solid)
			)
			(layer "F.Fab")
		)
		(fp_rect
			(start 0.875 1.528)
			(end -0.875 -1.525)
			(stroke
				(width 0.15)
				(type solid)
			)
			(fill no)
			(layer "F.Fab")
		)
		(pad "1" smd rect
			(at -1.301 -0.947 90)
			(size 0.7 1.2)
			(layers "F.Cu" "F.Mask" "F.Paste")
			(net 715 "/USB PHY/USB_USR_VBUS")
			(pinfunction "OUT")
			(pintype "power_out")
		)
		(pad "2" smd rect
			(at -1.301 0.004 90)
			(size 0.7 1.2)
			(layers "F.Cu" "F.Mask" "F.Paste")
			(net 1 "GND")
			(pinfunction "GND")
			(pintype "power_in")
		)
		(pad "3" smd rect
			(at -1.301 0.954 90)
			(size 0.7 1.2)
			(layers "F.Cu" "F.Mask" "F.Paste")
			(net 386 "Net-(U43-FLG)")
			(pinfunction "FLG")
			(pintype "output")
		)
		(pad "4" smd rect
			(at 1.299 0.954 90)
			(size 0.7 1.2)
			(layers "F.Cu" "F.Mask" "F.Paste")
			(net 385 "Net-(U43-EN)")
			(pinfunction "EN")
			(pintype "input")
		)
		(pad "5" smd rect
			(at 1.299 0.004 90)
			(size 0.7 1.2)
			(layers "F.Cu" "F.Mask" "F.Paste")
			(net 389 "Net-(U43-ISET)")
			(pinfunction "ISET")
			(pintype "passive")
		)
		(pad "6" smd rect
			(at 1.299 -0.947 90)
			(size 0.7 1.2)
			(layers "F.Cu" "F.Mask" "F.Paste")
			(net 703 "+5V")
			(pinfunction "IN")
			(pintype "power_in")
		)
	)
	(footprint "antmicro-footprints:C_0603_1608Metric"
		(layer "F.Cu")
		(at 186.225 176.399 -90)
		(descr "Capacitor SMD 0603")
		(tags "capacitor 0603")
		(property "Reference" "C208"
			(at -1.049 0.625 90)
			(layer "F.SilkS")
			(effects
				(font
					(size 0.7 0.7)
					(thickness 0.15)
				)
				(justify right bottom)
			)
		)
		(property "Value" "C_1u_25V_0603"
			(at 0 1.6 90)
			(layer "F.Fab")
			(effects
				(font
					(size 0.7 0.7)
					(thickness 0.15)
				)
				(justify right bottom)
			)
		)
		(property "Description" "SMD Multilayer Ceramic Capacitor, 1 µF, 25 V, 0603 [1608 Metric], ± 10%, X5R, CL"
			(at 0 0 270)
			(layer "F.Fab")
			(hide yes)
			(effects
				(font
					(size 1.27 1.27)
					(thickness 0.15)
				)
			)
		)
		(property "Author" "Antmicro"
			(at 9.826 362.624 0)
			(layer "F.Fab")
			(hide yes)
			(effects
				(font
					(size 1 1)
					(thickness 0.15)
				)
			)
		)
		(property "Dielectric" ""
			(at 9.826 362.624 0)
			(layer "F.Fab")
			(hide yes)
			(effects
				(font
					(size 1 1)
					(thickness 0.15)
				)
			)
		)
		(property "License" "Apache-2.0"
			(at 9.826 362.624 0)
			(layer "F.Fab")
			(hide yes)
			(effects
				(font
					(size 1 1)
					(thickness 0.15)
				)
			)
		)
		(property "MPN" "CL10A105KA8NNNC"
			(at 9.826 362.624 0)
			(layer "F.Fab")
			(hide yes)
			(effects
				(font
					(size 1 1)
					(thickness 0.15)
				)
			)
		)
		(property "Manufacturer" "Samsung Electro-Mechanics"
			(at 9.826 362.624 0)
			(layer "F.Fab")
			(hide yes)
			(effects
				(font
					(size 1 1)
					(thickness 0.15)
				)
			)
		)
		(property "Val" "1u"
			(at 9.826 362.624 0)
			(layer "F.Fab")
			(hide yes)
			(effects
				(font
					(size 1 1)
					(thickness 0.15)
				)
			)
		)
		(property "Voltage" "25V"
			(at 9.826 362.624 0)
			(layer "F.Fab")
			(hide yes)
			(effects
				(font
					(size 1 1)
					(thickness 0.15)
				)
			)
		)
		(sheetname "Power supply")
		(sheetfile "power-supply.kicad_sch")
		(attr smd)
		(fp_line
			(start -0.15 0.4)
			(end 0.15 0.4)
			(stroke
				(width 0.15)
				(type solid)
			)
			(layer "F.SilkS")
		)
		(fp_line
			(start -0.15 -0.4)
			(end 0.15 -0.4)
			(stroke
				(width 0.15)
				(type solid)
			)
			(layer "F.SilkS")
		)
		(fp_rect
			(start -1.25 -0.65)
			(end 1.25 0.65)
			(stroke
				(width 0.05)
				(type solid)
			)
			(fill no)
			(layer "F.CrtYd")
		)
		(fp_rect
			(start -0.8 -0.4)
			(end 0.8 0.4)
			(stroke
				(width 0.15)
				(type solid)
			)
			(fill no)
			(layer "F.Fab")
		)
		(pad "1" smd roundrect
			(at -0.7 0 270)
			(size 0.8 1)
			(layers "F.Cu" "F.Mask" "F.Paste")
			(roundrect_rratio 0.2)
			(net 1 "GND")
			(pintype "passive")
		)
		(pad "2" smd roundrect
			(at 0.7 0 270)
			(size 0.8 1)
			(layers "F.Cu" "F.Mask" "F.Paste")
			(roundrect_rratio 0.2)
			(net 702 "VDC")
			(pintype "passive")
		)
	)
	(footprint "antmicro-footprints:R_0402_1005Metric"
		(layer "F.Cu")
		(at 236.2 131.55 180)
		(descr "Resistor SMD 0402")
		(tags "resistor SMD 0402")
		(property "Reference" "R177"
			(at 1.825 3.525 180)
			(layer "F.SilkS")
			(effects
				(font
					(size 0.7 0.7)
					(thickness 0.15)
				)
				(justify left bottom)
			)
		)
		(property "Value" "R_33R_0402"
			(at 0 1.4 180)
			(layer "F.Fab")
			(effects
				(font
					(size 0.7 0.7)
					(thickness 0.15)
				)
				(justify left bottom)
			)
		)
		(property "Description" "SMD Chip Resistor, 33 ohm, ± 1%, 62.5 mW, 0402 [1005 Metric], Thick Film, General Purpose"
			(at 0 0 180)
			(layer "F.Fab")
			(hide yes)
			(effects
				(font
					(size 1.27 1.27)
					(thickness 0.15)
				)
			)
		)
		(property "Author" "Antmicro"
			(at 472.4 263.1 0)
			(layer "F.Fab")
			(hide yes)
			(effects
				(font
					(size 1 1)
					(thickness 0.15)
				)
			)
		)
		(property "License" "Apache-2.0"
			(at 472.4 263.1 0)
			(layer "F.Fab")
			(hide yes)
			(effects
				(font
					(size 1 1)
					(thickness 0.15)
				)
			)
		)
		(property "MPN" "CR0402-FX-33R0GLF"
			(at 472.4 263.1 0)
			(layer "F.Fab")
			(hide yes)
			(effects
				(font
					(size 1 1)
					(thickness 0.15)
				)
			)
		)
		(property "Manufacturer" "Bourns"
			(at 472.4 263.1 0)
			(layer "F.Fab")
			(hide yes)
			(effects
				(font
					(size 1 1)
					(thickness 0.15)
				)
			)
		)
		(property "Tolerance" "1%"
			(at 472.4 263.1 0)
			(layer "F.Fab")
			(hide yes)
			(effects
				(font
					(size 1 1)
					(thickness 0.15)
				)
			)
		)
		(property "Val" "33R"
			(at 472.4 263.1 0)
			(layer "F.Fab")
			(hide yes)
			(effects
				(font
					(size 1 1)
					(thickness 0.15)
				)
			)
		)
		(sheetname "USB PHY")
		(sheetfile "usb-phy.kicad_sch")
		(attr smd)
		(fp_rect
			(start -0.925 -0.47)
			(end 0.925 0.47)
			(stroke
				(width 0.05)
				(type default)
			)
			(fill no)
			(layer "F.CrtYd")
		)
		(fp_rect
			(start -0.5 -0.25)
			(end 0.5 0.25)
			(stroke
				(width 0.15)
				(type solid)
			)
			(fill no)
			(layer "F.Fab")
		)
		(pad "1" smd roundrect
			(at -0.48 0 180)
			(size 0.59 0.64)
			(layers "F.Cu" "F.Mask" "F.Paste")
			(roundrect_rratio 0.25)
			(net 369 "Net-(U22-B2Y)")
			(pintype "passive")
		)
		(pad "2" smd roundrect
			(at 0.48 0 180)
			(size 0.59 0.64)
			(layers "F.Cu" "F.Mask" "F.Paste")
			(roundrect_rratio 0.25)
			(net 161 "/FPGA Config/JTAG.TMS")
			(pintype "passive")
		)
	)
	(footprint "antmicro-footprints:R_Array_4x0201_Panasonic_EXB18V"
		(layer "F.Cu")
		(at 249.9 144.302)
		(property "Reference" "R44"
			(at -15.7 -39.952 0)
			(layer "F.SilkS")
			(effects
				(font
					(size 0.7 0.7)
					(thickness 0.15)
				)
				(justify right bottom)
			)
		)
		(property "Value" "R_4x33R_0201_array"
			(at -1.1 1.8 0)
			(layer "F.Fab")
			(effects
				(font
					(size 0.7 0.7)
					(thickness 0.15)
				)
				(justify left bottom)
			)
		)
		(property "Description" "Fixed Network Resistor, 33 ohm, Isolated, 4 Resistors, 0502 [1406 Metric], Flat, ± 5%"
			(at 0 0 0)
			(layer "F.Fab")
			(hide yes)
			(effects
				(font
					(size 1.27 1.27)
					(thickness 0.15)
				)
			)
		)
		(property "Author" "Antmicro"
			(at 0 0 0)
			(layer "F.Fab")
			(hide yes)
			(effects
				(font
					(size 1 1)
					(thickness 0.15)
				)
			)
		)
		(property "License" "Apache-2.0"
			(at 0 0 0)
			(layer "F.Fab")
			(hide yes)
			(effects
				(font
					(size 1 1)
					(thickness 0.15)
				)
			)
		)
		(property "MPN" "EXB-18V330JX"
			(at 0 0 0)
			(layer "F.Fab")
			(hide yes)
			(effects
				(font
					(size 1 1)
					(thickness 0.15)
				)
			)
		)
		(property "Manufacturer" "Panasonic"
			(at 0 0 0)
			(layer "F.Fab")
			(hide yes)
			(effects
				(font
					(size 1 1)
					(thickness 0.15)
				)
			)
		)
		(property "Val" "R_4x33R_0201"
			(at 0 0 0)
			(layer "F.Fab")
			(hide yes)
			(effects
				(font
					(size 1 1)
					(thickness 0.15)
				)
			)
		)
		(sheetname "Supervisior MCU")
		(sheetfile "supervisor-mcu.kicad_sch")
		(attr smd)
		(fp_line
			(start -0.8 -0.45)
			(end -0.8 0.45)
			(stroke
				(width 0.12)
				(type solid)
			)
			(layer "F.SilkS")
		)
		(fp_line
			(start 0.8 -0.45)
			(end 0.8 0.45)
			(stroke
				(width 0.12)
				(type solid)
			)
			(layer "F.SilkS")
		)
		(fp_rect
			(start -0.898 -0.66)
			(end 0.898 0.65)
			(stroke
				(width 0.05)
				(type solid)
			)
			(fill no)
			(layer "F.CrtYd")
		)
		(pad "1" smd roundrect
			(at -0.6 0.298)
			(size 0.2 0.4)
			(layers "F.Cu" "F.Mask" "F.Paste")
			(roundrect_rratio 0.25)
			(net 1104 "/Supervisior MCU/FPGA_M1")
			(pinfunction "R1.1")
			(pintype "passive")
		)
		(pad "2" smd roundrect
			(at -0.202 0.298)
			(size 0.2 0.4)
			(layers "F.Cu" "F.Mask" "F.Paste")
			(roundrect_rratio 0.25)
			(net 260 "/Supervisior MCU/FPGA_CFG_CS")
			(pinfunction "R2.1")
			(pintype "passive")
		)
		(pad "3" smd roundrect
			(at 0.2 0.298)
			(size 0.2 0.4)
			(layers "F.Cu" "F.Mask" "F.Paste")
			(roundrect_rratio 0.25)
			(net 1092 "/Supervisior MCU/USB_CLK1_SPARE")
			(pinfunction "R3.1")
			(pintype "passive")
		)
		(pad "4" smd roundrect
			(at 0.598 0.298)
			(size 0.2 0.4)
			(layers "F.Cu" "F.Mask" "F.Paste")
			(roundrect_rratio 0.25)
			(net 1117 "/Supervisior MCU/USB_SPARE3")
			(pinfunction "R4.1")
			(pintype "passive")
		)
		(pad "5" smd roundrect
			(at 0.598 -0.3)
			(size 0.2 0.4)
			(layers "F.Cu" "F.Mask" "F.Paste")
			(roundrect_rratio 0.25)
			(net 1385 "/SUP_MCU.SPARE3")
			(pinfunction "R4.2")
			(pintype "passive")
		)
		(pad "6" smd roundrect
			(at 0.2 -0.3)
			(size 0.2 0.4)
			(layers "F.Cu" "F.Mask" "F.Paste")
			(roundrect_rratio 0.25)
			(net 1386 "/SUP_MCU.SCLK1")
			(pinfunction "R3.2")
			(pintype "passive")
		)
		(pad "7" smd roundrect
			(at -0.202 -0.3)
			(size 0.2 0.4)
			(layers "F.Cu" "F.Mask" "F.Paste")
			(roundrect_rratio 0.25)
			(net 1334 "/SUP_MCU.CFG_CS")
			(pinfunction "R2.2")
			(pintype "passive")
		)
		(pad "8" smd roundrect
			(at -0.6 -0.3)
			(size 0.2 0.4)
			(layers "F.Cu" "F.Mask" "F.Paste")
			(roundrect_rratio 0.25)
			(net 1313 "/SUP_MCU.FPGA_M1")
			(pinfunction "R1.2")
			(pintype "passive")
		)
	)
	(footprint "antmicro-footprints:R_0603_1608Metric"
		(layer "F.Cu")
		(at 183 172.7 90)
		(descr "Resistor SMD 0603")
		(tags "resistor SMD 0603")
		(property "Reference" "R291"
			(at -1.39 1.37 270)
			(layer "F.SilkS")
			(effects
				(font
					(size 0.7 0.7)
					(thickness 0.15)
				)
				(justify left bottom)
			)
		)
		(property "Value" "R_0R_22.4A_0603"
			(at 0 1.6 90)
			(layer "F.Fab")
			(effects
				(font
					(size 0.7 0.7)
					(thickness 0.15)
				)
				(justify left bottom)
			)
		)
		(property "Description" "SMD Chip Resistor"
			(at 0 0 90)
			(layer "F.Fab")
			(hide yes)
			(effects
				(font
					(size 1.27 1.27)
					(thickness 0.15)
				)
			)
		)
		(property "Author" "Antmicro"
			(at 355.7 -10.3 0)
			(layer "F.Fab")
			(hide yes)
			(effects
				(font
					(size 1 1)
					(thickness 0.15)
				)
			)
		)
		(property "License" "Apache-2.0"
			(at 355.7 -10.3 0)
			(layer "F.Fab")
			(hide yes)
			(effects
				(font
					(size 1 1)
					(thickness 0.15)
				)
			)
		)
		(property "MPN" "PMR03EZPJ000"
			(at 355.7 -10.3 0)
			(layer "F.Fab")
			(hide yes)
			(effects
				(font
					(size 1 1)
					(thickness 0.15)
				)
			)
		)
		(property "Manufacturer" "ROHM Semiconductor"
			(at 355.7 -10.3 0)
			(layer "F.Fab")
			(hide yes)
			(effects
				(font
					(size 1 1)
					(thickness 0.15)
				)
			)
		)
		(property "Max. Curr." "22.4A"
			(at 355.7 -10.3 0)
			(layer "F.Fab")
			(hide yes)
			(effects
				(font
					(size 1 1)
					(thickness 0.15)
				)
			)
		)
		(property "Tolerance" "template_tolerance"
			(at 355.7 -10.3 0)
			(layer "F.Fab")
			(hide yes)
			(effects
				(font
					(size 1 1)
					(thickness 0.15)
				)
			)
		)
		(property "Val" "0R"
			(at 355.7 -10.3 0)
			(layer "F.Fab")
			(hide yes)
			(effects
				(font
					(size 1 1)
					(thickness 0.15)
				)
			)
		)
		(sheetname "DC-DC Converters")
		(sheetfile "dc-dc.kicad_sch")
		(attr smd)
		(fp_line
			(start -0.15 -0.4)
			(end 0.15 -0.4)
			(stroke
				(width 0.15)
				(type solid)
			)
			(layer "F.SilkS")
		)
		(fp_line
			(start -0.15 0.4)
			(end 0.15 0.4)
			(stroke
				(width 0.15)
				(type solid)
			)
			(layer "F.SilkS")
		)
		(fp_rect
			(start -1.25 -0.65)
			(end 1.25 0.65)
			(stroke
				(width 0.05)
				(type solid)
			)
			(fill no)
			(layer "F.CrtYd")
		)
		(fp_rect
			(start -0.8 -0.4)
			(end 0.8 0.4)
			(stroke
				(width 0.15)
				(type solid)
			)
			(fill no)
			(layer "F.Fab")
		)
		(pad "1" smd roundrect
			(at -0.7 0 90)
			(size 0.8 1)
			(layers "F.Cu" "F.Mask" "F.Paste")
			(roundrect_rratio 0.2)
			(net 739 "/DC-DC Converters/5V_local")
			(pintype "passive")
		)
		(pad "2" smd roundrect
			(at 0.7 0 90)
			(size 0.8 1)
			(layers "F.Cu" "F.Mask" "F.Paste")
			(roundrect_rratio 0.2)
			(net 703 "+5V")
			(pintype "passive")
		)
	)
	(footprint "antmicro-footprints:PinSocket_2x6_P2.54mm_Drill1.04mm_Horizontal"
		(layer "F.Cu")
		(at 213.4375 80.1495)
		(property "Reference" "J5"
			(at 14.3625 -1.9495 0)
			(layer "F.SilkS")
			(effects
				(font
					(size 0.7 0.7)
					(thickness 0.15)
				)
				(justify left bottom)
			)
		)
		(property "Value" "PinSocket_2x6_P2.54mm_Drill1.04mm_Horizontal"
			(at 0 4.75 0)
			(layer "F.Fab")
			(effects
				(font
					(size 0.7 0.7)
					(thickness 0.15)
				)
				(justify left bottom)
			)
		)
		(property "Description" "PCB Receptacle, Board-to-Board, 2.54 mm, 2 Rows, 12 Contacts, Through Hole Mount Right Angle, SSW"
			(at 0 0 0)
			(layer "F.Fab")
			(hide yes)
			(effects
				(font
					(size 1.27 1.27)
					(thickness 0.15)
				)
			)
		)
		(property "Author" "Antmicro"
			(at 0 0 0)
			(layer "F.Fab")
			(hide yes)
			(effects
				(font
					(size 1 1)
					(thickness 0.15)
				)
			)
		)
		(property "License" "Apache-2.0"
			(at 0 0 0)
			(layer "F.Fab")
			(hide yes)
			(effects
				(font
					(size 1 1)
					(thickness 0.15)
				)
			)
		)
		(property "MPN" "SSW-106-02-G-D-RA"
			(at 0 0 0)
			(layer "F.Fab")
			(hide yes)
			(effects
				(font
					(size 1 1)
					(thickness 0.15)
				)
			)
		)
		(property "Manufacturer" "Samtec"
			(at 0 0 0)
			(layer "F.Fab")
			(hide yes)
			(effects
				(font
					(size 1 1)
					(thickness 0.15)
				)
			)
		)
		(sheetname "User GPIO + LED + button + DIP switch")
		(sheetfile "user-gpio.kicad_sch")
		(attr through_hole)
		(fp_line
			(start -1.526 -1.524)
			(end -1.526 -10.035)
			(stroke
				(width 0.15)
				(type solid)
			)
			(layer "F.SilkS")
		)
		(fp_line
			(start 14.223 -10.035)
			(end -1.526 -10.035)
			(stroke
				(width 0.15)
				(type solid)
			)
			(layer "F.SilkS")
		)
		(fp_line
			(start 14.223 -10.035)
			(end 14.223 -1.524)
			(stroke
				(width 0.15)
				(type solid)
			)
			(layer "F.SilkS")
		)
		(fp_line
			(start 14.223 -1.524)
			(end -1.526 -1.524)
			(stroke
				(width 0.15)
				(type solid)
			)
			(layer "F.SilkS")
		)
		(fp_circle
			(center -1.2 0)
			(end -1.15 0)
			(stroke
				(width 0.15)
				(type solid)
			)
			(fill yes)
			(layer "F.SilkS")
		)
		(fp_rect
			(start -1.9 -10.4)
			(end 14.6 3.6)
			(stroke
				(width 0.05)
				(type solid)
			)
			(fill no)
			(layer "F.CrtYd")
		)
		(fp_line
			(start -1.526 -10.035)
			(end 14.223 -10.035)
			(stroke
				(width 0.15)
				(type solid)
			)
			(layer "F.Fab")
		)
		(fp_line
			(start -1.526 -10.035)
			(end 14.223 -10.035)
			(stroke
				(width 0.15)
				(type solid)
			)
			(layer "F.Fab")
		)
		(fp_line
			(start -1.526 -1.524)
			(end -1.526 -10.035)
			(stroke
				(width 0.15)
				(type solid)
			)
			(layer "F.Fab")
		)
		(fp_line
			(start -1.526 -1.524)
			(end -1.526 -10.035)
			(stroke
				(width 0.15)
				(type solid)
			)
			(layer "F.Fab")
		)
		(fp_line
			(start 14.223 -10.035)
			(end 14.223 -1.524)
			(stroke
				(width 0.15)
				(type solid)
			)
			(layer "F.Fab")
		)
		(fp_line
			(start 14.223 -10.035)
			(end 14.223 -1.524)
			(stroke
				(width 0.15)
				(type solid)
			)
			(layer "F.Fab")
		)
		(fp_line
			(start 14.223 -1.524)
			(end -1.526 -1.524)
			(stroke
				(width 0.15)
				(type solid)
			)
			(layer "F.Fab")
		)
		(pad "1" thru_hole rect
			(at 0 0)
			(size 1.84 1.84)
			(drill 1.04)
			(layers "*.Cu" "*.Mask")
			(remove_unused_layers no)
			(net 808 "/User GPIO + LED + button + DIP switch/PMOD_A_7")
			(pintype "passive")
		)
		(pad "2" thru_hole circle
			(at 0 2.539)
			(size 1.84 1.84)
			(drill 1.04)
			(layers "*.Cu" "*.Mask")
			(remove_unused_layers no)
			(net 809 "/User GPIO + LED + button + DIP switch/PMOD_A_1")
			(pintype "passive")
		)
		(pad "3" thru_hole circle
			(at 2.539 0)
			(size 1.84 1.84)
			(drill 1.04)
			(layers "*.Cu" "*.Mask")
			(remove_unused_layers no)
			(net 806 "/User GPIO + LED + button + DIP switch/PMOD_A_8")
			(pintype "passive")
		)
		(pad "4" thru_hole circle
			(at 2.539 2.539)
			(size 1.8 1.8)
			(drill 1.04)
			(layers "*.Cu" "*.Mask")
			(remove_unused_layers no)
			(net 807 "/User GPIO + LED + button + DIP switch/PMOD_A_2")
			(pintype "passive")
		)
		(pad "5" thru_hole circle
			(at 5.078 0)
			(size 1.84 1.84)
			(drill 1.04)
			(layers "*.Cu" "*.Mask")
			(remove_unused_layers no)
			(net 804 "/User GPIO + LED + button + DIP switch/PMOD_A_9")
			(pintype "passive")
		)
		(pad "6" thru_hole circle
			(at 5.078 2.539)
			(size 1.84 1.84)
			(drill 1.04)
			(layers "*.Cu" "*.Mask")
			(remove_unused_layers no)
			(net 805 "/User GPIO + LED + button + DIP switch/PMOD_A_3")
			(pintype "passive")
		)
		(pad "7" thru_hole circle
			(at 7.618 0)
			(size 1.84 1.84)
			(drill 1.04)
			(layers "*.Cu" "*.Mask")
			(remove_unused_layers no)
			(net 802 "/User GPIO + LED + button + DIP switch/PMOD_A_10")
			(pintype "passive")
		)
		(pad "8" thru_hole circle
			(at 7.618 2.539)
			(size 1.84 1.84)
			(drill 1.04)
			(layers "*.Cu" "*.Mask")
			(remove_unused_layers no)
			(net 803 "/User GPIO + LED + button + DIP switch/PMOD_A_4")
			(pintype "passive")
		)
		(pad "9" thru_hole circle
			(at 10.159 0)
			(size 1.84 1.84)
			(drill 1.04)
			(layers "*.Cu" "*.Mask")
			(remove_unused_layers no)
			(net 1 "GND")
			(pintype "passive")
		)
		(pad "10" thru_hole circle
			(at 10.159 2.539)
			(size 1.84 1.84)
			(drill 1.04)
			(layers "*.Cu" "*.Mask")
			(remove_unused_layers no)
			(net 1 "GND")
			(pintype "passive")
		)
		(pad "11" thru_hole circle
			(at 12.698 0)
			(size 1.84 1.84)
			(drill 1.04)
			(layers "*.Cu" "*.Mask")
			(remove_unused_layers no)
			(net 24 "+3V3")
			(pintype "passive")
		)
		(pad "12" thru_hole circle
			(at 12.698 2.539)
			(size 1.84 1.84)
			(drill 1.04)
			(layers "*.Cu" "*.Mask")
			(remove_unused_layers no)
			(net 24 "+3V3")
			(pintype "passive")
		)
	)
	(footprint "antmicro-footprints:FB_0805_2012Metric"
		(layer "F.Cu")
		(at 237 179)
		(descr "FERRITE BEAD 0805")
		(tags "FERRITE BEAD 0805")
		(property "Reference" "FB2"
			(at -1 1.9 0)
			(layer "F.SilkS")
			(effects
				(font
					(size 0.7 0.7)
					(thickness 0.15)
				)
				(justify left bottom)
			)
		)
		(property "Value" "FB_220Z_2A_Murata-BLM21PG_0805"
			(at 0 1.8 0)
			(layer "F.Fab")
			(effects
				(font
					(size 0.7 0.7)
					(thickness 0.15)
				)
				(justify left bottom)
			)
		)
		(property "Description" "Ferrite Bead, 0805 [2012 Metric], 220 ohm, 2 A, BLM21, 0.045 ohm, ± 25%, DC power line"
			(at 0 0 0)
			(layer "F.Fab")
			(hide yes)
			(effects
				(font
					(size 1.27 1.27)
					(thickness 0.15)
				)
			)
		)
		(property "Author" "Antmicro"
			(at 0 0 0)
			(layer "F.Fab")
			(hide yes)
			(effects
				(font
					(size 1 1)
					(thickness 0.15)
				)
			)
		)
		(property "Current" ""
			(at 0 0 0)
			(layer "F.Fab")
			(hide yes)
			(effects
				(font
					(size 1 1)
					(thickness 0.15)
				)
			)
		)
		(property "License" "Apache-2.0"
			(at 0 0 0)
			(layer "F.Fab")
			(hide yes)
			(effects
				(font
					(size 1 1)
					(thickness 0.15)
				)
			)
		)
		(property "MPN" "BLM21PG221SN1D"
			(at 0 0 0)
			(layer "F.Fab")
			(hide yes)
			(effects
				(font
					(size 1 1)
					(thickness 0.15)
				)
			)
		)
		(property "Manufacturer" "Murata"
			(at 0 0 0)
			(layer "F.Fab")
			(hide yes)
			(effects
				(font
					(size 1 1)
					(thickness 0.15)
				)
			)
		)
		(property "Val" "220Z/2A"
			(at 0 0 0)
			(layer "F.Fab")
			(hide yes)
			(effects
				(font
					(size 1 1)
					(thickness 0.15)
				)
			)
		)
		(sheetname "Power supply")
		(sheetfile "power-supply.kicad_sch")
		(attr smd)
		(fp_line
			(start -0.319 0.698)
			(end 0.281 0.698)
			(stroke
				(width 0.15)
				(type solid)
			)
			(layer "F.SilkS")
		)
		(fp_line
			(start -0.299 -0.698)
			(end 0.299 -0.698)
			(stroke
				(width 0.15)
				(type solid)
			)
			(layer "F.SilkS")
		)
		(fp_rect
			(start 1.95 -0.9)
			(end -1.95 0.9)
			(stroke
				(width 0.05)
				(type default)
			)
			(fill no)
			(layer "F.CrtYd")
		)
		(fp_line
			(start -0.948 -0.681)
			(end 0.948 -0.681)
			(stroke
				(width 0.15)
				(type solid)
			)
			(layer "F.Fab")
		)
		(fp_line
			(start -0.948 -0.676)
			(end -0.948 0.676)
			(stroke
				(width 0.15)
				(type solid)
			)
			(layer "F.Fab")
		)
		(fp_line
			(start -0.948 0.681)
			(end 0.948 0.681)
			(stroke
				(width 0.15)
				(type solid)
			)
			(layer "F.Fab")
		)
		(fp_line
			(start 0.948 -0.676)
			(end 0.948 0.676)
			(stroke
				(width 0.15)
				(type solid)
			)
			(layer "F.Fab")
		)
		(pad "1" smd roundrect
			(at -1.1 0)
			(size 1.2 1.3)
			(layers "F.Cu" "F.Mask" "F.Paste")
			(roundrect_rratio 0.25)
			(net 756 "Net-(D4-Pad1)")
			(pintype "passive")
		)
		(pad "2" smd roundrect
			(at 1.1 0)
			(size 1.2 1.3)
			(layers "F.Cu" "F.Mask" "F.Paste")
			(roundrect_rratio 0.25)
			(net 697 "/Power supply/VSS")
			(pintype "passive")
		)
	)
	(footprint "antmicro-footprints:R_0402_1005Metric"
		(layer "F.Cu")
		(at 225.1 114.2)
		(descr "Resistor SMD 0402")
		(tags "resistor SMD 0402")
		(property "Reference" "R94"
			(at -3.65 0.4 0)
			(layer "F.SilkS")
			(effects
				(font
					(size 0.7 0.7)
					(thickness 0.15)
				)
				(justify left bottom)
			)
		)
		(property "Value" "R_10k_0402"
			(at 0 1.4 0)
			(layer "F.Fab")
			(effects
				(font
					(size 0.7 0.7)
					(thickness 0.15)
				)
				(justify left bottom)
			)
		)
		(property "Description" "SMD Chip Resistor, 10 kohm, ± 1%, 62.5 mW, 0402 [1005 Metric], Thick Film, General Purpose"
			(at 0 0 0)
			(layer "F.Fab")
			(hide yes)
			(effects
				(font
					(size 1.27 1.27)
					(thickness 0.15)
				)
			)
		)
		(property "Author" "Antmicro"
			(at 0 0 0)
			(layer "F.Fab")
			(hide yes)
			(effects
				(font
					(size 1 1)
					(thickness 0.15)
				)
			)
		)
		(property "License" "Apache-2.0"
			(at 0 0 0)
			(layer "F.Fab")
			(hide yes)
			(effects
				(font
					(size 1 1)
					(thickness 0.15)
				)
			)
		)
		(property "MPN" "CR0402-FX-1002GLF"
			(at 0 0 0)
			(layer "F.Fab")
			(hide yes)
			(effects
				(font
					(size 1 1)
					(thickness 0.15)
				)
			)
		)
		(property "Manufacturer" "Bourns"
			(at 0 0 0)
			(layer "F.Fab")
			(hide yes)
			(effects
				(font
					(size 1 1)
					(thickness 0.15)
				)
			)
		)
		(property "Tolerance" "1%"
			(at 0 0 0)
			(layer "F.Fab")
			(hide yes)
			(effects
				(font
					(size 1 1)
					(thickness 0.15)
				)
			)
		)
		(property "Val" "10k"
			(at 0 0 0)
			(layer "F.Fab")
			(hide yes)
			(effects
				(font
					(size 1 1)
					(thickness 0.15)
				)
			)
		)
		(sheetname "SPI Flash + SD Card")
		(sheetfile "spi-flash.kicad_sch")
		(attr smd)
		(fp_rect
			(start -0.925 -0.47)
			(end 0.925 0.47)
			(stroke
				(width 0.05)
				(type default)
			)
			(fill no)
			(layer "F.CrtYd")
		)
		(fp_rect
			(start -0.5 -0.25)
			(end 0.5 0.25)
			(stroke
				(width 0.15)
				(type solid)
			)
			(fill no)
			(layer "F.Fab")
		)
		(pad "1" smd roundrect
			(at -0.48 0)
			(size 0.59 0.64)
			(layers "F.Cu" "F.Mask" "F.Paste")
			(roundrect_rratio 0.25)
			(net 419 "/FPGA Bank 16 & 17/USR_FLASH_1.DQ2")
			(pintype "passive")
		)
		(pad "2" smd roundrect
			(at 0.48 0)
			(size 0.59 0.64)
			(layers "F.Cu" "F.Mask" "F.Paste")
			(roundrect_rratio 0.25)
			(net 3 "VCC_USR_B")
			(pintype "passive")
		)
	)
	(footprint "antmicro-footprints:R_0402_1005Metric"
		(layer "F.Cu")
		(at 250.399 97.5 90)
		(descr "Resistor SMD 0402")
		(tags "resistor SMD 0402")
		(property "Reference" "R344"
			(at 0.15 -0.449 90)
			(layer "F.SilkS")
			(effects
				(font
					(size 0.7 0.7)
					(thickness 0.15)
				)
				(justify left bottom)
			)
		)
		(property "Value" "R_0R_0402"
			(at 0 1.4 90)
			(layer "F.Fab")
			(effects
				(font
					(size 0.7 0.7)
					(thickness 0.15)
				)
				(justify left bottom)
			)
		)
		(property "Description" "SMD Chip Resistor, Jumper, 0 ohm, 100 mW, 0402 [1005 Metric], Thick Film, General Purpose"
			(at 0 0 90)
			(layer "F.Fab")
			(hide yes)
			(effects
				(font
					(size 1.27 1.27)
					(thickness 0.15)
				)
			)
		)
		(property "Author" "Antmicro"
			(at 347.899 -152.899 0)
			(layer "F.Fab")
			(hide yes)
			(effects
				(font
					(size 1 1)
					(thickness 0.15)
				)
			)
		)
		(property "Current" "1A"
			(at 347.899 -152.899 0)
			(layer "F.Fab")
			(hide yes)
			(effects
				(font
					(size 1 1)
					(thickness 0.15)
				)
			)
		)
		(property "License" "Apache-2.0"
			(at 347.899 -152.899 0)
			(layer "F.Fab")
			(hide yes)
			(effects
				(font
					(size 1 1)
					(thickness 0.15)
				)
			)
		)
		(property "MPN" "ERJ2GE0R00X"
			(at 347.899 -152.899 0)
			(layer "F.Fab")
			(hide yes)
			(effects
				(font
					(size 1 1)
					(thickness 0.15)
				)
			)
		)
		(property "Manufacturer" "Panasonic"
			(at 347.899 -152.899 0)
			(layer "F.Fab")
			(hide yes)
			(effects
				(font
					(size 1 1)
					(thickness 0.15)
				)
			)
		)
		(property "Tolerance" ""
			(at 347.899 -152.899 0)
			(layer "F.Fab")
			(hide yes)
			(effects
				(font
					(size 1 1)
					(thickness 0.15)
				)
			)
		)
		(property "Val" "0R"
			(at 347.899 -152.899 0)
			(layer "F.Fab")
			(hide yes)
			(effects
				(font
					(size 1 1)
					(thickness 0.15)
				)
			)
		)
		(sheetname "USB PHY")
		(sheetfile "usb-phy.kicad_sch")
		(attr smd)
		(fp_rect
			(start -0.925 -0.47)
			(end 0.925 0.47)
			(stroke
				(width 0.05)
				(type default)
			)
			(fill no)
			(layer "F.CrtYd")
		)
		(fp_rect
			(start -0.5 -0.25)
			(end 0.5 0.25)
			(stroke
				(width 0.15)
				(type solid)
			)
			(fill no)
			(layer "F.Fab")
		)
		(pad "1" smd roundrect
			(at -0.48 0 90)
			(size 0.59 0.64)
			(layers "F.Cu" "F.Mask" "F.Paste")
			(roundrect_rratio 0.25)
			(net 569 "/FPGA Bank 12 & 13/USB_HOST.VBUS_PEN")
			(pintype "passive")
		)
		(pad "2" smd roundrect
			(at 0.48 0 90)
			(size 0.59 0.64)
			(layers "F.Cu" "F.Mask" "F.Paste")
			(roundrect_rratio 0.25)
			(net 583 "/USB PHY/USB_HOST_VBUS_EN")
			(pintype "passive")
		)
	)
	(footprint "antmicro-footprints:C_0402_1005Metric"
		(layer "F.Cu")
		(at 228.725 137.8 -90)
		(descr "Capacitor SMD 0402")
		(tags "capacitor SMD 0402")
		(property "Reference" "C369"
			(at -1.55 -2.375 180)
			(layer "F.SilkS")
			(effects
				(font
					(size 0.7 0.7)
					(thickness 0.15)
				)
				(justify right bottom)
			)
		)
		(property "Value" "C_100n_0402"
			(at 0 1.4 90)
			(layer "F.Fab")
			(effects
				(font
					(size 0.7 0.7)
					(thickness 0.15)
				)
				(justify right bottom)
			)
		)
		(property "Description" "SMD Multilayer Ceramic Capacitor, 0.1 µF, 50 V, 0402 [1005 Metric], ± 10%, X5R, GRM Series"
			(at 0 0 270)
			(layer "F.Fab")
			(hide yes)
			(effects
				(font
					(size 1.27 1.27)
					(thickness 0.15)
				)
			)
		)
		(property "Author" "Antmicro"
			(at 90.925 366.525 0)
			(layer "F.Fab")
			(hide yes)
			(effects
				(font
					(size 1 1)
					(thickness 0.15)
				)
			)
		)
		(property "Dielectric" "X5R"
			(at 90.925 366.525 0)
			(layer "F.Fab")
			(hide yes)
			(effects
				(font
					(size 1 1)
					(thickness 0.15)
				)
			)
		)
		(property "License" "Apache-2.0"
			(at 90.925 366.525 0)
			(layer "F.Fab")
			(hide yes)
			(effects
				(font
					(size 1 1)
					(thickness 0.15)
				)
			)
		)
		(property "MPN" "GRM155R61H104KE14D"
			(at 90.925 366.525 0)
			(layer "F.Fab")
			(hide yes)
			(effects
				(font
					(size 1 1)
					(thickness 0.15)
				)
			)
		)
		(property "Manufacturer" "Murata"
			(at 90.925 366.525 0)
			(layer "F.Fab")
			(hide yes)
			(effects
				(font
					(size 1 1)
					(thickness 0.15)
				)
			)
		)
		(property "Val" "100n"
			(at 90.925 366.525 0)
			(layer "F.Fab")
			(hide yes)
			(effects
				(font
					(size 1 1)
					(thickness 0.15)
				)
			)
		)
		(property "Voltage" "50V"
			(at 90.925 366.525 0)
			(layer "F.Fab")
			(hide yes)
			(effects
				(font
					(size 1 1)
					(thickness 0.15)
				)
			)
		)
		(sheetname "Clocks")
		(sheetfile "clocks.kicad_sch")
		(attr smd)
		(fp_rect
			(start -0.925 -0.47)
			(end 0.925 0.47)
			(stroke
				(width 0.05)
				(type default)
			)
			(fill no)
			(layer "F.CrtYd")
		)
		(fp_line
			(start -0.494 0.248)
			(end -0.494 -0.25)
			(stroke
				(width 0.15)
				(type solid)
			)
			(layer "F.Fab")
		)
		(fp_line
			(start 0.504 0.248)
			(end -0.494 0.248)
			(stroke
				(width 0.15)
				(type solid)
			)
			(layer "F.Fab")
		)
		(fp_line
			(start -0.494 -0.25)
			(end 0.504 -0.25)
			(stroke
				(width 0.15)
				(type solid)
			)
			(layer "F.Fab")
		)
		(fp_line
			(start 0.504 -0.25)
			(end 0.504 0.248)
			(stroke
				(width 0.15)
				(type solid)
			)
			(layer "F.Fab")
		)
		(pad "1" smd roundrect
			(at -0.48 0 270)
			(size 0.59 0.64)
			(layers "F.Cu" "F.Mask" "F.Paste")
			(roundrect_rratio 0.25)
			(net 1 "GND")
			(pintype "passive")
		)
		(pad "2" smd roundrect
			(at 0.48 0 270)
			(size 0.59 0.64)
			(layers "F.Cu" "F.Mask" "F.Paste")
			(roundrect_rratio 0.25)
			(net 1231 "Net-(C366-Pad2)")
			(pintype "passive")
		)
	)
	(footprint "antmicro-footprints:C_0402_1005Metric"
		(layer "F.Cu")
		(at 173.570001 124.922501 180)
		(descr "Capacitor SMD 0402")
		(tags "capacitor SMD 0402")
		(property "Reference" "C307"
			(at -3.729999 -0.329999 0)
			(layer "F.SilkS")
			(effects
				(font
					(size 0.7 0.7)
					(thickness 0.15)
				)
				(justify right bottom)
			)
		)
		(property "Value" "C_100n_0402"
			(at 0 1.4 0)
			(layer "F.Fab")
			(effects
				(font
					(size 0.7 0.7)
					(thickness 0.15)
				)
				(justify right bottom)
			)
		)
		(property "Description" "SMD Multilayer Ceramic Capacitor, 0.1 µF, 50 V, 0402 [1005 Metric], ± 10%, X5R, GRM Series"
			(at 0 0 180)
			(layer "F.Fab")
			(hide yes)
			(effects
				(font
					(size 1.27 1.27)
					(thickness 0.15)
				)
			)
		)
		(property "Author" "Antmicro"
			(at 347.140002 249.845002 0)
			(layer "F.Fab")
			(hide yes)
			(effects
				(font
					(size 1 1)
					(thickness 0.15)
				)
			)
		)
		(property "Dielectric" "X5R"
			(at 347.140002 249.845002 0)
			(layer "F.Fab")
			(hide yes)
			(effects
				(font
					(size 1 1)
					(thickness 0.15)
				)
			)
		)
		(property "License" "Apache-2.0"
			(at 347.140002 249.845002 0)
			(layer "F.Fab")
			(hide yes)
			(effects
				(font
					(size 1 1)
					(thickness 0.15)
				)
			)
		)
		(property "MPN" "GRM155R61H104KE14D"
			(at 347.140002 249.845002 0)
			(layer "F.Fab")
			(hide yes)
			(effects
				(font
					(size 1 1)
					(thickness 0.15)
				)
			)
		)
		(property "Manufacturer" "Murata"
			(at 347.140002 249.845002 0)
			(layer "F.Fab")
			(hide yes)
			(effects
				(font
					(size 1 1)
					(thickness 0.15)
				)
			)
		)
		(property "Val" "100n"
			(at 347.140002 249.845002 0)
			(layer "F.Fab")
			(hide yes)
			(effects
				(font
					(size 1 1)
					(thickness 0.15)
				)
			)
		)
		(property "Voltage" "50V"
			(at 347.140002 249.845002 0)
			(layer "F.Fab")
			(hide yes)
			(effects
				(font
					(size 1 1)
					(thickness 0.15)
				)
			)
		)
		(sheetname "FMC+ HSPC")
		(sheetfile "fmc-hspc.kicad_sch")
		(attr smd)
		(fp_rect
			(start -0.925 -0.47)
			(end 0.925 0.47)
			(stroke
				(width 0.05)
				(type default)
			)
			(fill no)
			(layer "F.CrtYd")
		)
		(fp_line
			(start 0.504 0.248)
			(end -0.494 0.248)
			(stroke
				(width 0.15)
				(type solid)
			)
			(layer "F.Fab")
		)
		(fp_line
			(start 0.504 -0.25)
			(end 0.504 0.248)
			(stroke
				(width 0.15)
				(type solid)
			)
			(layer "F.Fab")
		)
		(fp_line
			(start -0.494 0.248)
			(end -0.494 -0.25)
			(stroke
				(width 0.15)
				(type solid)
			)
			(layer "F.Fab")
		)
		(fp_line
			(start -0.494 -0.25)
			(end 0.504 -0.25)
			(stroke
				(width 0.15)
				(type solid)
			)
			(layer "F.Fab")
		)
		(pad "1" smd roundrect
			(at -0.48 0 180)
			(size 0.59 0.64)
			(layers "F.Cu" "F.Mask" "F.Paste")
			(roundrect_rratio 0.25)
			(net 89 "/FMC+ HSPC/GTX115.TX3_N")
			(pintype "passive")
		)
		(pad "2" smd roundrect
			(at 0.48 0 180)
			(size 0.59 0.64)
			(layers "F.Cu" "F.Mask" "F.Paste")
			(roundrect_rratio 0.25)
			(net 88 "/FMC+ HSPC/GTX_TX4_C_N")
			(pintype "passive")
		)
	)
	(footprint "antmicro-footprints:NetTie-2_SMD_Pad0.127mm"
		(layer "F.Cu")
		(at 247.7 143.602 90)
		(descr "Net tie, 2 pin, 0.127mm  SMD pads")
		(tags "net tie")
		(property "Reference" "NT3"
			(at -0.128 -1.345 90)
			(layer "F.SilkS")
			(hide yes)
			(effects
				(font
					(size 0.7 0.7)
					(thickness 0.15)
				)
				(justify left bottom)
			)
		)
		(property "Value" "Net-Tie_2"
			(at 0 1.199 90)
			(layer "F.Fab")
			(effects
				(font
					(size 0.7 0.7)
					(thickness 0.15)
				)
				(justify left bottom)
			)
		)
		(property "Description" "Net tie, 2 pins"
			(at 0 0 90)
			(layer "F.Fab")
			(hide yes)
			(effects
				(font
					(size 1.27 1.27)
					(thickness 0.15)
				)
			)
		)
		(property "Author" "Antmicro"
			(at 391.302 -104.098 0)
			(layer "F.Fab")
			(hide yes)
			(effects
				(font
					(size 1 1)
					(thickness 0.15)
				)
			)
		)
		(property "License" "Apache-2.0"
			(at 391.302 -104.098 0)
			(layer "F.Fab")
			(hide yes)
			(effects
				(font
					(size 1 1)
					(thickness 0.15)
				)
			)
		)
		(property "MPN" ""
			(at 391.302 -104.098 0)
			(layer "F.Fab")
			(hide yes)
			(effects
				(font
					(size 1 1)
					(thickness 0.15)
				)
			)
		)
		(property "Manufacturer" ""
			(at 391.302 -104.098 0)
			(layer "F.Fab")
			(hide yes)
			(effects
				(font
					(size 1 1)
					(thickness 0.15)
				)
			)
		)
		(sheetname "FPGA Config")
		(sheetfile "fpga-config.kicad_sch")
		(attr exclude_from_pos_files)
		(net_tie_pad_groups "1, 2")
		(fp_poly
			(pts
				(xy -0.0635 -0.0635) (xy 0.0625 -0.0635) (xy 0.0625 0.0635) (xy -0.0635 0.0635)
			)
			(stroke
				(width 0)
				(type solid)
			)
			(fill yes)
			(layer "F.Cu")
		)
		(pad "1" smd roundrect
			(at -0.127 0 270)
			(size 0.127 0.127)
			(layers "F.Cu")
			(roundrect_rratio 0.5)
			(chamfer_ratio 0)
			(chamfer top_left bottom_left)
			(net 1312 "/SUP_MCU.FPGA_M0")
			(pinfunction "1")
			(pintype "passive")
		)
		(pad "2" smd roundrect
			(at 0.126 0 90)
			(size 0.127 0.127)
			(layers "F.Cu")
			(roundrect_rratio 0.5)
			(chamfer_ratio 0)
			(chamfer top_left bottom_left)
			(net 300 "/FPGA Config/MODE0")
			(pinfunction "2")
			(pintype "passive")
		)
	)
	(footprint "antmicro-footprints:Onsemi_WLCSP6_1.40x0.90"
		(layer "F.Cu")
		(at 169.45 176)
		(property "Reference" "U34"
			(at -1.1 1.85 0)
			(layer "F.SilkS")
			(effects
				(font
					(size 0.7 0.7)
					(thickness 0.15)
				)
				(justify left bottom)
			)
		)
		(property "Value" "NCP451AFCT2G"
			(at -6.21 1.96 0)
			(layer "F.Fab")
			(effects
				(font
					(size 0.7 0.7)
					(thickness 0.15)
				)
				(justify left bottom)
			)
		)
		(property "Description" "Power Load Switch, High Side, Active High, 1 Output, 0.012 ohm On State, 5.5 V supp, 3 A, WLCSP-6"
			(at 0 0 0)
			(layer "F.Fab")
			(hide yes)
			(effects
				(font
					(size 1.27 1.27)
					(thickness 0.15)
				)
			)
		)
		(property "Author" "Antmicro"
			(at 0 0 0)
			(layer "F.Fab")
			(hide yes)
			(effects
				(font
					(size 1 1)
					(thickness 0.15)
				)
			)
		)
		(property "DNP" "DNP"
			(at 0 0 0)
			(layer "F.Fab")
			(hide yes)
			(effects
				(font
					(size 1 1)
					(thickness 0.15)
				)
			)
		)
		(property "License" "Apache-2.0"
			(at 0 0 0)
			(layer "F.Fab")
			(hide yes)
			(effects
				(font
					(size 1 1)
					(thickness 0.15)
				)
			)
		)
		(property "MPN" "NCP451AFCT2G"
			(at 0 0 0)
			(layer "F.Fab")
			(hide yes)
			(effects
				(font
					(size 1 1)
					(thickness 0.15)
				)
			)
		)
		(property "Manufacturer" "ON Semiconductor"
			(at 0 0 0)
			(layer "F.Fab")
			(hide yes)
			(effects
				(font
					(size 1 1)
					(thickness 0.15)
				)
			)
		)
		(property "dnp" ""
			(at 0 0 0)
			(layer "F.Fab")
			(hide yes)
			(effects
				(font
					(size 1 1)
					(thickness 0.15)
				)
			)
		)
		(property "exclude_from_bom" ""
			(at 0 0 0)
			(layer "F.Fab")
			(hide yes)
			(effects
				(font
					(size 1 1)
					(thickness 0.15)
				)
			)
		)
		(sheetname "DC-DC Converters")
		(sheetfile "dc-dc.kicad_sch")
		(attr smd exclude_from_bom)
		(fp_line
			(start -0.5 -0.47)
			(end -0.5 -0.77)
			(stroke
				(width 0.15)
				(type solid)
			)
			(layer "F.SilkS")
		)
		(fp_line
			(start -0.5 0.47)
			(end -0.5 0.77)
			(stroke
				(width 0.15)
				(type solid)
			)
			(layer "F.SilkS")
		)
		(fp_line
			(start -0.2 -0.77)
			(end -0.5 -0.77)
			(stroke
				(width 0.15)
				(type solid)
			)
			(layer "F.SilkS")
		)
		(fp_line
			(start -0.2 0.77)
			(end -0.5 0.77)
			(stroke
				(width 0.15)
				(type solid)
			)
			(layer "F.SilkS")
		)
		(fp_line
			(start 0.2 -0.77)
			(end 0.5 -0.77)
			(stroke
				(width 0.15)
				(type solid)
			)
			(layer "F.SilkS")
		)
		(fp_line
			(start 0.2 0.77)
			(end 0.5 0.77)
			(stroke
				(width 0.15)
				(type solid)
			)
			(layer "F.SilkS")
		)
		(fp_line
			(start 0.5 -0.47)
			(end 0.5 -0.77)
			(stroke
				(width 0.15)
				(type solid)
			)
			(layer "F.SilkS")
		)
		(fp_line
			(start 0.5 0.47)
			(end 0.5 0.77)
			(stroke
				(width 0.15)
				(type solid)
			)
			(layer "F.SilkS")
		)
		(fp_circle
			(center -0.77 -0.5)
			(end -0.724 -0.5)
			(stroke
				(width 0.15)
				(type solid)
			)
			(fill yes)
			(layer "F.SilkS")
		)
		(fp_rect
			(start -0.953 -1.201)
			(end 0.951 1.199)
			(stroke
				(width 0.05)
				(type solid)
			)
			(fill no)
			(layer "F.CrtYd")
		)
		(fp_line
			(start -0.454 0.698)
			(end -0.454 -0.701)
			(stroke
				(width 0.15)
				(type solid)
			)
			(layer "F.Fab")
		)
		(fp_line
			(start -0.25 -0.69)
			(end -0.45 -0.49)
			(stroke
				(width 0.15)
				(type solid)
			)
			(layer "F.Fab")
		)
		(fp_line
			(start 0.451 -0.701)
			(end -0.454 -0.701)
			(stroke
				(width 0.15)
				(type solid)
			)
			(layer "F.Fab")
		)
		(fp_line
			(start 0.451 0.698)
			(end -0.454 0.698)
			(stroke
				(width 0.15)
				(type solid)
			)
			(layer "F.Fab")
		)
		(fp_line
			(start 0.451 0.698)
			(end 0.451 -0.701)
			(stroke
				(width 0.15)
				(type solid)
			)
			(layer "F.Fab")
		)
		(pad "A1" smd circle
			(at -0.249 -0.499)
			(size 0.25 0.25)
			(layers "F.Cu" "F.Mask" "F.Paste")
			(net 25 "+1V35")
			(pinfunction "OUT")
			(pintype "power_out")
		)
		(pad "A2" smd circle
			(at 0.246 -0.499)
			(size 0.25 0.25)
			(layers "F.Cu" "F.Mask" "F.Paste")
			(net 740 "/DC-DC Converters/1V35_local")
			(pinfunction "IN")
			(pintype "power_in")
		)
		(pad "B1" smd circle
			(at -0.249 0.001)
			(size 0.25 0.25)
			(layers "F.Cu" "F.Mask" "F.Paste")
			(net 25 "+1V35")
			(pinfunction "OUT")
			(pintype "passive")
		)
		(pad "B2" smd circle
			(at 0.246 0.001)
			(size 0.25 0.25)
			(layers "F.Cu" "F.Mask" "F.Paste")
			(net 740 "/DC-DC Converters/1V35_local")
			(pinfunction "IN")
			(pintype "passive")
		)
		(pad "C1" smd circle
			(at -0.249 0.496)
			(size 0.25 0.25)
			(layers "F.Cu" "F.Mask" "F.Paste")
			(net 1 "GND")
			(pinfunction "GND")
			(pintype "power_in")
		)
		(pad "C2" smd circle
			(at 0.246 0.496)
			(size 0.25 0.25)
			(layers "F.Cu" "F.Mask" "F.Paste")
			(net 1053 "/DC-DC Converters/PB_CTRL.VDDR_EN")
			(pinfunction "EN")
			(pintype "input")
		)
	)
	(footprint "antmicro-footprints:R_0402_1005Metric"
		(layer "F.Cu")
		(at 164.0625 168.6 90)
		(descr "Resistor SMD 0402")
		(tags "resistor SMD 0402")
		(property "Reference" "R298"
			(at -1 1.2375 90)
			(layer "F.SilkS")
			(effects
				(font
					(size 0.7 0.7)
					(thickness 0.15)
				)
				(justify left bottom)
			)
		)
		(property "Value" "R_0R_0402"
			(at 0 1.4 90)
			(layer "F.Fab")
			(effects
				(font
					(size 0.7 0.7)
					(thickness 0.15)
				)
				(justify left bottom)
			)
		)
		(property "Description" "SMD Chip Resistor, Jumper, 0 ohm, 100 mW, 0402 [1005 Metric], Thick Film, General Purpose"
			(at 0 0 90)
			(layer "F.Fab")
			(hide yes)
			(effects
				(font
					(size 1.27 1.27)
					(thickness 0.15)
				)
			)
		)
		(property "Author" "Antmicro"
			(at 332.6625 4.5375 0)
			(layer "F.Fab")
			(hide yes)
			(effects
				(font
					(size 1 1)
					(thickness 0.15)
				)
			)
		)
		(property "Current" "1A"
			(at 332.6625 4.5375 0)
			(layer "F.Fab")
			(hide yes)
			(effects
				(font
					(size 1 1)
					(thickness 0.15)
				)
			)
		)
		(property "License" "Apache-2.0"
			(at 332.6625 4.5375 0)
			(layer "F.Fab")
			(hide yes)
			(effects
				(font
					(size 1 1)
					(thickness 0.15)
				)
			)
		)
		(property "MPN" "ERJ2GE0R00X"
			(at 332.6625 4.5375 0)
			(layer "F.Fab")
			(hide yes)
			(effects
				(font
					(size 1 1)
					(thickness 0.15)
				)
			)
		)
		(property "Manufacturer" "Panasonic"
			(at 332.6625 4.5375 0)
			(layer "F.Fab")
			(hide yes)
			(effects
				(font
					(size 1 1)
					(thickness 0.15)
				)
			)
		)
		(property "Tolerance" ""
			(at 332.6625 4.5375 0)
			(layer "F.Fab")
			(hide yes)
			(effects
				(font
					(size 1 1)
					(thickness 0.15)
				)
			)
		)
		(property "Val" "0R"
			(at 332.6625 4.5375 0)
			(layer "F.Fab")
			(hide yes)
			(effects
				(font
					(size 1 1)
					(thickness 0.15)
				)
			)
		)
		(sheetname "DC-DC Converters")
		(sheetfile "dc-dc.kicad_sch")
		(attr smd)
		(fp_rect
			(start -0.925 -0.47)
			(end 0.925 0.47)
			(stroke
				(width 0.05)
				(type default)
			)
			(fill no)
			(layer "F.CrtYd")
		)
		(fp_rect
			(start -0.5 -0.25)
			(end 0.5 0.25)
			(stroke
				(width 0.15)
				(type solid)
			)
			(fill no)
			(layer "F.Fab")
		)
		(pad "1" smd roundrect
			(at -0.48 0 90)
			(size 0.59 0.64)
			(layers "F.Cu" "F.Mask" "F.Paste")
			(roundrect_rratio 0.25)
			(net 960 "/DC-DC Converters/FB2")
			(pintype "passive")
		)
		(pad "2" smd roundrect
			(at 0.48 0 90)
			(size 0.59 0.64)
			(layers "F.Cu" "F.Mask" "F.Paste")
			(roundrect_rratio 0.25)
			(net 734 "/DC-DC Converters/1V8_local")
			(pintype "passive")
		)
	)
	(footprint "antmicro-footprints:QFN-56-1EP_8x8mm_P0.5mm"
		(layer "F.Cu")
		(at 248.4 135.9 180)
		(descr "QFN 56 Pin")
		(tags "QFN")
		(property "Reference" "U20"
			(at 1.82 4.7 180)
			(layer "F.SilkS")
			(effects
				(font
					(size 0.7 0.7)
					(thickness 0.15)
				)
				(justify left bottom)
			)
		)
		(property "Value" "FT4232H_VQFN"
			(at 0 5.32 180)
			(layer "F.Fab")
			(effects
				(font
					(size 0.7 0.7)
					(thickness 0.15)
				)
				(justify left bottom)
			)
		)
		(property "Description" "Interface Bridges, USB to UART, MPSSE, 1.62 V, 1.98 V, VQFN, 56 Pins, -40 °C"
			(at 0 0 180)
			(layer "F.Fab")
			(hide yes)
			(effects
				(font
					(size 1.27 1.27)
					(thickness 0.15)
				)
			)
		)
		(property "Author" "Antmicro"
			(at 496.8 271.8 0)
			(layer "F.Fab")
			(hide yes)
			(effects
				(font
					(size 1 1)
					(thickness 0.15)
				)
			)
		)
		(property "License" "Apache-2.0"
			(at 496.8 271.8 0)
			(layer "F.Fab")
			(hide yes)
			(effects
				(font
					(size 1 1)
					(thickness 0.15)
				)
			)
		)
		(property "MPN" "FT4232H-56Q-REEL"
			(at 496.8 271.8 0)
			(layer "F.Fab")
			(hide yes)
			(effects
				(font
					(size 1 1)
					(thickness 0.15)
				)
			)
		)
		(property "Manufacturer" "FTDI Chip"
			(at 496.8 271.8 0)
			(layer "F.Fab")
			(hide yes)
			(effects
				(font
					(size 1 1)
					(thickness 0.15)
				)
			)
		)
		(sheetname "USB PHY")
		(sheetfile "usb-phy.kicad_sch")
		(attr smd)
		(fp_line
			(start 4.11 4.11)
			(end 4.11 3.634)
			(stroke
				(width 0.15)
				(type solid)
			)
			(layer "F.SilkS")
		)
		(fp_line
			(start 4.11 -4.111)
			(end 4.11 -3.635)
			(stroke
				(width 0.15)
				(type solid)
			)
			(layer "F.SilkS")
		)
		(fp_line
			(start 3.634 4.11)
			(end 4.11 4.11)
			(stroke
				(width 0.15)
				(type solid)
			)
			(layer "F.SilkS")
		)
		(fp_line
			(start 3.634 -4.111)
			(end 4.11 -4.111)
			(stroke
				(width 0.15)
				(type solid)
			)
			(layer "F.SilkS")
		)
		(fp_line
			(start -3.635 4.11)
			(end -4.111 4.11)
			(stroke
				(width 0.15)
				(type solid)
			)
			(layer "F.SilkS")
		)
		(fp_line
			(start -3.635 -4.111)
			(end -4.111 -4.111)
			(stroke
				(width 0.15)
				(type solid)
			)
			(layer "F.SilkS")
		)
		(fp_line
			(start -4.111 4.11)
			(end -4.111 3.634)
			(stroke
				(width 0.15)
				(type solid)
			)
			(layer "F.SilkS")
		)
		(fp_line
			(start -4.111 -3.635)
			(end -4.111 -4.111)
			(stroke
				(width 0.15)
				(type solid)
			)
			(layer "F.SilkS")
		)
		(fp_circle
			(center -4.35 -3.6)
			(end -4.3 -3.6)
			(stroke
				(width 0.15)
				(type solid)
			)
			(fill yes)
			(layer "F.SilkS")
		)
		(fp_rect
			(start 4.4 4.4)
			(end -4.4 -4.4)
			(stroke
				(width 0.05)
				(type solid)
			)
			(fill no)
			(layer "F.CrtYd")
		)
		(fp_line
			(start -4 -3)
			(end -3 -4)
			(stroke
				(width 0.15)
				(type solid)
			)
			(layer "F.Fab")
		)
		(fp_rect
			(start 4 4)
			(end -4 -4)
			(stroke
				(width 0.15)
				(type solid)
			)
			(fill no)
			(layer "F.Fab")
		)
		(pad "" smd roundrect
			(at -2.101 -2.101 180)
			(size 1.13 1.13)
			(layers "F.Paste")
			(roundrect_rratio 0.221239)
		)
		(pad "" smd roundrect
			(at -2.101 -0.7 180)
			(size 1.13 1.13)
			(layers "F.Paste")
			(roundrect_rratio 0.221239)
		)
		(pad "" smd roundrect
			(at -2.101 0.699 180)
			(size 1.13 1.13)
			(layers "F.Paste")
			(roundrect_rratio 0.221239)
		)
		(pad "" smd roundrect
			(at -2.101 2.1 180)
			(size 1.13 1.13)
			(layers "F.Paste")
			(roundrect_rratio 0.221239)
		)
		(pad "" smd roundrect
			(at -0.7 -2.101 180)
			(size 1.13 1.13)
			(layers "F.Paste")
			(roundrect_rratio 0.221239)
		)
		(pad "" smd roundrect
			(at -0.7 -0.7 180)
			(size 1.13 1.13)
			(layers "F.Paste")
			(roundrect_rratio 0.221239)
		)
		(pad "" smd roundrect
			(at -0.7 0.699 180)
			(size 1.13 1.13)
			(layers "F.Paste")
			(roundrect_rratio 0.221239)
		)
		(pad "" smd roundrect
			(at -0.7 2.1 180)
			(size 1.13 1.13)
			(layers "F.Paste")
			(roundrect_rratio 0.221239)
		)
		(pad "" smd roundrect
			(at 0.699 -2.101 180)
			(size 1.13 1.13)
			(layers "F.Paste")
			(roundrect_rratio 0.221239)
		)
		(pad "" smd roundrect
			(at 0.699 -0.7 180)
			(size 1.13 1.13)
			(layers "F.Paste")
			(roundrect_rratio 0.221239)
		)
		(pad "" smd roundrect
			(at 0.699 0.699 180)
			(size 1.13 1.13)
			(layers "F.Paste")
			(roundrect_rratio 0.221239)
		)
		(pad "" smd roundrect
			(at 0.699 2.1 180)
			(size 1.13 1.13)
			(layers "F.Paste")
			(roundrect_rratio 0.221239)
		)
		(pad "" smd roundrect
			(at 2.1 -2.101 180)
			(size 1.13 1.13)
			(layers "F.Paste")
			(roundrect_rratio 0.221239)
		)
		(pad "" smd roundrect
			(at 2.1 -0.7 180)
			(size 1.13 1.13)
			(layers "F.Paste")
			(roundrect_rratio 0.221239)
		)
		(pad "" smd roundrect
			(at 2.1 0.699 180)
			(size 1.13 1.13)
			(layers "F.Paste")
			(roundrect_rratio 0.221239)
		)
		(pad "" smd roundrect
			(at 2.1 2.1 180)
			(size 1.13 1.13)
			(layers "F.Paste")
			(roundrect_rratio 0.221239)
		)
		(pad "1" smd roundrect
			(at -3.938 -3.25 180)
			(size 0.875 0.3)
			(layers "F.Cu" "F.Mask" "F.Paste")
			(roundrect_rratio 0.25)
			(net 997 "/USB PHY/FTDI_EECS")
			(pinfunction "EECS")
			(pintype "bidirectional")
		)
		(pad "2" smd roundrect
			(at -3.938 -2.75 180)
			(size 0.875 0.3)
			(layers "F.Cu" "F.Mask" "F.Paste")
			(roundrect_rratio 0.25)
			(net 712 "/USB PHY/FTDI_VCORE")
			(pinfunction "V_{CORE}")
			(pintype "power_in")
		)
		(pad "3" smd roundrect
			(at -3.938 -2.25 180)
			(size 0.875 0.3)
			(layers "F.Cu" "F.Mask" "F.Paste")
			(roundrect_rratio 0.25)
			(net 710 "/USB PHY/FTDI_XI")
			(pinfunction "OSCI")
			(pintype "input")
		)
		(pad "4" smd roundrect
			(at -3.938 -1.75 180)
			(size 0.875 0.3)
			(layers "F.Cu" "F.Mask" "F.Paste")
			(roundrect_rratio 0.25)
			(net 713 "/USB PHY/FTDI_XO")
			(pinfunction "OSCO")
			(pintype "output")
		)
		(pad "5" smd roundrect
			(at -3.938 -1.25 180)
			(size 0.875 0.3)
			(layers "F.Cu" "F.Mask" "F.Paste")
			(roundrect_rratio 0.25)
			(net 714 "/USB PHY/FTDI_VPHY")
			(pinfunction "V_{PHY}")
			(pintype "power_in")
		)
		(pad "6" smd roundrect
			(at -3.938 -0.75 180)
			(size 0.875 0.3)
			(layers "F.Cu" "F.Mask" "F.Paste")
			(roundrect_rratio 0.25)
			(net 920 "/USB PHY/FTDI_REF")
			(pinfunction "REF")
			(pintype "input")
		)
		(pad "7" smd roundrect
			(at -3.938 -0.25 180)
			(size 0.875 0.3)
			(layers "F.Cu" "F.Mask" "F.Paste")
			(roundrect_rratio 0.25)
			(net 839 "/USB PHY/USB_DBG_CONN_D-")
			(pinfunction "D-")
			(pintype "bidirectional")
		)
		(pad "8" smd roundrect
			(at -3.938 0.249 180)
			(size 0.875 0.3)
			(layers "F.Cu" "F.Mask" "F.Paste")
			(roundrect_rratio 0.25)
			(net 838 "/USB PHY/USB_DBG_CONN_D+")
			(pinfunction "D+")
			(pintype "bidirectional")
		)
		(pad "9" smd roundrect
			(at -3.938 0.749 180)
			(size 0.875 0.3)
			(layers "F.Cu" "F.Mask" "F.Paste")
			(roundrect_rratio 0.25)
			(net 711 "/USB PHY/FTDI_VPLL")
			(pinfunction "V_{PLL}")
			(pintype "power_in")
		)
		(pad "10" smd roundrect
			(at -3.938 1.249 180)
			(size 0.875 0.3)
			(layers "F.Cu" "F.Mask" "F.Paste")
			(roundrect_rratio 0.25)
			(net 1 "GND")
			(pinfunction "TEST")
			(pintype "input")
		)
		(pad "11" smd roundrect
			(at -3.938 1.749 180)
			(size 0.875 0.3)
			(layers "F.Cu" "F.Mask" "F.Paste")
			(roundrect_rratio 0.25)
			(net 919 "/USB PHY/FTDI_RST")
			(pinfunction "~{RESET}")
			(pintype "input")
		)
		(pad "12" smd roundrect
			(at -3.938 2.249 180)
			(size 0.875 0.3)
			(layers "F.Cu" "F.Mask" "F.Paste")
			(roundrect_rratio 0.25)
			(net 1015 "/USB PHY/FTDI_JTAG_TCK")
			(pinfunction "ADBUS0")
			(pintype "bidirectional")
		)
		(pad "13" smd roundrect
			(at -3.938 2.749 180)
			(size 0.875 0.3)
			(layers "F.Cu" "F.Mask" "F.Paste")
			(roundrect_rratio 0.25)
			(net 1016 "/USB PHY/FTDI_JTAG_TDI")
			(pinfunction "ADBUS1")
			(pintype "bidirectional")
		)
		(pad "14" smd roundrect
			(at -3.938 3.249 180)
			(size 0.875 0.3)
			(layers "F.Cu" "F.Mask" "F.Paste")
			(roundrect_rratio 0.25)
			(net 1017 "/USB PHY/FTDI_JTAG_TDO")
			(pinfunction "ADBUS2")
			(pintype "bidirectional")
		)
		(pad "15" smd roundrect
			(at -3.25 3.937 270)
			(size 0.875 0.3)
			(layers "F.Cu" "F.Mask" "F.Paste")
			(roundrect_rratio 0.25)
			(net 1018 "/USB PHY/FTDI_JTAG_TMS")
			(pinfunction "ADBUS3")
			(pintype "bidirectional")
		)
		(pad "16" smd roundrect
			(at -2.75 3.937 270)
			(size 0.875 0.3)
			(layers "F.Cu" "F.Mask" "F.Paste")
			(roundrect_rratio 0.25)
			(net 707 "/USB PHY/FTDI_3V3")
			(pinfunction "V_{CCIO}")
			(pintype "power_in")
		)
		(pad "17" smd roundrect
			(at -2.25 3.937 270)
			(size 0.875 0.3)
			(layers "F.Cu" "F.Mask" "F.Paste")
			(roundrect_rratio 0.25)
			(net 1182 "unconnected-(U20-ADBUS4-Pad17)")
			(pinfunction "ADBUS4")
			(pintype "bidirectional+no_connect")
		)
		(pad "18" smd roundrect
			(at -1.75 3.937 270)
			(size 0.875 0.3)
			(layers "F.Cu" "F.Mask" "F.Paste")
			(roundrect_rratio 0.25)
			(net 1020 "/USB PHY/FTDI_JTAG_RST")
			(pinfunction "ADBUS5")
			(pintype "bidirectional")
		)
		(pad "19" smd roundrect
			(at -1.25 3.937 270)
			(size 0.875 0.3)
			(layers "F.Cu" "F.Mask" "F.Paste")
			(roundrect_rratio 0.25)
			(net 1183 "unconnected-(U20-ADBUS6-Pad19)")
			(pinfunction "ADBUS6")
			(pintype "bidirectional+no_connect")
		)
		(pad "20" smd roundrect
			(at -0.75 3.937 270)
			(size 0.875 0.3)
			(layers "F.Cu" "F.Mask" "F.Paste")
			(roundrect_rratio 0.25)
			(net 1184 "unconnected-(U20-ADBUS7-Pad20)")
			(pinfunction "ADBUS7")
			(pintype "bidirectional+no_connect")
		)
		(pad "21" smd roundrect
			(at -0.25 3.937 270)
			(size 0.875 0.3)
			(layers "F.Cu" "F.Mask" "F.Paste")
			(roundrect_rratio 0.25)
			(net 1 "GND")
			(pinfunction "GND")
			(pintype "power_in")
		)
		(pad "22" smd roundrect
			(at 0.249 3.937 270)
			(size 0.875 0.3)
			(layers "F.Cu" "F.Mask" "F.Paste")
			(roundrect_rratio 0.25)
			(net 1023 "/USB PHY/BDBUS0")
			(pinfunction "BDBUS0")
			(pintype "bidirectional")
		)
		(pad "23" smd roundrect
			(at 0.749 3.937 270)
			(size 0.875 0.3)
			(layers "F.Cu" "F.Mask" "F.Paste")
			(roundrect_rratio 0.25)
			(net 1024 "/USB PHY/BDBUS1")
			(pinfunction "BDBUS1")
			(pintype "bidirectional")
		)
		(pad "24" smd roundrect
			(at 1.249 3.937 270)
			(size 0.875 0.3)
			(layers "F.Cu" "F.Mask" "F.Paste")
			(roundrect_rratio 0.25)
			(net 1025 "/USB PHY/BDBUS2")
			(pinfunction "BDBUS2")
			(pintype "bidirectional")
		)
		(pad "25" smd roundrect
			(at 1.749 3.937 270)
			(size 0.875 0.3)
			(layers "F.Cu" "F.Mask" "F.Paste")
			(roundrect_rratio 0.25)
			(net 925 "/USB PHY/BDBUS3")
			(pinfunction "BDBUS3")
			(pintype "bidirectional")
		)
		(pad "26" smd roundrect
			(at 2.249 3.937 270)
			(size 0.875 0.3)
			(layers "F.Cu" "F.Mask" "F.Paste")
			(roundrect_rratio 0.25)
			(net 934 "/USB PHY/SPI_EN")
			(pinfunction "BDBUS4")
			(pintype "bidirectional")
		)
		(pad "27" smd roundrect
			(at 2.749 3.937 270)
			(size 0.875 0.3)
			(layers "F.Cu" "F.Mask" "F.Paste")
			(roundrect_rratio 0.25)
			(net 940 "/USB PHY/I2C_EN")
			(pinfunction "BDBUS5")
			(pintype "bidirectional")
		)
		(pad "28" smd roundrect
			(at 3.249 3.937 270)
			(size 0.875 0.3)
			(layers "F.Cu" "F.Mask" "F.Paste")
			(roundrect_rratio 0.25)
			(net 1185 "unconnected-(U20-BDBUS6-Pad28)")
			(pinfunction "BDBUS6")
			(pintype "bidirectional+no_connect")
		)
		(pad "29" smd roundrect
			(at 3.937 3.249 180)
			(size 0.875 0.3)
			(layers "F.Cu" "F.Mask" "F.Paste")
			(roundrect_rratio 0.25)
			(net 1186 "unconnected-(U20-BDBUS7-Pad29)")
			(pinfunction "BDBUS7")
			(pintype "bidirectional+no_connect")
		)
		(pad "30" smd roundrect
			(at 3.937 2.749 180)
			(size 0.875 0.3)
			(layers "F.Cu" "F.Mask" "F.Paste")
			(roundrect_rratio 0.25)
			(net 1187 "unconnected-(U20-~{SUSPEND}-Pad30)")
			(pinfunction "~{SUSPEND}")
			(pintype "output+no_connect")
		)
		(pad "31" smd roundrect
			(at 3.937 2.249 180)
			(size 0.875 0.3)
			(layers "F.Cu" "F.Mask" "F.Paste")
			(roundrect_rratio 0.25)
			(net 712 "/USB PHY/FTDI_VCORE")
			(pinfunction "V_{CORE}")
			(pintype "passive")
		)
		(pad "32" smd roundrect
			(at 3.937 1.749 180)
			(size 0.875 0.3)
			(layers "F.Cu" "F.Mask" "F.Paste")
			(roundrect_rratio 0.25)
			(net 921 "/USB PHY/FTDI_UART0_TX")
			(pinfunction "CDBUS0")
			(pintype "bidirectional")
		)
		(pad "33" smd roundrect
			(at 3.937 1.249 180)
			(size 0.875 0.3)
			(layers "F.Cu" "F.Mask" "F.Paste")
			(roundrect_rratio 0.25)
			(net 922 "/USB PHY/FTDI_UART0_RX")
			(pinfunction "CDBUS1")
			(pintype "bidirectional")
		)
		(pad "34" smd roundrect
			(at 3.937 0.749 180)
			(size 0.875 0.3)
			(layers "F.Cu" "F.Mask" "F.Paste")
			(roundrect_rratio 0.25)
			(net 1188 "unconnected-(U20-CDBUS2-Pad34)")
			(pinfunction "CDBUS2")
			(pintype "bidirectional+no_connect")
		)
		(pad "35" smd roundrect
			(at 3.937 0.249 180)
			(size 0.875 0.3)
			(layers "F.Cu" "F.Mask" "F.Paste")
			(roundrect_rratio 0.25)
			(net 1189 "unconnected-(U20-CDBUS3-Pad35)")
			(pinfunction "CDBUS3")
			(pintype "bidirectional+no_connect")
		)
		(pad "36" smd roundrect
			(at 3.937 -0.25 180)
			(size 0.875 0.3)
			(layers "F.Cu" "F.Mask" "F.Paste")
			(roundrect_rratio 0.25)
			(net 707 "/USB PHY/FTDI_3V3")
			(pinfunction "V_{CCIO}")
			(pintype "passive")
		)
		(pad "37" smd roundrect
			(at 3.937 -0.75 180)
			(size 0.875 0.3)
			(layers "F.Cu" "F.Mask" "F.Paste")
			(roundrect_rratio 0.25)
			(net 1190 "unconnected-(U20-CDBUS4-Pad37)")
			(pinfunction "CDBUS4")
			(pintype "bidirectional+no_connect")
		)
		(pad "38" smd roundrect
			(at 3.937 -1.25 180)
			(size 0.875 0.3)
			(layers "F.Cu" "F.Mask" "F.Paste")
			(roundrect_rratio 0.25)
			(net 1196 "unconnected-(U20-CDBUS5-Pad38)")
			(pinfunction "CDBUS5")
			(pintype "bidirectional+no_connect")
		)
		(pad "39" smd roundrect
			(at 3.937 -1.75 180)
			(size 0.875 0.3)
			(layers "F.Cu" "F.Mask" "F.Paste")
			(roundrect_rratio 0.25)
			(net 1197 "unconnected-(U20-CDBUS6-Pad39)")
			(pinfunction "CDBUS6")
			(pintype "bidirectional+no_connect")
		)
		(pad "40" smd roundrect
			(at 3.937 -2.25 180)
			(size 0.875 0.3)
			(layers "F.Cu" "F.Mask" "F.Paste")
			(roundrect_rratio 0.25)
			(net 1198 "unconnected-(U20-CDBUS7-Pad40)")
			(pinfunction "CDBUS7")
			(pintype "bidirectional+no_connect")
		)
		(pad "41" smd roundrect
			(at 3.937 -2.75 180)
			(size 0.875 0.3)
			(layers "F.Cu" "F.Mask" "F.Paste")
			(roundrect_rratio 0.25)
			(net 1 "GND")
			(pinfunction "GND")
			(pintype "passive")
		)
		(pad "42" smd roundrect
			(at 3.937 -3.25 180)
			(size 0.875 0.3)
			(layers "F.Cu" "F.Mask" "F.Paste")
			(roundrect_rratio 0.25)
			(net 923 "/USB PHY/FTDI_UART1_TX")
			(pinfunction "DDBUS0")
			(pintype "bidirectional")
		)
		(pad "43" smd roundrect
			(at 3.249 -3.938 270)
			(size 0.875 0.3)
			(layers "F.Cu" "F.Mask" "F.Paste")
			(roundrect_rratio 0.25)
			(net 712 "/USB PHY/FTDI_VCORE")
			(pinfunction "V_{REGOUT}")
			(pintype "power_out")
		)
		(pad "44" smd roundrect
			(at 2.749 -3.938 270)
			(size 0.875 0.3)
			(layers "F.Cu" "F.Mask" "F.Paste")
			(roundrect_rratio 0.25)
			(net 707 "/USB PHY/FTDI_3V3")
			(pinfunction "V_{REGIN}")
			(pintype "power_in")
		)
		(pad "45" smd roundrect
			(at 2.249 -3.938 270)
			(size 0.875 0.3)
			(layers "F.Cu" "F.Mask" "F.Paste")
			(roundrect_rratio 0.25)
			(net 1 "GND")
			(pinfunction "GND")
			(pintype "passive")
		)
		(pad "46" smd roundrect
			(at 1.749 -3.938 270)
			(size 0.875 0.3)
			(layers "F.Cu" "F.Mask" "F.Paste")
			(roundrect_rratio 0.25)
			(net 924 "/USB PHY/FTDI_UART1_RX")
			(pinfunction "DDBUS1")
			(pintype "bidirectional")
		)
		(pad "47" smd roundrect
			(at 1.249 -3.938 270)
			(size 0.875 0.3)
			(layers "F.Cu" "F.Mask" "F.Paste")
			(roundrect_rratio 0.25)
			(net 1199 "unconnected-(U20-DDBUS2-Pad47)")
			(pinfunction "DDBUS2")
			(pintype "bidirectional+no_connect")
		)
		(pad "48" smd roundrect
			(at 0.749 -3.938 270)
			(size 0.875 0.3)
			(layers "F.Cu" "F.Mask" "F.Paste")
			(roundrect_rratio 0.25)
			(net 1200 "unconnected-(U20-DDBUS3-Pad48)")
			(pinfunction "DDBUS3")
			(pintype "bidirectional+no_connect")
		)
		(pad "49" smd roundrect
			(at 0.249 -3.938 270)
			(size 0.875 0.3)
			(layers "F.Cu" "F.Mask" "F.Paste")
			(roundrect_rratio 0.25)
			(net 1201 "unconnected-(U20-DDBUS4-Pad49)")
			(pinfunction "DDBUS4")
			(pintype "bidirectional+no_connect")
		)
		(pad "50" smd roundrect
			(at -0.25 -3.938 270)
			(size 0.875 0.3)
			(layers "F.Cu" "F.Mask" "F.Paste")
			(roundrect_rratio 0.25)
			(net 707 "/USB PHY/FTDI_3V3")
			(pinfunction "V_{CCIO}")
			(pintype "passive")
		)
		(pad "51" smd roundrect
			(at -0.75 -3.938 270)
			(size 0.875 0.3)
			(layers "F.Cu" "F.Mask" "F.Paste")
			(roundrect_rratio 0.25)
			(net 1202 "unconnected-(U20-DDBUS5-Pad51)")
			(pinfunction "DDBUS5")
			(pintype "bidirectional+no_connect")
		)
		(pad "52" smd roundrect
			(at -1.25 -3.938 270)
			(size 0.875 0.3)
			(layers "F.Cu" "F.Mask" "F.Paste")
			(roundrect_rratio 0.25)
			(net 1203 "unconnected-(U20-DDBUS6-Pad52)")
			(pinfunction "DDBUS6")
			(pintype "bidirectional+no_connect")
		)
		(pad "53" smd roundrect
			(at -1.75 -3.938 270)
			(size 0.875 0.3)
			(layers "F.Cu" "F.Mask" "F.Paste")
			(roundrect_rratio 0.25)
			(net 1204 "unconnected-(U20-DDBUS7-Pad53)")
			(pinfunction "DDBUS7")
			(pintype "bidirectional+no_connect")
		)
		(pad "54" smd roundrect
			(at -2.25 -3.938 270)
			(size 0.875 0.3)
			(layers "F.Cu" "F.Mask" "F.Paste")
			(roundrect_rratio 0.25)
			(net 918 "/USB PHY/FTDI_PWREN")
			(pinfunction "~{PWR_{EN}}")
			(pintype "output")
		)
		(pad "55" smd roundrect
			(at -2.75 -3.938 270)
			(size 0.875 0.3)
			(layers "F.Cu" "F.Mask" "F.Paste")
			(roundrect_rratio 0.25)
			(net 998 "/USB PHY/FTDI_EEDAT")
			(pinfunction "EEDATA")
			(pintype "bidirectional")
		)
		(pad "56" smd roundrect
			(at -3.25 -3.938 270)
			(size 0.875 0.3)
			(layers "F.Cu" "F.Mask" "F.Paste")
			(roundrect_rratio 0.25)
			(net 996 "/USB PHY/FTDI_EECLK")
			(pinfunction "EECLK")
			(pintype "output")
		)
		(pad "57" smd rect
			(at 0 0 180)
			(size 5.9 5.9)
			(layers "F.Cu" "F.Mask")
			(net 1 "GND")
			(pinfunction "GND")
			(pintype "passive")
		)
	)
	(footprint "antmicro-footprints:C_0402_1005Metric"
		(layer "F.Cu")
		(at 243.325 132.9 -90)
		(descr "Capacitor SMD 0402")
		(tags "capacitor SMD 0402")
		(property "Reference" "C241"
			(at 3.925 0.5 270)
			(layer "F.SilkS")
			(effects
				(font
					(size 0.7 0.7)
					(thickness 0.15)
				)
				(justify left bottom)
			)
		)
		(property "Value" "C_100n_0402"
			(at 0 1.169 270)
			(layer "F.Fab")
			(effects
				(font
					(size 0.7 0.7)
					(thickness 0.15)
				)
				(justify left bottom)
			)
		)
		(property "Description" "SMD Multilayer Ceramic Capacitor, 0.1 µF, 50 V, 0402 [1005 Metric], ± 10%, X5R, GRM Series"
			(at 0 0 270)
			(layer "F.Fab")
			(hide yes)
			(effects
				(font
					(size 1.27 1.27)
					(thickness 0.15)
				)
			)
		)
		(property "Author" "Antmicro"
			(at 110.425 376.225 0)
			(layer "F.Fab")
			(hide yes)
			(effects
				(font
					(size 1 1)
					(thickness 0.15)
				)
			)
		)
		(property "Dielectric" "X5R"
			(at 110.425 376.225 0)
			(layer "F.Fab")
			(hide yes)
			(effects
				(font
					(size 1 1)
					(thickness 0.15)
				)
			)
		)
		(property "License" "Apache-2.0"
			(at 110.425 376.225 0)
			(layer "F.Fab")
			(hide yes)
			(effects
				(font
					(size 1 1)
					(thickness 0.15)
				)
			)
		)
		(property "MPN" "GRM155R61H104KE14D"
			(at 110.425 376.225 0)
			(layer "F.Fab")
			(hide yes)
			(effects
				(font
					(size 1 1)
					(thickness 0.15)
				)
			)
		)
		(property "Manufacturer" "Murata"
			(at 110.425 376.225 0)
			(layer "F.Fab")
			(hide yes)
			(effects
				(font
					(size 1 1)
					(thickness 0.15)
				)
			)
		)
		(property "Val" "100n"
			(at 110.425 376.225 0)
			(layer "F.Fab")
			(hide yes)
			(effects
				(font
					(size 1 1)
					(thickness 0.15)
				)
			)
		)
		(property "Voltage" "50V"
			(at 110.425 376.225 0)
			(layer "F.Fab")
			(hide yes)
			(effects
				(font
					(size 1 1)
					(thickness 0.15)
				)
			)
		)
		(sheetname "USB PHY")
		(sheetfile "usb-phy.kicad_sch")
		(attr smd)
		(fp_rect
			(start -0.925 -0.47)
			(end 0.925 0.47)
			(stroke
				(width 0.05)
				(type default)
			)
			(fill no)
			(layer "F.CrtYd")
		)
		(fp_line
			(start -0.494 0.248)
			(end -0.494 -0.25)
			(stroke
				(width 0.15)
				(type solid)
			)
			(layer "F.Fab")
		)
		(fp_line
			(start 0.504 0.248)
			(end -0.494 0.248)
			(stroke
				(width 0.15)
				(type solid)
			)
			(layer "F.Fab")
		)
		(fp_line
			(start -0.494 -0.25)
			(end 0.504 -0.25)
			(stroke
				(width 0.15)
				(type solid)
			)
			(layer "F.Fab")
		)
		(fp_line
			(start 0.504 -0.25)
			(end 0.504 0.248)
			(stroke
				(width 0.15)
				(type solid)
			)
			(layer "F.Fab")
		)
		(pad "1" smd roundrect
			(at -0.48 0 270)
			(size 0.59 0.64)
			(layers "F.Cu" "F.Mask" "F.Paste")
			(roundrect_rratio 0.25)
			(net 1 "GND")
			(pintype "passive")
		)
		(pad "2" smd roundrect
			(at 0.48 0 270)
			(size 0.59 0.64)
			(layers "F.Cu" "F.Mask" "F.Paste")
			(roundrect_rratio 0.25)
			(net 712 "/USB PHY/FTDI_VCORE")
			(pintype "passive")
		)
	)
	(footprint "antmicro-footprints:R_0402_1005Metric"
		(layer "F.Cu")
		(at 218.8 158.95)
		(descr "Resistor SMD 0402")
		(tags "resistor SMD 0402")
		(property "Reference" "R11"
			(at -2.85 0.4 0)
			(layer "F.SilkS")
			(effects
				(font
					(size 0.7 0.7)
					(thickness 0.15)
				)
				(justify left bottom)
			)
		)
		(property "Value" "R_10k_0402"
			(at 0 1.4 0)
			(layer "F.Fab")
			(effects
				(font
					(size 0.7 0.7)
					(thickness 0.15)
				)
				(justify left bottom)
			)
		)
		(property "Description" "SMD Chip Resistor, 10 kohm, ± 1%, 62.5 mW, 0402 [1005 Metric], Thick Film, General Purpose"
			(at 0 0 0)
			(layer "F.Fab")
			(hide yes)
			(effects
				(font
					(size 1.27 1.27)
					(thickness 0.15)
				)
			)
		)
		(property "Author" "Antmicro"
			(at 0 0 0)
			(layer "F.Fab")
			(hide yes)
			(effects
				(font
					(size 1 1)
					(thickness 0.15)
				)
			)
		)
		(property "License" "Apache-2.0"
			(at 0 0 0)
			(layer "F.Fab")
			(hide yes)
			(effects
				(font
					(size 1 1)
					(thickness 0.15)
				)
			)
		)
		(property "MPN" "CR0402-FX-1002GLF"
			(at 0 0 0)
			(layer "F.Fab")
			(hide yes)
			(effects
				(font
					(size 1 1)
					(thickness 0.15)
				)
			)
		)
		(property "Manufacturer" "Bourns"
			(at 0 0 0)
			(layer "F.Fab")
			(hide yes)
			(effects
				(font
					(size 1 1)
					(thickness 0.15)
				)
			)
		)
		(property "Tolerance" "1%"
			(at 0 0 0)
			(layer "F.Fab")
			(hide yes)
			(effects
				(font
					(size 1 1)
					(thickness 0.15)
				)
			)
		)
		(property "Val" "10k"
			(at 0 0 0)
			(layer "F.Fab")
			(hide yes)
			(effects
				(font
					(size 1 1)
					(thickness 0.15)
				)
			)
		)
		(sheetname "FPGA Config")
		(sheetfile "fpga-config.kicad_sch")
		(attr smd)
		(fp_rect
			(start -0.925 -0.47)
			(end 0.925 0.47)
			(stroke
				(width 0.05)
				(type default)
			)
			(fill no)
			(layer "F.CrtYd")
		)
		(fp_rect
			(start -0.5 -0.25)
			(end 0.5 0.25)
			(stroke
				(width 0.15)
				(type solid)
			)
			(fill no)
			(layer "F.Fab")
		)
		(pad "1" smd roundrect
			(at -0.48 0)
			(size 0.59 0.64)
			(layers "F.Cu" "F.Mask" "F.Paste")
			(roundrect_rratio 0.25)
			(net 113 "/FPGA Config/TEMP_~{ALERT}")
			(pintype "passive")
		)
		(pad "2" smd roundrect
			(at 0.48 0)
			(size 0.59 0.64)
			(layers "F.Cu" "F.Mask" "F.Paste")
			(roundrect_rratio 0.25)
			(net 24 "+3V3")
			(pintype "passive")
		)
	)
	(footprint "antmicro-footprints:C_0402_1005Metric"
		(layer "F.Cu")
		(at 174.030001 131.000001 90)
		(descr "Capacitor SMD 0402")
		(tags "capacitor SMD 0402")
		(property "Reference" "C308"
			(at -3.699999 0.369999 90)
			(layer "F.SilkS")
			(effects
				(font
					(size 0.7 0.7)
					(thickness 0.15)
				)
				(justify left bottom)
			)
		)
		(property "Value" "C_100n_0402"
			(at 0 1.4 90)
			(layer "F.Fab")
			(effects
				(font
					(size 0.7 0.7)
					(thickness 0.15)
				)
				(justify left bottom)
			)
		)
		(property "Description" "SMD Multilayer Ceramic Capacitor, 0.1 µF, 50 V, 0402 [1005 Metric], ± 10%, X5R, GRM Series"
			(at 0 0 90)
			(layer "F.Fab")
			(hide yes)
			(effects
				(font
					(size 1.27 1.27)
					(thickness 0.15)
				)
			)
		)
		(property "Author" "Antmicro"
			(at 305.030002 -43.03 0)
			(layer "F.Fab")
			(hide yes)
			(effects
				(font
					(size 1 1)
					(thickness 0.15)
				)
			)
		)
		(property "Dielectric" "X5R"
			(at 305.030002 -43.03 0)
			(layer "F.Fab")
			(hide yes)
			(effects
				(font
					(size 1 1)
					(thickness 0.15)
				)
			)
		)
		(property "License" "Apache-2.0"
			(at 305.030002 -43.03 0)
			(layer "F.Fab")
			(hide yes)
			(effects
				(font
					(size 1 1)
					(thickness 0.15)
				)
			)
		)
		(property "MPN" "GRM155R61H104KE14D"
			(at 305.030002 -43.03 0)
			(layer "F.Fab")
			(hide yes)
			(effects
				(font
					(size 1 1)
					(thickness 0.15)
				)
			)
		)
		(property "Manufacturer" "Murata"
			(at 305.030002 -43.03 0)
			(layer "F.Fab")
			(hide yes)
			(effects
				(font
					(size 1 1)
					(thickness 0.15)
				)
			)
		)
		(property "Val" "100n"
			(at 305.030002 -43.03 0)
			(layer "F.Fab")
			(hide yes)
			(effects
				(font
					(size 1 1)
					(thickness 0.15)
				)
			)
		)
		(property "Voltage" "50V"
			(at 305.030002 -43.03 0)
			(layer "F.Fab")
			(hide yes)
			(effects
				(font
					(size 1 1)
					(thickness 0.15)
				)
			)
		)
		(sheetname "FMC+ HSPC")
		(sheetfile "fmc-hspc.kicad_sch")
		(attr smd)
		(fp_rect
			(start -0.925 -0.47)
			(end 0.925 0.47)
			(stroke
				(width 0.05)
				(type default)
			)
			(fill no)
			(layer "F.CrtYd")
		)
		(fp_line
			(start 0.504 -0.25)
			(end 0.504 0.248)
			(stroke
				(width 0.15)
				(type solid)
			)
			(layer "F.Fab")
		)
		(fp_line
			(start -0.494 -0.25)
			(end 0.504 -0.25)
			(stroke
				(width 0.15)
				(type solid)
			)
			(layer "F.Fab")
		)
		(fp_line
			(start 0.504 0.248)
			(end -0.494 0.248)
			(stroke
				(width 0.15)
				(type solid)
			)
			(layer "F.Fab")
		)
		(fp_line
			(start -0.494 0.248)
			(end -0.494 -0.25)
			(stroke
				(width 0.15)
				(type solid)
			)
			(layer "F.Fab")
		)
		(pad "1" smd roundrect
			(at -0.48 0 90)
			(size 0.59 0.64)
			(layers "F.Cu" "F.Mask" "F.Paste")
			(roundrect_rratio 0.25)
			(net 97 "/FMC+ HSPC/GTX115.TX2_P")
			(pintype "passive")
		)
		(pad "2" smd roundrect
			(at 0.48 0 90)
			(size 0.59 0.64)
			(layers "F.Cu" "F.Mask" "F.Paste")
			(roundrect_rratio 0.25)
			(net 96 "/FMC+ HSPC/GTX_TX5_C_P")
			(pintype "passive")
		)
	)
	(footprint "antmicro-footprints:R_0402_1005Metric"
		(layer "F.Cu")
		(at 242.15 108.5)
		(descr "Resistor SMD 0402")
		(tags "resistor SMD 0402")
		(property "Reference" "R261"
			(at -3.65 0.35 0)
			(layer "F.SilkS")
			(effects
				(font
					(size 0.7 0.7)
					(thickness 0.15)
				)
				(justify left bottom)
			)
		)
		(property "Value" "R_0R_0402"
			(at 0 1.4 0)
			(layer "F.Fab")
			(effects
				(font
					(size 0.7 0.7)
					(thickness 0.15)
				)
				(justify left bottom)
			)
		)
		(property "Description" "SMD Chip Resistor, Jumper, 0 ohm, 100 mW, 0402 [1005 Metric], Thick Film, General Purpose"
			(at 0 0 0)
			(layer "F.Fab")
			(hide yes)
			(effects
				(font
					(size 1.27 1.27)
					(thickness 0.15)
				)
			)
		)
		(property "Author" "Antmicro"
			(at 0 0 0)
			(layer "F.Fab")
			(hide yes)
			(effects
				(font
					(size 1 1)
					(thickness 0.15)
				)
			)
		)
		(property "Current" "1A"
			(at 0 0 0)
			(layer "F.Fab")
			(hide yes)
			(effects
				(font
					(size 1 1)
					(thickness 0.15)
				)
			)
		)
		(property "License" "Apache-2.0"
			(at 0 0 0)
			(layer "F.Fab")
			(hide yes)
			(effects
				(font
					(size 1 1)
					(thickness 0.15)
				)
			)
		)
		(property "MPN" "ERJ2GE0R00X"
			(at 0 0 0)
			(layer "F.Fab")
			(hide yes)
			(effects
				(font
					(size 1 1)
					(thickness 0.15)
				)
			)
		)
		(property "Manufacturer" "Panasonic"
			(at 0 0 0)
			(layer "F.Fab")
			(hide yes)
			(effects
				(font
					(size 1 1)
					(thickness 0.15)
				)
			)
		)
		(property "Tolerance" ""
			(at 0 0 0)
			(layer "F.Fab")
			(hide yes)
			(effects
				(font
					(size 1 1)
					(thickness 0.15)
				)
			)
		)
		(property "Val" "0R"
			(at 0 0 0)
			(layer "F.Fab")
			(hide yes)
			(effects
				(font
					(size 1 1)
					(thickness 0.15)
				)
			)
		)
		(sheetname "HDMI + Ethernet")
		(sheetfile "hdmi-ethernet.kicad_sch")
		(attr smd)
		(fp_rect
			(start -0.925 -0.47)
			(end 0.925 0.47)
			(stroke
				(width 0.05)
				(type default)
			)
			(fill no)
			(layer "F.CrtYd")
		)
		(fp_rect
			(start -0.5 -0.25)
			(end 0.5 0.25)
			(stroke
				(width 0.15)
				(type solid)
			)
			(fill no)
			(layer "F.Fab")
		)
		(pad "1" smd roundrect
			(at -0.48 0)
			(size 0.59 0.64)
			(layers "F.Cu" "F.Mask" "F.Paste")
			(roundrect_rratio 0.25)
			(net 565 "/FPGA Bank 16 & 17/HDMI.CLK_N")
			(pintype "passive")
		)
		(pad "2" smd roundrect
			(at 0.48 0)
			(size 0.59 0.64)
			(layers "F.Cu" "F.Mask" "F.Paste")
			(roundrect_rratio 0.25)
			(net 868 "/HDMI + Ethernet/HDMI_CONN_CLK_N")
			(pintype "passive")
		)
	)
	(footprint "antmicro-footprints:USB-C_Receptacle_GCT_USB4105-GF-A"
		(locked yes)
		(layer "F.Cu")
		(at 267.11 146 90)
		(property "Reference" "J13"
			(at -6.1 0.49 180)
			(layer "F.SilkS")
			(effects
				(font
					(size 0.7 0.7)
					(thickness 0.15)
				)
				(justify left bottom)
			)
		)
		(property "Value" "USB-C_GCT_USB4105-GF-A"
			(at 0 5 90)
			(layer "F.Fab")
			(effects
				(font
					(size 0.7 0.7)
					(thickness 0.15)
				)
				(justify left bottom)
			)
		)
		(property "Description" "USB-C (USB TYPE-C) USB 2.0 Receptacle Connector 24 (16+8 Dummy) Position Surface Mount, Right Angle"
			(at 0 0 90)
			(layer "F.Fab")
			(hide yes)
			(effects
				(font
					(size 1.27 1.27)
					(thickness 0.15)
				)
			)
		)
		(property "Author" "Antmicro"
			(at 413.11 -121.11 0)
			(layer "F.Fab")
			(hide yes)
			(effects
				(font
					(size 1 1)
					(thickness 0.15)
				)
			)
		)
		(property "License" "Apache-2.0"
			(at 413.11 -121.11 0)
			(layer "F.Fab")
			(hide yes)
			(effects
				(font
					(size 1 1)
					(thickness 0.15)
				)
			)
		)
		(property "MPN" "USB4105-GF-A"
			(at 413.11 -121.11 0)
			(layer "F.Fab")
			(hide yes)
			(effects
				(font
					(size 1 1)
					(thickness 0.15)
				)
			)
		)
		(property "Manufacturer" "GCT"
			(at 413.11 -121.11 0)
			(layer "F.Fab")
			(hide yes)
			(effects
				(font
					(size 1 1)
					(thickness 0.15)
				)
			)
		)
		(property "VSD_Class" "USB-C"
			(at 413.11 -121.11 0)
			(layer "F.Fab")
			(hide yes)
			(effects
				(font
					(size 1 1)
					(thickness 0.15)
				)
			)
		)
		(sheetname "USB PHY")
		(sheetfile "usb-phy.kicad_sch")
		(attr smd)
		(fp_line
			(start 4.788 -1.395)
			(end 4.788 -0.145)
			(stroke
				(width 0.15)
				(type solid)
			)
			(layer "F.SilkS")
		)
		(fp_line
			(start -4.79 -1.395)
			(end -4.79 -0.145)
			(stroke
				(width 0.15)
				(type solid)
			)
			(layer "F.SilkS")
		)
		(fp_line
			(start -4.79 2.575)
			(end -4.79 3.854)
			(stroke
				(width 0.15)
				(type solid)
			)
			(layer "F.SilkS")
		)
		(fp_line
			(start 4.788 3.854)
			(end 4.788 2.575)
			(stroke
				(width 0.15)
				(type solid)
			)
			(layer "F.SilkS")
		)
		(fp_line
			(start -4.79 3.854)
			(end 4.788 3.854)
			(stroke
				(width 0.15)
				(type solid)
			)
			(layer "F.SilkS")
		)
		(fp_circle
			(center -3.8 -4.27071)
			(end -3.75 -4.22071)
			(stroke
				(width 0.15)
				(type solid)
			)
			(fill yes)
			(layer "F.SilkS")
		)
		(fp_rect
			(start -5.1 -4.4)
			(end 5.1 3.9)
			(stroke
				(width 0.05)
				(type solid)
			)
			(fill no)
			(layer "F.CrtYd")
		)
		(fp_line
			(start 4.788 -3.676)
			(end 4.788 3.854)
			(stroke
				(width 0.15)
				(type solid)
			)
			(layer "F.Fab")
		)
		(fp_line
			(start -4.79 -3.676)
			(end 4.788 -3.676)
			(stroke
				(width 0.15)
				(type solid)
			)
			(layer "F.Fab")
		)
		(fp_line
			(start 4.788 3.854)
			(end -4.79 3.854)
			(stroke
				(width 0.15)
				(type solid)
			)
			(layer "F.Fab")
		)
		(fp_line
			(start -4.702 3.854)
			(end 4.788 3.854)
			(stroke
				(width 0.15)
				(type solid)
			)
			(layer "F.Fab")
		)
		(fp_line
			(start -4.79 3.854)
			(end -4.79 -3.676)
			(stroke
				(width 0.15)
				(type solid)
			)
			(layer "F.Fab")
		)
		(pad "" np_thru_hole circle
			(at -2.891 -2.426 90)
			(size 0.65 0.65)
			(drill 0.65)
			(layers "*.Cu" "*.Mask")
		)
		(pad "" np_thru_hole circle
			(at 2.89 -2.426 90)
			(size 0.65 0.65)
			(drill 0.65)
			(layers "*.Cu" "*.Mask")
		)
		(pad "A1" smd roundrect
			(at -3.202 -3.5 90)
			(size 0.6 1.15)
			(layers "F.Cu" "F.Mask" "F.Paste")
			(roundrect_rratio 0.25)
			(net 1 "GND")
			(pinfunction "GND")
			(pintype "power_in")
		)
		(pad "A4" smd roundrect
			(at -2.4 -3.5 90)
			(size 0.6 1.15)
			(layers "F.Cu" "F.Mask" "F.Paste")
			(roundrect_rratio 0.25)
			(net 704 "/Power supply/USB_DBG_PD.VBUS")
			(pinfunction "VBUS")
			(pintype "passive")
		)
		(pad "A5" smd roundrect
			(at -1.25 -3.5 90)
			(size 0.3 1.15)
			(layers "F.Cu" "F.Mask" "F.Paste")
			(roundrect_rratio 0.25)
			(net 837 "/Power supply/USB_DBG_PD.CC1")
			(pinfunction "CC_{1}")
			(pintype "bidirectional")
		)
		(pad "A6" smd roundrect
			(at -0.25 -3.5 90)
			(size 0.3 1.15)
			(layers "F.Cu" "F.Mask" "F.Paste")
			(roundrect_rratio 0.25)
			(net 838 "/USB PHY/USB_DBG_CONN_D+")
			(pinfunction "D_{A}+")
			(pintype "bidirectional")
		)
		(pad "A7" smd roundrect
			(at 0.248 -3.5 90)
			(size 0.3 1.15)
			(layers "F.Cu" "F.Mask" "F.Paste")
			(roundrect_rratio 0.25)
			(net 839 "/USB PHY/USB_DBG_CONN_D-")
			(pinfunction "D_{A}-")
			(pintype "bidirectional")
		)
		(pad "A8" smd roundrect
			(at 1.249 -3.5 90)
			(size 0.3 1.15)
			(layers "F.Cu" "F.Mask" "F.Paste")
			(roundrect_rratio 0.25)
			(net 32 "unconnected-(J13-SBU_{1}-PadA8)")
			(pinfunction "SBU_{1}")
			(pintype "bidirectional+no_connect")
		)
		(pad "A9" smd roundrect
			(at 2.398 -3.5 90)
			(size 0.6 1.15)
			(layers "F.Cu" "F.Mask" "F.Paste")
			(roundrect_rratio 0.25)
			(net 704 "/Power supply/USB_DBG_PD.VBUS")
			(pinfunction "VBUS")
			(pintype "passive")
		)
		(pad "A12" smd roundrect
			(at 3.2 -3.5 90)
			(size 0.6 1.15)
			(layers "F.Cu" "F.Mask" "F.Paste")
			(roundrect_rratio 0.25)
			(net 1 "GND")
			(pinfunction "GND")
			(pintype "passive")
		)
		(pad "B1" smd roundrect
			(at 3.2 -3.5 90)
			(size 0.6 1.15)
			(layers "F.Cu" "F.Mask" "F.Paste")
			(roundrect_rratio 0.25)
			(net 1 "GND")
			(pinfunction "GND")
			(pintype "passive")
		)
		(pad "B4" smd roundrect
			(at 2.398 -3.5 90)
			(size 0.6 1.15)
			(layers "F.Cu" "F.Mask" "F.Paste")
			(roundrect_rratio 0.25)
			(net 704 "/Power supply/USB_DBG_PD.VBUS")
			(pinfunction "VBUS")
			(pintype "passive")
		)
		(pad "B5" smd roundrect
			(at 1.749 -3.5 90)
			(size 0.3 1.15)
			(layers "F.Cu" "F.Mask" "F.Paste")
			(roundrect_rratio 0.25)
			(net 840 "/Power supply/USB_DBG_PD.CC2")
			(pinfunction "CC_{2}")
			(pintype "bidirectional")
		)
		(pad "B6" smd roundrect
			(at 0.748 -3.5 90)
			(size 0.3 1.15)
			(layers "F.Cu" "F.Mask" "F.Paste")
			(roundrect_rratio 0.25)
			(net 838 "/USB PHY/USB_DBG_CONN_D+")
			(pinfunction "D_{B}+")
			(pintype "bidirectional")
		)
		(pad "B7" smd roundrect
			(at -0.75 -3.5 90)
			(size 0.3 1.15)
			(layers "F.Cu" "F.Mask" "F.Paste")
			(roundrect_rratio 0.25)
			(net 839 "/USB PHY/USB_DBG_CONN_D-")
			(pinfunction "D_{B}-")
			(pintype "bidirectional")
		)
		(pad "B8" smd roundrect
			(at -1.75 -3.5 90)
			(size 0.3 1.15)
			(layers "F.Cu" "F.Mask" "F.Paste")
			(roundrect_rratio 0.25)
			(net 33 "unconnected-(J13-SBU_{2}-PadB8)")
			(pinfunction "SBU_{2}")
			(pintype "bidirectional+no_connect")
		)
		(pad "B9" smd roundrect
			(at -2.4 -3.5 90)
			(size 0.6 1.15)
			(layers "F.Cu" "F.Mask" "F.Paste")
			(roundrect_rratio 0.25)
			(net 704 "/Power supply/USB_DBG_PD.VBUS")
			(pinfunction "VBUS")
			(pintype "passive")
		)
		(pad "B12" smd roundrect
			(at -3.202 -3.5 90)
			(size 0.6 1.15)
			(layers "F.Cu" "F.Mask" "F.Paste")
			(roundrect_rratio 0.25)
			(net 1 "GND")
			(pinfunction "GND")
			(pintype "passive")
		)
		(pad "SH" thru_hole oval
			(at -4.321 -2.926 90)
			(size 1.05 2.1)
			(drill oval 0.6 1.7)
			(layers "*.Cu" "*.Mask")
			(remove_unused_layers no)
			(net 1 "GND")
			(pinfunction "SH")
			(pintype "passive")
		)
		(pad "SH" thru_hole oval
			(at -4.321 1.255 90)
			(size 1 2)
			(drill oval 0.6 1.4)
			(layers "*.Cu" "*.Mask")
			(remove_unused_layers no)
			(net 1 "GND")
			(pinfunction "SH")
			(pintype "passive")
		)
		(pad "SH" thru_hole oval
			(at 4.32 -2.926 90)
			(size 1.05 2.1)
			(drill oval 0.6 1.7)
			(layers "*.Cu" "*.Mask")
			(remove_unused_layers no)
			(net 1 "GND")
			(pinfunction "SH")
			(pintype "passive")
		)
		(pad "SH" thru_hole oval
			(at 4.32 1.255 90)
			(size 1 2)
			(drill oval 0.6 1.4)
			(layers "*.Cu" "*.Mask")
			(remove_unused_layers no)
			(net 1 "GND")
			(pinfunction "SH")
			(pintype "passive")
		)
	)
	(footprint "antmicro-footprints:R_0402_1005Metric"
		(layer "F.Cu")
		(at 264.7 135.6 90)
		(descr "Resistor SMD 0402")
		(tags "resistor SMD 0402")
		(property "Reference" "R152"
			(at 31.25 -29.85 180)
			(layer "F.SilkS")
			(effects
				(font
					(size 0.7 0.7)
					(thickness 0.15)
				)
				(justify left bottom)
			)
		)
		(property "Value" "R_330R_0402"
			(at 0 1.4 90)
			(layer "F.Fab")
			(effects
				(font
					(size 0.7 0.7)
					(thickness 0.15)
				)
				(justify left bottom)
			)
		)
		(property "Description" "SMD Chip Resistor, 330 ohm, ± 1%, 62.5 mW, 0402 [1005 Metric], Thick Film, General Purpose"
			(at 0 0 90)
			(layer "F.Fab")
			(hide yes)
			(effects
				(font
					(size 1.27 1.27)
					(thickness 0.15)
				)
			)
		)
		(property "Author" "Antmicro"
			(at 400.3 -129.1 0)
			(layer "F.Fab")
			(hide yes)
			(effects
				(font
					(size 1 1)
					(thickness 0.15)
				)
			)
		)
		(property "License" "Apache-2.0"
			(at 400.3 -129.1 0)
			(layer "F.Fab")
			(hide yes)
			(effects
				(font
					(size 1 1)
					(thickness 0.15)
				)
			)
		)
		(property "MPN" "CR0402-FX-3300GLF"
			(at 400.3 -129.1 0)
			(layer "F.Fab")
			(hide yes)
			(effects
				(font
					(size 1 1)
					(thickness 0.15)
				)
			)
		)
		(property "Manufacturer" "Bourns"
			(at 400.3 -129.1 0)
			(layer "F.Fab")
			(hide yes)
			(effects
				(font
					(size 1 1)
					(thickness 0.15)
				)
			)
		)
		(property "Tolerance" "1%"
			(at 400.3 -129.1 0)
			(layer "F.Fab")
			(hide yes)
			(effects
				(font
					(size 1 1)
					(thickness 0.15)
				)
			)
		)
		(property "Val" "330R"
			(at 400.3 -129.1 0)
			(layer "F.Fab")
			(hide yes)
			(effects
				(font
					(size 1 1)
					(thickness 0.15)
				)
			)
		)
		(sheetname "USB PHY")
		(sheetfile "usb-phy.kicad_sch")
		(attr smd)
		(fp_rect
			(start -0.925 -0.47)
			(end 0.925 0.47)
			(stroke
				(width 0.05)
				(type default)
			)
			(fill no)
			(layer "F.CrtYd")
		)
		(fp_rect
			(start -0.5 -0.25)
			(end 0.5 0.25)
			(stroke
				(width 0.15)
				(type solid)
			)
			(fill no)
			(layer "F.Fab")
		)
		(pad "1" smd roundrect
			(at -0.48 0 90)
			(size 0.59 0.64)
			(layers "F.Cu" "F.Mask" "F.Paste")
			(roundrect_rratio 0.25)
			(net 792 "Net-(D28-A)")
			(pintype "passive")
		)
		(pad "2" smd roundrect
			(at 0.48 0 90)
			(size 0.59 0.64)
			(layers "F.Cu" "F.Mask" "F.Paste")
			(roundrect_rratio 0.25)
			(net 914 "/USB PHY/LED_TX1")
			(pintype "passive")
		)
	)
	(footprint "antmicro-footprints:C_0402_1005Metric"
		(layer "F.Cu")
		(at 157.9 153.76 90)
		(descr "Capacitor SMD 0402")
		(tags "capacitor SMD 0402")
		(property "Reference" "C355"
			(at 0.8 0.35 90)
			(layer "F.SilkS")
			(effects
				(font
					(size 0.7 0.7)
					(thickness 0.15)
				)
				(justify left bottom)
			)
		)
		(property "Value" "C_10u_0402"
			(at 0 1.4 90)
			(layer "F.Fab")
			(effects
				(font
					(size 0.7 0.7)
					(thickness 0.15)
				)
				(justify left bottom)
			)
		)
		(property "Description" "SMD Multilayer Ceramic Capacitor, 10 µF, 6.3 V, 0402 [1005 Metric], ± 20%, X5R, CC Series"
			(at 0 0 90)
			(layer "F.Fab")
			(hide yes)
			(effects
				(font
					(size 1.27 1.27)
					(thickness 0.15)
				)
			)
		)
		(property "Author" "Antmicro"
			(at 311.66 -4.14 0)
			(layer "F.Fab")
			(hide yes)
			(effects
				(font
					(size 1 1)
					(thickness 0.15)
				)
			)
		)
		(property "Dielectric" ""
			(at 311.66 -4.14 0)
			(layer "F.Fab")
			(hide yes)
			(effects
				(font
					(size 1 1)
					(thickness 0.15)
				)
			)
		)
		(property "License" "Apache-2.0"
			(at 311.66 -4.14 0)
			(layer "F.Fab")
			(hide yes)
			(effects
				(font
					(size 1 1)
					(thickness 0.15)
				)
			)
		)
		(property "MPN" "CC0402MRX5R5BB106"
			(at 311.66 -4.14 0)
			(layer "F.Fab")
			(hide yes)
			(effects
				(font
					(size 1 1)
					(thickness 0.15)
				)
			)
		)
		(property "Manufacturer" "YAGEO"
			(at 311.66 -4.14 0)
			(layer "F.Fab")
			(hide yes)
			(effects
				(font
					(size 1 1)
					(thickness 0.15)
				)
			)
		)
		(property "Val" "10u"
			(at 311.66 -4.14 0)
			(layer "F.Fab")
			(hide yes)
			(effects
				(font
					(size 1 1)
					(thickness 0.15)
				)
			)
		)
		(property "Voltage" ""
			(at 311.66 -4.14 0)
			(layer "F.Fab")
			(hide yes)
			(effects
				(font
					(size 1 1)
					(thickness 0.15)
				)
			)
		)
		(sheetname "DC-DC Converters")
		(sheetfile "dc-dc.kicad_sch")
		(attr smd)
		(fp_rect
			(start -0.925 -0.47)
			(end 0.925 0.47)
			(stroke
				(width 0.05)
				(type default)
			)
			(fill no)
			(layer "F.CrtYd")
		)
		(fp_line
			(start 0.504 -0.25)
			(end 0.504 0.248)
			(stroke
				(width 0.15)
				(type solid)
			)
			(layer "F.Fab")
		)
		(fp_line
			(start -0.494 -0.25)
			(end 0.504 -0.25)
			(stroke
				(width 0.15)
				(type solid)
			)
			(layer "F.Fab")
		)
		(fp_line
			(start 0.504 0.248)
			(end -0.494 0.248)
			(stroke
				(width 0.15)
				(type solid)
			)
			(layer "F.Fab")
		)
		(fp_line
			(start -0.494 0.248)
			(end -0.494 -0.25)
			(stroke
				(width 0.15)
				(type solid)
			)
			(layer "F.Fab")
		)
		(pad "1" smd roundrect
			(at -0.48 0 90)
			(size 0.59 0.64)
			(layers "F.Cu" "F.Mask" "F.Paste")
			(roundrect_rratio 0.25)
			(net 1 "GND")
			(pintype "passive")
		)
		(pad "2" smd roundrect
			(at 0.48 0 90)
			(size 0.59 0.64)
			(layers "F.Cu" "F.Mask" "F.Paste")
			(roundrect_rratio 0.25)
			(net 750 "/DC-DC Converters/VDDR_VTT")
			(pintype "passive")
		)
	)
	(footprint "antmicro-footprints:R_0402_1005Metric"
		(layer "F.Cu")
		(at 225.025 119.5)
		(descr "Resistor SMD 0402")
		(tags "resistor SMD 0402")
		(property "Reference" "R77"
			(at -2.975 0.4 0)
			(layer "F.SilkS")
			(effects
				(font
					(size 0.7 0.7)
					(thickness 0.15)
				)
				(justify left bottom)
			)
		)
		(property "Value" "R_0R_0402"
			(at 0 1.4 0)
			(layer "F.Fab")
			(effects
				(font
					(size 0.7 0.7)
					(thickness 0.15)
				)
				(justify left bottom)
			)
		)
		(property "Description" "SMD Chip Resistor, Jumper, 0 ohm, 100 mW, 0402 [1005 Metric], Thick Film, General Purpose"
			(at 0 0 0)
			(layer "F.Fab")
			(hide yes)
			(effects
				(font
					(size 1.27 1.27)
					(thickness 0.15)
				)
			)
		)
		(property "Author" "Antmicro"
			(at 0 0 0)
			(layer "F.Fab")
			(hide yes)
			(effects
				(font
					(size 1 1)
					(thickness 0.15)
				)
			)
		)
		(property "Current" "1A"
			(at 0 0 0)
			(layer "F.Fab")
			(hide yes)
			(effects
				(font
					(size 1 1)
					(thickness 0.15)
				)
			)
		)
		(property "License" "Apache-2.0"
			(at 0 0 0)
			(layer "F.Fab")
			(hide yes)
			(effects
				(font
					(size 1 1)
					(thickness 0.15)
				)
			)
		)
		(property "MPN" "ERJ2GE0R00X"
			(at 0 0 0)
			(layer "F.Fab")
			(hide yes)
			(effects
				(font
					(size 1 1)
					(thickness 0.15)
				)
			)
		)
		(property "Manufacturer" "Panasonic"
			(at 0 0 0)
			(layer "F.Fab")
			(hide yes)
			(effects
				(font
					(size 1 1)
					(thickness 0.15)
				)
			)
		)
		(property "Tolerance" ""
			(at 0 0 0)
			(layer "F.Fab")
			(hide yes)
			(effects
				(font
					(size 1 1)
					(thickness 0.15)
				)
			)
		)
		(property "Val" "0R"
			(at 0 0 0)
			(layer "F.Fab")
			(hide yes)
			(effects
				(font
					(size 1 1)
					(thickness 0.15)
				)
			)
		)
		(sheetname "SPI Flash + SD Card")
		(sheetfile "spi-flash.kicad_sch")
		(attr smd)
		(fp_rect
			(start -0.925 -0.47)
			(end 0.925 0.47)
			(stroke
				(width 0.05)
				(type default)
			)
			(fill no)
			(layer "F.CrtYd")
		)
		(fp_rect
			(start -0.5 -0.25)
			(end 0.5 0.25)
			(stroke
				(width 0.15)
				(type solid)
			)
			(fill no)
			(layer "F.Fab")
		)
		(pad "1" smd roundrect
			(at -0.48 0)
			(size 0.59 0.64)
			(layers "F.Cu" "F.Mask" "F.Paste")
			(roundrect_rratio 0.25)
			(net 43 "/FPGA Bank 14 & 15/SYSTEM_FLASH.DQ1")
			(pintype "passive")
		)
		(pad "2" smd roundrect
			(at 0.48 0)
			(size 0.59 0.64)
			(layers "F.Cu" "F.Mask" "F.Paste")
			(roundrect_rratio 0.25)
			(net 897 "/SPI Flash + SD Card/SYSTEM_FLASH_DQ1")
			(pintype "passive")
		)
	)
	(footprint "antmicro-footprints:C_0402_1005Metric"
		(layer "F.Cu")
		(at 240.25 147.2 180)
		(descr "Capacitor SMD 0402")
		(tags "capacitor SMD 0402")
		(property "Reference" "C245"
			(at 1.8 -2.2 180)
			(layer "F.SilkS")
			(effects
				(font
					(size 0.7 0.7)
					(thickness 0.15)
				)
				(justify left bottom)
			)
		)
		(property "Value" "C_100n_0402"
			(at 0 1.169 180)
			(layer "F.Fab")
			(effects
				(font
					(size 0.7 0.7)
					(thickness 0.15)
				)
				(justify left bottom)
			)
		)
		(property "Description" "SMD Multilayer Ceramic Capacitor, 0.1 µF, 50 V, 0402 [1005 Metric], ± 10%, X5R, GRM Series"
			(at 0 0 180)
			(layer "F.Fab")
			(hide yes)
			(effects
				(font
					(size 1.27 1.27)
					(thickness 0.15)
				)
			)
		)
		(property "Author" "Antmicro"
			(at 480.5 294.4 0)
			(layer "F.Fab")
			(hide yes)
			(effects
				(font
					(size 1 1)
					(thickness 0.15)
				)
			)
		)
		(property "Dielectric" "X5R"
			(at 480.5 294.4 0)
			(layer "F.Fab")
			(hide yes)
			(effects
				(font
					(size 1 1)
					(thickness 0.15)
				)
			)
		)
		(property "License" "Apache-2.0"
			(at 480.5 294.4 0)
			(layer "F.Fab")
			(hide yes)
			(effects
				(font
					(size 1 1)
					(thickness 0.15)
				)
			)
		)
		(property "MPN" "GRM155R61H104KE14D"
			(at 480.5 294.4 0)
			(layer "F.Fab")
			(hide yes)
			(effects
				(font
					(size 1 1)
					(thickness 0.15)
				)
			)
		)
		(property "Manufacturer" "Murata"
			(at 480.5 294.4 0)
			(layer "F.Fab")
			(hide yes)
			(effects
				(font
					(size 1 1)
					(thickness 0.15)
				)
			)
		)
		(property "Val" "100n"
			(at 480.5 294.4 0)
			(layer "F.Fab")
			(hide yes)
			(effects
				(font
					(size 1 1)
					(thickness 0.15)
				)
			)
		)
		(property "Voltage" "50V"
			(at 480.5 294.4 0)
			(layer "F.Fab")
			(hide yes)
			(effects
				(font
					(size 1 1)
					(thickness 0.15)
				)
			)
		)
		(sheetname "USB PHY")
		(sheetfile "usb-phy.kicad_sch")
		(attr smd)
		(fp_rect
			(start -0.925 -0.47)
			(end 0.925 0.47)
			(stroke
				(width 0.05)
				(type default)
			)
			(fill no)
			(layer "F.CrtYd")
		)
		(fp_line
			(start 0.504 0.248)
			(end -0.494 0.248)
			(stroke
				(width 0.15)
				(type solid)
			)
			(layer "F.Fab")
		)
		(fp_line
			(start 0.504 -0.25)
			(end 0.504 0.248)
			(stroke
				(width 0.15)
				(type solid)
			)
			(layer "F.Fab")
		)
		(fp_line
			(start -0.494 0.248)
			(end -0.494 -0.25)
			(stroke
				(width 0.15)
				(type solid)
			)
			(layer "F.Fab")
		)
		(fp_line
			(start -0.494 -0.25)
			(end 0.504 -0.25)
			(stroke
				(width 0.15)
				(type solid)
			)
			(layer "F.Fab")
		)
		(pad "1" smd roundrect
			(at -0.48 0 180)
			(size 0.59 0.64)
			(layers "F.Cu" "F.Mask" "F.Paste")
			(roundrect_rratio 0.25)
			(net 1 "GND")
			(pintype "passive")
		)
		(pad "2" smd roundrect
			(at 0.48 0 180)
			(size 0.59 0.64)
			(layers "F.Cu" "F.Mask" "F.Paste")
			(roundrect_rratio 0.25)
			(net 707 "/USB PHY/FTDI_3V3")
			(pintype "passive")
		)
	)
	(footprint "antmicro-footprints:SW_KMR211NGLFS_SMD"
		(layer "F.Cu")
		(at 177.978 73.62 -90)
		(property "Reference" "S1"
			(at 3.58 1.778 0)
			(layer "F.SilkS")
			(effects
				(font
					(size 0.7 0.7)
					(thickness 0.15)
				)
				(justify left bottom)
			)
		)
		(property "Value" "SW_KMR211NGLFS_SMD"
			(at -3 3 270)
			(layer "F.Fab")
			(effects
				(font
					(size 0.7 0.7)
					(thickness 0.15)
				)
				(justify left bottom)
			)
		)
		(property "Description" "Tactile Switch, KMR 2 Series, Top Actuated, Surface Mount, Oval Button, 120 gf, 50mA at 32VDC"
			(at 0 0 270)
			(layer "F.Fab")
			(hide yes)
			(effects
				(font
					(size 1.27 1.27)
					(thickness 0.15)
				)
			)
		)
		(property "Author" "Antmicro"
			(at 104.358 251.598 0)
			(layer "F.Fab")
			(hide yes)
			(effects
				(font
					(size 1 1)
					(thickness 0.15)
				)
			)
		)
		(property "License" "Apache-2.0"
			(at 104.358 251.598 0)
			(layer "F.Fab")
			(hide yes)
			(effects
				(font
					(size 1 1)
					(thickness 0.15)
				)
			)
		)
		(property "MPN" "KMR211NGLFS"
			(at 104.358 251.598 0)
			(layer "F.Fab")
			(hide yes)
			(effects
				(font
					(size 1 1)
					(thickness 0.15)
				)
			)
		)
		(property "Manufacturer" "C&K"
			(at 104.358 251.598 0)
			(layer "F.Fab")
			(hide yes)
			(effects
				(font
					(size 1 1)
					(thickness 0.15)
				)
			)
		)
		(sheetname "FPGA Config")
		(sheetfile "fpga-config.kicad_sch")
		(attr smd)
		(fp_line
			(start -2.1 1.601)
			(end -2.1 1.48)
			(stroke
				(width 0.15)
				(type solid)
			)
			(layer "F.SilkS")
		)
		(fp_line
			(start 2.101 1.601)
			(end -2.1 1.601)
			(stroke
				(width 0.15)
				(type solid)
			)
			(layer "F.SilkS")
		)
		(fp_line
			(start 2.101 1.601)
			(end 2.101 1.48)
			(stroke
				(width 0.15)
				(type solid)
			)
			(layer "F.SilkS")
		)
		(fp_line
			(start 2.101 -1.58)
			(end 2.101 -1.459)
			(stroke
				(width 0.15)
				(type solid)
			)
			(layer "F.SilkS")
		)
		(fp_line
			(start -2.1 -1.6)
			(end -2.1 -1.499)
			(stroke
				(width 0.15)
				(type solid)
			)
			(layer "F.SilkS")
		)
		(fp_line
			(start 2.101 -1.6)
			(end -2.1 -1.6)
			(stroke
				(width 0.15)
				(type solid)
			)
			(layer "F.SilkS")
		)
		(fp_rect
			(start 2.751 1.75)
			(end -2.748 -1.749)
			(stroke
				(width 0.05)
				(type solid)
			)
			(fill no)
			(layer "F.CrtYd")
		)
		(fp_line
			(start -2.1 1.601)
			(end 2.101 1.601)
			(stroke
				(width 0.15)
				(type solid)
			)
			(layer "F.Fab")
		)
		(fp_line
			(start 2.101 1.601)
			(end 2.101 -1.6)
			(stroke
				(width 0.15)
				(type solid)
			)
			(layer "F.Fab")
		)
		(fp_line
			(start 0.25 0.802)
			(end -0.248 0.802)
			(stroke
				(width 0.15)
				(type solid)
			)
			(layer "F.Fab")
		)
		(fp_line
			(start -0.248 -0.8)
			(end 0.25 -0.8)
			(stroke
				(width 0.15)
				(type solid)
			)
			(layer "F.Fab")
		)
		(fp_line
			(start -2.1 -1.6)
			(end -2.1 1.601)
			(stroke
				(width 0.15)
				(type solid)
			)
			(layer "F.Fab")
		)
		(fp_line
			(start 2.101 -1.6)
			(end -2.1 -1.6)
			(stroke
				(width 0.15)
				(type solid)
			)
			(layer "F.Fab")
		)
		(fp_arc
			(start -0.248 0.802)
			(mid -1.050001 0.001)
			(end -0.248 -0.8)
			(stroke
				(width 0.15)
				(type solid)
			)
			(layer "F.Fab")
		)
		(fp_arc
			(start 0.25 -0.8)
			(mid 1.051001 0.001)
			(end 0.25 0.802)
			(stroke
				(width 0.15)
				(type solid)
			)
			(layer "F.Fab")
		)
		(pad "1" smd rect
			(at -2.048 -0.8 90)
			(size 0.9 1)
			(layers "F.Cu" "F.Mask" "F.Paste")
			(net 301 "/FPGA Config/PROGRAM_B")
			(pinfunction "1")
			(pintype "passive")
		)
		(pad "2" smd rect
			(at 2.05 -0.8 90)
			(size 0.9 1)
			(layers "F.Cu" "F.Mask" "F.Paste")
			(net 301 "/FPGA Config/PROGRAM_B")
			(pinfunction "2")
			(pintype "passive")
		)
		(pad "3" smd rect
			(at -2.048 0.802 90)
			(size 0.9 1)
			(layers "F.Cu" "F.Mask" "F.Paste")
			(net 1 "GND")
			(pinfunction "3")
			(pintype "passive")
		)
		(pad "4" smd rect
			(at 2.05 0.802 90)
			(size 0.9 1)
			(layers "F.Cu" "F.Mask" "F.Paste")
			(net 1 "GND")
			(pinfunction "4")
			(pintype "passive")
		)
	)
	(footprint "antmicro-footprints:LED_0603_1608Metric_G"
		(layer "F.Cu")
		(at 261.5 88.6)
		(descr "LED SMD 0603 Green")
		(tags "LED SMD 0603 Green")
		(property "Reference" "D20"
			(at -1.05 1.55 0)
			(layer "F.SilkS")
			(effects
				(font
					(size 0.7 0.7)
					(thickness 0.15)
				)
				(justify left bottom)
			)
		)
		(property "Value" "LED_G_0603_KP-1608CGCK"
			(at 0 1.6 0)
			(layer "F.Fab")
			(effects
				(font
					(size 0.7 0.7)
					(thickness 0.15)
				)
				(justify left bottom)
			)
		)
		(property "Description" "LED, Green, SMD, 0603, 20 mA, 2.1 V, 570 nm"
			(at 0 0 0)
			(layer "F.Fab")
			(hide yes)
			(effects
				(font
					(size 1.27 1.27)
					(thickness 0.15)
				)
			)
		)
		(property "Author" "Antmicro"
			(at 0 0 0)
			(layer "F.Fab")
			(hide yes)
			(effects
				(font
					(size 1 1)
					(thickness 0.15)
				)
			)
		)
		(property "Color" "Green"
			(at 0 0 0)
			(layer "F.Fab")
			(hide yes)
			(effects
				(font
					(size 1 1)
					(thickness 0.15)
				)
			)
		)
		(property "License" "Apache-2.0"
			(at 0 0 0)
			(layer "F.Fab")
			(hide yes)
			(effects
				(font
					(size 1 1)
					(thickness 0.15)
				)
			)
		)
		(property "MPN" "KP-1608CGCK"
			(at 0 0 0)
			(layer "F.Fab")
			(hide yes)
			(effects
				(font
					(size 1 1)
					(thickness 0.15)
				)
			)
		)
		(property "Manufacturer" "Kingbright"
			(at 0 0 0)
			(layer "F.Fab")
			(hide yes)
			(effects
				(font
					(size 1 1)
					(thickness 0.15)
				)
			)
		)
		(sheetname "User GPIO + LED + button + DIP switch")
		(sheetfile "user-gpio.kicad_sch")
		(attr smd)
		(fp_line
			(start -1.18 -0.319)
			(end -1.18 0.321)
			(stroke
				(width 0.15)
				(type solid)
			)
			(layer "F.SilkS")
		)
		(fp_line
			(start -0.094672 0.001008)
			(end -0.24 0.001008)
			(stroke
				(width 0.1)
				(type solid)
			)
			(layer "F.SilkS")
		)
		(fp_line
			(start -0.094672 0.001008)
			(end 0.105328 -0.198992)
			(stroke
				(width 0.1)
				(type solid)
			)
			(layer "F.SilkS")
		)
		(fp_line
			(start -0.094672 0.201008)
			(end -0.094672 -0.198992)
			(stroke
				(width 0.1)
				(type solid)
			)
			(layer "F.SilkS")
		)
		(fp_line
			(start 0.105328 0.001008)
			(end 0.24 0.001)
			(stroke
				(width 0.1)
				(type solid)
			)
			(layer "F.SilkS")
		)
		(fp_line
			(start 0.105328 0.201008)
			(end -0.094672 0.001008)
			(stroke
				(width 0.1)
				(type solid)
			)
			(layer "F.SilkS")
		)
		(fp_line
			(start 0.105328 0.201008)
			(end 0.105328 -0.198992)
			(stroke
				(width 0.1)
				(type solid)
			)
			(layer "F.SilkS")
		)
		(fp_line
			(start 0.22 -0.35)
			(end -0.22 -0.35)
			(stroke
				(width 0.15)
				(type solid)
			)
			(layer "F.SilkS")
		)
		(fp_line
			(start 0.22 0.35)
			(end -0.22 0.35)
			(stroke
				(width 0.15)
				(type solid)
			)
			(layer "F.SilkS")
		)
		(fp_rect
			(start 1.25 0.65)
			(end -1.25 -0.65)
			(stroke
				(width 0.05)
				(type solid)
			)
			(fill no)
			(layer "F.CrtYd")
		)
		(fp_line
			(start -0.199 -0.202)
			(end -0.199 0.1)
			(stroke
				(width 0.15)
				(type solid)
			)
			(layer "F.Fab")
		)
		(fp_line
			(start -0.199 0)
			(end -0.597 0)
			(stroke
				(width 0.15)
				(type solid)
			)
			(layer "F.Fab")
		)
		(fp_line
			(start -0.199 0.2)
			(end -0.199 0.1)
			(stroke
				(width 0.15)
				(type solid)
			)
			(layer "F.Fab")
		)
		(fp_line
			(start -0.101 0)
			(end 0.201 0.2)
			(stroke
				(width 0.15)
				(type solid)
			)
			(layer "F.Fab")
		)
		(fp_line
			(start 0.201 -0.202)
			(end -0.101 0)
			(stroke
				(width 0.15)
				(type solid)
			)
			(layer "F.Fab")
		)
		(fp_line
			(start 0.201 0)
			(end 0.201 -0.202)
			(stroke
				(width 0.15)
				(type solid)
			)
			(layer "F.Fab")
		)
		(fp_line
			(start 0.201 0.2)
			(end 0.201 0)
			(stroke
				(width 0.15)
				(type solid)
			)
			(layer "F.Fab")
		)
		(fp_line
			(start 0.599 0)
			(end 0.201 0)
			(stroke
				(width 0.15)
				(type solid)
			)
			(layer "F.Fab")
		)
		(fp_rect
			(start 0.848 0.4)
			(end -0.85 -0.402)
			(stroke
				(width 0.15)
				(type solid)
			)
			(fill no)
			(layer "F.Fab")
		)
		(pad "1" smd roundrect
			(at -0.7 0 180)
			(size 0.8 1)
			(layers "F.Cu" "F.Mask" "F.Paste")
			(roundrect_rratio 0.2)
			(net 22 "Net-(D20-C)")
			(pinfunction "C")
			(pintype "passive")
		)
		(pad "2" smd roundrect
			(at 0.7 0 180)
			(size 0.8 1)
			(layers "F.Cu" "F.Mask" "F.Paste")
			(roundrect_rratio 0.2)
			(net 779 "Net-(D20-A)")
			(pinfunction "A")
			(pintype "passive")
		)
	)
	(footprint "antmicro-footprints:SOT-23-3"
		(layer "F.Cu")
		(at 158.7 145.55 90)
		(property "Reference" "U41"
			(at -1 2.55 90)
			(layer "F.SilkS")
			(effects
				(font
					(size 0.7 0.7)
					(thickness 0.15)
				)
				(justify left bottom)
			)
		)
		(property "Value" "REF3012AIDBZT"
			(at -1.9 2.7 90)
			(layer "F.Fab")
			(effects
				(font
					(size 0.7 0.7)
					(thickness 0.15)
				)
				(justify left bottom)
			)
		)
		(property "Description" "Voltage Reference, Low Power, Low Dropout, Series"
			(at 0 0 90)
			(layer "F.Fab")
			(hide yes)
			(effects
				(font
					(size 1.27 1.27)
					(thickness 0.15)
				)
			)
		)
		(property "Author" "Antmicro"
			(at 304.25 -13.15 0)
			(layer "F.Fab")
			(hide yes)
			(effects
				(font
					(size 1 1)
					(thickness 0.15)
				)
			)
		)
		(property "License" "Apache-2.0"
			(at 304.25 -13.15 0)
			(layer "F.Fab")
			(hide yes)
			(effects
				(font
					(size 1 1)
					(thickness 0.15)
				)
			)
		)
		(property "MPN" "REF3012AIDBZT"
			(at 304.25 -13.15 0)
			(layer "F.Fab")
			(hide yes)
			(effects
				(font
					(size 1 1)
					(thickness 0.15)
				)
			)
		)
		(property "Manufacturer" "Texas Instruments"
			(at 304.25 -13.15 0)
			(layer "F.Fab")
			(hide yes)
			(effects
				(font
					(size 1 1)
					(thickness 0.15)
				)
			)
		)
		(sheetname "DC-DC Converters")
		(sheetfile "dc-dc.kicad_sch")
		(attr smd)
		(fp_line
			(start 0.7 -1.5)
			(end -0.7 -1.5)
			(stroke
				(width 0.15)
				(type solid)
			)
			(layer "F.SilkS")
		)
		(fp_line
			(start -0.85 -1.35)
			(end -0.7 -1.5)
			(stroke
				(width 0.15)
				(type solid)
			)
			(layer "F.SilkS")
		)
		(fp_line
			(start -1.45 -1.35)
			(end -0.85 -1.35)
			(stroke
				(width 0.15)
				(type solid)
			)
			(layer "F.SilkS")
		)
		(fp_line
			(start 0.7 -0.4)
			(end 0.7 -1.5)
			(stroke
				(width 0.15)
				(type solid)
			)
			(layer "F.SilkS")
		)
		(fp_line
			(start 0.7 0.4)
			(end 0.7 1.5)
			(stroke
				(width 0.15)
				(type solid)
			)
			(layer "F.SilkS")
		)
		(fp_line
			(start 0.7 1.5)
			(end -0.7 1.5)
			(stroke
				(width 0.15)
				(type solid)
			)
			(layer "F.SilkS")
		)
		(fp_line
			(start -0.7 1.5)
			(end -0.7 1.35)
			(stroke
				(width 0.15)
				(type solid)
			)
			(layer "F.SilkS")
		)
		(fp_line
			(start 0.825 -1.6)
			(end 0.825 -0.45)
			(stroke
				(width 0.05)
				(type solid)
			)
			(layer "F.CrtYd")
		)
		(fp_line
			(start -0.9 -1.6)
			(end 0.825 -1.6)
			(stroke
				(width 0.05)
				(type solid)
			)
			(layer "F.CrtYd")
		)
		(fp_line
			(start -0.9 -1.6)
			(end -0.9 -1.4)
			(stroke
				(width 0.05)
				(type solid)
			)
			(layer "F.CrtYd")
		)
		(fp_line
			(start -0.9 -1.4)
			(end -1.75 -1.4)
			(stroke
				(width 0.05)
				(type solid)
			)
			(layer "F.CrtYd")
		)
		(fp_line
			(start -0.85 -0.5)
			(end -1.75 -0.5)
			(stroke
				(width 0.05)
				(type solid)
			)
			(layer "F.CrtYd")
		)
		(fp_line
			(start -1.75 -0.5)
			(end -1.75 -1.4)
			(stroke
				(width 0.05)
				(type solid)
			)
			(layer "F.CrtYd")
		)
		(fp_line
			(start 1.75 -0.45)
			(end 1.75 0.45)
			(stroke
				(width 0.05)
				(type solid)
			)
			(layer "F.CrtYd")
		)
		(fp_line
			(start 0.825 -0.45)
			(end 1.75 -0.45)
			(stroke
				(width 0.05)
				(type solid)
			)
			(layer "F.CrtYd")
		)
		(fp_line
			(start 1.75 0.45)
			(end 0.85 0.45)
			(stroke
				(width 0.05)
				(type solid)
			)
			(layer "F.CrtYd")
		)
		(fp_line
			(start 0.85 0.45)
			(end 0.85 1.65)
			(stroke
				(width 0.05)
				(type solid)
			)
			(layer "F.CrtYd")
		)
		(fp_line
			(start -0.85 0.5)
			(end -0.85 -0.5)
			(stroke
				(width 0.05)
				(type solid)
			)
			(layer "F.CrtYd")
		)
		(fp_line
			(start -1.75 0.5)
			(end -0.85 0.5)
			(stroke
				(width 0.05)
				(type solid)
			)
			(layer "F.CrtYd")
		)
		(fp_line
			(start -0.85 1.4)
			(end -1.75 1.4)
			(stroke
				(width 0.05)
				(type solid)
			)
			(layer "F.CrtYd")
		)
		(fp_line
			(start -1.75 1.4)
			(end -1.75 0.5)
			(stroke
				(width 0.05)
				(type solid)
			)
			(layer "F.CrtYd")
		)
		(fp_line
			(start 0.85 1.65)
			(end -0.85 1.65)
			(stroke
				(width 0.05)
				(type solid)
			)
			(layer "F.CrtYd")
		)
		(fp_line
			(start -0.85 1.65)
			(end -0.85 1.4)
			(stroke
				(width 0.05)
				(type solid)
			)
			(layer "F.CrtYd")
		)
		(fp_line
			(start -0.437 -1.526)
			(end 0.688 -1.526)
			(stroke
				(width 0.15)
				(type solid)
			)
			(layer "F.Fab")
		)
		(fp_line
			(start -0.437 -1.526)
			(end -0.712 -1.325)
			(stroke
				(width 0.15)
				(type solid)
			)
			(layer "F.Fab")
		)
		(fp_line
			(start -0.712 -1.325)
			(end -0.712 1.523)
			(stroke
				(width 0.15)
				(type solid)
			)
			(layer "F.Fab")
		)
		(fp_line
			(start 0.688 1.519)
			(end 0.688 -1.52)
			(stroke
				(width 0.15)
				(type solid)
			)
			(layer "F.Fab")
		)
		(fp_line
			(start -0.712 1.519)
			(end 0.688 1.519)
			(stroke
				(width 0.15)
				(type solid)
			)
			(layer "F.Fab")
		)
		(pad "1" smd roundrect
			(at -1.1 -0.951 90)
			(size 1 0.6)
			(layers "F.Cu" "F.Mask" "F.Paste")
			(roundrect_rratio 0.15)
			(net 747 "/DC-DC Converters/1V85_OUT")
			(pinfunction "IN")
			(pintype "power_in")
		)
		(pad "2" smd roundrect
			(at -1.1 0.949 90)
			(size 1 0.6)
			(layers "F.Cu" "F.Mask" "F.Paste")
			(roundrect_rratio 0.15)
			(net 15 "Net-(U41-OUT)")
			(pinfunction "OUT")
			(pintype "output")
		)
		(pad "3" smd roundrect
			(at 1.1 -0.0005 90)
			(size 1 0.6)
			(layers "F.Cu" "F.Mask" "F.Paste")
			(roundrect_rratio 0.15)
			(net 1 "GND")
			(pinfunction "GND")
			(pintype "passive")
		)
	)
	(footprint "antmicro-footprints:XDFN4"
		(layer "F.Cu")
		(at 152.5 146.65 -90)
		(property "Reference" "U38"
			(at -0.85 -0.4 90)
			(layer "F.SilkS")
			(effects
				(font
					(size 0.7 0.7)
					(thickness 0.15)
				)
				(justify left bottom)
			)
		)
		(property "Value" "TPS7A20185PDQNR"
			(at -1.73 1.92 270)
			(layer "F.Fab")
			(effects
				(font
					(size 0.7 0.7)
					(thickness 0.15)
				)
				(justify left bottom)
			)
		)
		(property "Description" "Linear voltage regulator"
			(at 0 0 270)
			(layer "F.Fab")
			(hide yes)
			(effects
				(font
					(size 1.27 1.27)
					(thickness 0.15)
				)
			)
		)
		(property "Author" "Antmicro"
			(at 5.85 299.15 0)
			(layer "F.Fab")
			(hide yes)
			(effects
				(font
					(size 1 1)
					(thickness 0.15)
				)
			)
		)
		(property "License" "Apache-2.0"
			(at 5.85 299.15 0)
			(layer "F.Fab")
			(hide yes)
			(effects
				(font
					(size 1 1)
					(thickness 0.15)
				)
			)
		)
		(property "MPN" "TPS7A20185PDQNR"
			(at 5.85 299.15 0)
			(layer "F.Fab")
			(hide yes)
			(effects
				(font
					(size 1 1)
					(thickness 0.15)
				)
			)
		)
		(property "Manufacturer" "Texas Instruments"
			(at 5.85 299.15 0)
			(layer "F.Fab")
			(hide yes)
			(effects
				(font
					(size 1 1)
					(thickness 0.15)
				)
			)
		)
		(sheetname "DC-DC Converters")
		(sheetfile "dc-dc.kicad_sch")
		(attr smd)
		(fp_circle
			(center -0.75 -0.6)
			(end -0.699 -0.6)
			(stroke
				(width 0.15)
				(type solid)
			)
			(fill yes)
			(layer "F.SilkS")
		)
		(fp_poly
			(pts
				(xy -0.152 -0.152) (xy 0.15 -0.152) (xy 0.15 0.15) (xy -0.152 0.15)
			)
			(stroke
				(width 0.01)
				(type solid)
			)
			(fill yes)
			(layer "F.Paste")
		)
		(fp_poly
			(pts
				(xy -0.652 -0.452) (xy -0.18 -0.452) (xy -0.43 -0.202) (xy -0.652 -0.202)
			)
			(stroke
				(width 0.01)
				(type solid)
			)
			(fill yes)
			(layer "F.Paste")
		)
		(fp_poly
			(pts
				(xy -0.652 0.45) (xy -0.25 0.45) (xy -0.25 0.378) (xy -0.43 0.2) (xy -0.652 0.2)
			)
			(stroke
				(width 0.01)
				(type solid)
			)
			(fill yes)
			(layer "F.Paste")
		)
		(fp_poly
			(pts
				(xy 0.65 0.45) (xy 0.248 0.45) (xy 0.248 0.378) (xy 0.428 0.2) (xy 0.65 0.2)
			)
			(stroke
				(width 0.01)
				(type solid)
			)
			(fill yes)
			(layer "F.Paste")
		)
		(fp_poly
			(pts
				(xy 0.65 -0.452) (xy 0.248 -0.452) (xy 0.248 -0.38) (xy 0.428 -0.202) (xy 0.65 -0.202)
			)
			(stroke
				(width 0.01)
				(type solid)
			)
			(fill yes)
			(layer "F.Paste")
		)
		(fp_rect
			(start -0.8 -0.8)
			(end 0.8 0.8)
			(stroke
				(width 0.05)
				(type solid)
			)
			(fill no)
			(layer "F.CrtYd")
		)
		(fp_line
			(start -0.5 -0.3)
			(end -0.3 -0.5)
			(stroke
				(width 0.15)
				(type solid)
			)
			(layer "F.Fab")
		)
		(fp_rect
			(start -0.5 -0.5)
			(end 0.498 0.498)
			(stroke
				(width 0.15)
				(type solid)
			)
			(fill no)
			(layer "F.Fab")
		)
		(pad "1" smd custom
			(at -0.452 -0.327 270)
			(size 0.1 0.1)
			(layers "F.Cu")
			(net 747 "/DC-DC Converters/1V85_OUT")
			(pinfunction "VOUT")
			(pintype "power_out")
			(zone_connect 2)
			(options
				(clearance outline)
				(anchor rect)
			)
			(primitives
				(gr_poly
					(pts
						(xy -0.2 -0.125) (xy 0.27 -0.125) (xy 0.02 0.125) (xy -0.2 0.125)
					)
					(width 0.01)
					(fill yes)
				)
			)
		)
		(pad "2" smd custom
			(at -0.452 0.325 270)
			(size 0.1 0.1)
			(layers "F.Cu")
			(net 1 "GND")
			(pinfunction "GND")
			(pintype "power_in")
			(zone_connect 2)
			(options
				(clearance outline)
				(anchor rect)
			)
			(primitives
				(gr_poly
					(pts
						(xy -0.2 0.125) (xy 0.2 0.125) (xy 0.2 0.055) (xy 0.02 -0.125) (xy -0.2 -0.125)
					)
					(width 0.01)
					(fill yes)
				)
			)
		)
		(pad "3" smd custom
			(at 0.45 0.325 270)
			(size 0.1 0.1)
			(layers "F.Cu")
			(net 742 "/DC-DC Converters/1V85_VIN")
			(pinfunction "EN")
			(pintype "input")
			(zone_connect 2)
			(options
				(clearance outline)
				(anchor rect)
			)
			(primitives
				(gr_poly
					(pts
						(xy 0.2 0.125) (xy -0.2 0.125) (xy -0.2 0.055) (xy -0.02 -0.125) (xy 0.2 -0.125)
					)
					(width 0.01)
					(fill yes)
				)
			)
		)
		(pad "4" smd custom
			(at 0.45 -0.327 270)
			(size 0.1 0.1)
			(layers "F.Cu")
			(net 742 "/DC-DC Converters/1V85_VIN")
			(pinfunction "VIN")
			(pintype "input")
			(zone_connect 2)
			(options
				(clearance outline)
				(anchor rect)
			)
			(primitives
				(gr_poly
					(pts
						(xy 0.2 -0.125) (xy -0.2 -0.125) (xy -0.2 -0.055) (xy -0.02 0.125) (xy 0.2 0.125)
					)
					(width 0.01)
					(fill yes)
				)
			)
		)
		(pad "5" smd rect
			(at 0 0 315)
			(size 0.48 0.48)
			(layers "F.Cu" "F.Mask")
			(net 1 "GND")
			(pinfunction "EXP")
			(pintype "passive")
			(zone_connect 2)
		)
	)
	(footprint "antmicro-footprints:NetTie-2_SMD_Pad0.127mm"
		(layer "F.Cu")
		(at 247.3 143.602 90)
		(descr "Net tie, 2 pin, 0.127mm  SMD pads")
		(tags "net tie")
		(property "Reference" "NT21"
			(at -0.128 -1.345 90)
			(layer "F.SilkS")
			(hide yes)
			(effects
				(font
					(size 0.7 0.7)
					(thickness 0.15)
				)
				(justify left bottom)
			)
		)
		(property "Value" "Net-Tie_2"
			(at 0 1.199 90)
			(layer "F.Fab")
			(effects
				(font
					(size 0.7 0.7)
					(thickness 0.15)
				)
				(justify left bottom)
			)
		)
		(property "Description" "Net tie, 2 pins"
			(at 0 0 90)
			(layer "F.Fab")
			(hide yes)
			(effects
				(font
					(size 1.27 1.27)
					(thickness 0.15)
				)
			)
		)
		(property "Author" "Antmicro"
			(at 390.902 -103.698 0)
			(layer "F.Fab")
			(hide yes)
			(effects
				(font
					(size 1 1)
					(thickness 0.15)
				)
			)
		)
		(property "License" "Apache-2.0"
			(at 390.902 -103.698 0)
			(layer "F.Fab")
			(hide yes)
			(effects
				(font
					(size 1 1)
					(thickness 0.15)
				)
			)
		)
		(property "MPN" ""
			(at 390.902 -103.698 0)
			(layer "F.Fab")
			(hide yes)
			(effects
				(font
					(size 1 1)
					(thickness 0.15)
				)
			)
		)
		(property "Manufacturer" ""
			(at 390.902 -103.698 0)
			(layer "F.Fab")
			(hide yes)
			(effects
				(font
					(size 1 1)
					(thickness 0.15)
				)
			)
		)
		(sheetname "FPGA Config")
		(sheetfile "fpga-config.kicad_sch")
		(attr exclude_from_pos_files)
		(net_tie_pad_groups "1, 2")
		(fp_poly
			(pts
				(xy -0.0635 -0.0635) (xy 0.0625 -0.0635) (xy 0.0625 0.0635) (xy -0.0635 0.0635)
			)
			(stroke
				(width 0)
				(type solid)
			)
			(fill yes)
			(layer "F.Cu")
		)
		(pad "1" smd roundrect
			(at -0.127 0 270)
			(size 0.127 0.127)
			(layers "F.Cu")
			(roundrect_rratio 0.5)
			(chamfer_ratio 0)
			(chamfer top_left bottom_left)
			(net 1335 "/SUP_MCU.TEMP_ALERT_N")
			(pinfunction "1")
			(pintype "passive")
		)
		(pad "2" smd roundrect
			(at 0.126 0 90)
			(size 0.127 0.127)
			(layers "F.Cu")
			(roundrect_rratio 0.5)
			(chamfer_ratio 0)
			(chamfer top_left bottom_left)
			(net 113 "/FPGA Config/TEMP_~{ALERT}")
			(pinfunction "2")
			(pintype "passive")
		)
	)
	(footprint "antmicro-footprints:C_0402_1005Metric"
		(layer "F.Cu")
		(at 173.570001 109.016251 180)
		(descr "Capacitor SMD 0402")
		(tags "capacitor SMD 0402")
		(property "Reference" "C301"
			(at -3.729999 -0.383749 0)
			(layer "F.SilkS")
			(effects
				(font
					(size 0.7 0.7)
					(thickness 0.15)
				)
				(justify right bottom)
			)
		)
		(property "Value" "C_100n_0402"
			(at 0 1.4 0)
			(layer "F.Fab")
			(effects
				(font
					(size 0.7 0.7)
					(thickness 0.15)
				)
				(justify right bottom)
			)
		)
		(property "Description" "SMD Multilayer Ceramic Capacitor, 0.1 µF, 50 V, 0402 [1005 Metric], ± 10%, X5R, GRM Series"
			(at 0 0 180)
			(layer "F.Fab")
			(hide yes)
			(effects
				(font
					(size 1.27 1.27)
					(thickness 0.15)
				)
			)
		)
		(property "Author" "Antmicro"
			(at 347.140002 218.032502 0)
			(layer "F.Fab")
			(hide yes)
			(effects
				(font
					(size 1 1)
					(thickness 0.15)
				)
			)
		)
		(property "Dielectric" "X5R"
			(at 347.140002 218.032502 0)
			(layer "F.Fab")
			(hide yes)
			(effects
				(font
					(size 1 1)
					(thickness 0.15)
				)
			)
		)
		(property "License" "Apache-2.0"
			(at 347.140002 218.032502 0)
			(layer "F.Fab")
			(hide yes)
			(effects
				(font
					(size 1 1)
					(thickness 0.15)
				)
			)
		)
		(property "MPN" "GRM155R61H104KE14D"
			(at 347.140002 218.032502 0)
			(layer "F.Fab")
			(hide yes)
			(effects
				(font
					(size 1 1)
					(thickness 0.15)
				)
			)
		)
		(property "Manufacturer" "Murata"
			(at 347.140002 218.032502 0)
			(layer "F.Fab")
			(hide yes)
			(effects
				(font
					(size 1 1)
					(thickness 0.15)
				)
			)
		)
		(property "Val" "100n"
			(at 347.140002 218.032502 0)
			(layer "F.Fab")
			(hide yes)
			(effects
				(font
					(size 1 1)
					(thickness 0.15)
				)
			)
		)
		(property "Voltage" "50V"
			(at 347.140002 218.032502 0)
			(layer "F.Fab")
			(hide yes)
			(effects
				(font
					(size 1 1)
					(thickness 0.15)
				)
			)
		)
		(sheetname "FMC+ HSPC")
		(sheetfile "fmc-hspc.kicad_sch")
		(attr smd)
		(fp_rect
			(start -0.925 -0.47)
			(end 0.925 0.47)
			(stroke
				(width 0.05)
				(type default)
			)
			(fill no)
			(layer "F.CrtYd")
		)
		(fp_line
			(start 0.504 0.248)
			(end -0.494 0.248)
			(stroke
				(width 0.15)
				(type solid)
			)
			(layer "F.Fab")
		)
		(fp_line
			(start 0.504 -0.25)
			(end 0.504 0.248)
			(stroke
				(width 0.15)
				(type solid)
			)
			(layer "F.Fab")
		)
		(fp_line
			(start -0.494 0.248)
			(end -0.494 -0.25)
			(stroke
				(width 0.15)
				(type solid)
			)
			(layer "F.Fab")
		)
		(fp_line
			(start -0.494 -0.25)
			(end 0.504 -0.25)
			(stroke
				(width 0.15)
				(type solid)
			)
			(layer "F.Fab")
		)
		(pad "1" smd roundrect
			(at -0.48 0 180)
			(size 0.59 0.64)
			(layers "F.Cu" "F.Mask" "F.Paste")
			(roundrect_rratio 0.25)
			(net 69 "/FMC+ HSPC/GTX116.TX2_N")
			(pintype "passive")
		)
		(pad "2" smd roundrect
			(at 0.48 0 180)
			(size 0.59 0.64)
			(layers "F.Cu" "F.Mask" "F.Paste")
			(roundrect_rratio 0.25)
			(net 67 "/FMC+ HSPC/GTX_TX1_C_N")
			(pintype "passive")
		)
	)
	(footprint "antmicro-footprints:R_0402_1005Metric"
		(layer "F.Cu")
		(at 259.6 130.7)
		(descr "Resistor SMD 0402")
		(tags "resistor SMD 0402")
		(property "Reference" "R191"
			(at -1.05 -6.1 0)
			(layer "F.SilkS")
			(effects
				(font
					(size 0.7 0.7)
					(thickness 0.15)
				)
				(justify left bottom)
			)
		)
		(property "Value" "R_10k_0402"
			(at 0 1.4 0)
			(layer "F.Fab")
			(effects
				(font
					(size 0.7 0.7)
					(thickness 0.15)
				)
				(justify left bottom)
			)
		)
		(property "Description" "SMD Chip Resistor, 10 kohm, ± 1%, 62.5 mW, 0402 [1005 Metric], Thick Film, General Purpose"
			(at 0 0 0)
			(layer "F.Fab")
			(hide yes)
			(effects
				(font
					(size 1.27 1.27)
					(thickness 0.15)
				)
			)
		)
		(property "Author" "Antmicro"
			(at 0 0 0)
			(layer "F.Fab")
			(hide yes)
			(effects
				(font
					(size 1 1)
					(thickness 0.15)
				)
			)
		)
		(property "License" "Apache-2.0"
			(at 0 0 0)
			(layer "F.Fab")
			(hide yes)
			(effects
				(font
					(size 1 1)
					(thickness 0.15)
				)
			)
		)
		(property "MPN" "CR0402-FX-1002GLF"
			(at 0 0 0)
			(layer "F.Fab")
			(hide yes)
			(effects
				(font
					(size 1 1)
					(thickness 0.15)
				)
			)
		)
		(property "Manufacturer" "Bourns"
			(at 0 0 0)
			(layer "F.Fab")
			(hide yes)
			(effects
				(font
					(size 1 1)
					(thickness 0.15)
				)
			)
		)
		(property "Tolerance" "1%"
			(at 0 0 0)
			(layer "F.Fab")
			(hide yes)
			(effects
				(font
					(size 1 1)
					(thickness 0.15)
				)
			)
		)
		(property "Val" "10k"
			(at 0 0 0)
			(layer "F.Fab")
			(hide yes)
			(effects
				(font
					(size 1 1)
					(thickness 0.15)
				)
			)
		)
		(sheetname "USB PHY")
		(sheetfile "usb-phy.kicad_sch")
		(attr smd)
		(fp_rect
			(start -0.925 -0.47)
			(end 0.925 0.47)
			(stroke
				(width 0.05)
				(type default)
			)
			(fill no)
			(layer "F.CrtYd")
		)
		(fp_rect
			(start -0.5 -0.25)
			(end 0.5 0.25)
			(stroke
				(width 0.15)
				(type solid)
			)
			(fill no)
			(layer "F.Fab")
		)
		(pad "1" smd roundrect
			(at -0.48 0)
			(size 0.59 0.64)
			(layers "F.Cu" "F.Mask" "F.Paste")
			(roundrect_rratio 0.25)
			(net 943 "Net-(R191-Pad1)")
			(pintype "passive")
		)
		(pad "2" smd roundrect
			(at 0.48 0)
			(size 0.59 0.64)
			(layers "F.Cu" "F.Mask" "F.Paste")
			(roundrect_rratio 0.25)
			(net 497 "/FPGA Bank 12 & 13/USB_USER.VDET")
			(pintype "passive")
		)
	)
	(footprint "antmicro-footprints:C_0402_1005Metric"
		(layer "F.Cu")
		(at 245.099 118.904)
		(descr "Capacitor SMD 0402")
		(tags "capacitor SMD 0402")
		(property "Reference" "C397"
			(at -1.949 1.246 0)
			(layer "F.SilkS")
			(effects
				(font
					(size 0.7 0.7)
					(thickness 0.15)
				)
				(justify left bottom)
			)
		)
		(property "Value" "C_10u_0402"
			(at 0 1.4 0)
			(layer "F.Fab")
			(effects
				(font
					(size 0.7 0.7)
					(thickness 0.15)
				)
				(justify left bottom)
			)
		)
		(property "Description" "SMD Multilayer Ceramic Capacitor, 10 µF, 6.3 V, 0402 [1005 Metric], ± 20%, X5R, CC Series"
			(at 0 0 0)
			(layer "F.Fab")
			(hide yes)
			(effects
				(font
					(size 1.27 1.27)
					(thickness 0.15)
				)
			)
		)
		(property "Author" "Antmicro"
			(at 0 0 0)
			(layer "F.Fab")
			(hide yes)
			(effects
				(font
					(size 1 1)
					(thickness 0.15)
				)
			)
		)
		(property "Dielectric" ""
			(at 0 0 0)
			(layer "F.Fab")
			(hide yes)
			(effects
				(font
					(size 1 1)
					(thickness 0.15)
				)
			)
		)
		(property "License" "Apache-2.0"
			(at 0 0 0)
			(layer "F.Fab")
			(hide yes)
			(effects
				(font
					(size 1 1)
					(thickness 0.15)
				)
			)
		)
		(property "MPN" "CC0402MRX5R5BB106"
			(at 0 0 0)
			(layer "F.Fab")
			(hide yes)
			(effects
				(font
					(size 1 1)
					(thickness 0.15)
				)
			)
		)
		(property "Manufacturer" "YAGEO"
			(at 0 0 0)
			(layer "F.Fab")
			(hide yes)
			(effects
				(font
					(size 1 1)
					(thickness 0.15)
				)
			)
		)
		(property "Val" "10u"
			(at 0 0 0)
			(layer "F.Fab")
			(hide yes)
			(effects
				(font
					(size 1 1)
					(thickness 0.15)
				)
			)
		)
		(property "Voltage" ""
			(at 0 0 0)
			(layer "F.Fab")
			(hide yes)
			(effects
				(font
					(size 1 1)
					(thickness 0.15)
				)
			)
		)
		(sheetname "USB PHY")
		(sheetfile "usb-phy.kicad_sch")
		(attr smd)
		(fp_rect
			(start -0.925 -0.47)
			(end 0.925 0.47)
			(stroke
				(width 0.05)
				(type default)
			)
			(fill no)
			(layer "F.CrtYd")
		)
		(fp_line
			(start -0.494 -0.25)
			(end 0.504 -0.25)
			(stroke
				(width 0.15)
				(type solid)
			)
			(layer "F.Fab")
		)
		(fp_line
			(start -0.494 0.248)
			(end -0.494 -0.25)
			(stroke
				(width 0.15)
				(type solid)
			)
			(layer "F.Fab")
		)
		(fp_line
			(start 0.504 -0.25)
			(end 0.504 0.248)
			(stroke
				(width 0.15)
				(type solid)
			)
			(layer "F.Fab")
		)
		(fp_line
			(start 0.504 0.248)
			(end -0.494 0.248)
			(stroke
				(width 0.15)
				(type solid)
			)
			(layer "F.Fab")
		)
		(pad "1" smd roundrect
			(at -0.48 0)
			(size 0.59 0.64)
			(layers "F.Cu" "F.Mask" "F.Paste")
			(roundrect_rratio 0.25)
			(net 1 "GND")
			(pintype "passive")
		)
		(pad "2" smd roundrect
			(at 0.48 0)
			(size 0.59 0.64)
			(layers "F.Cu" "F.Mask" "F.Paste")
			(roundrect_rratio 0.25)
			(net 715 "/USB PHY/USB_USR_VBUS")
			(pintype "passive")
		)
	)
	(footprint "antmicro-footprints:MP_Pad6mm_Drill3mm"
		(layer "F.Cu")
		(at 153.5 73.5)
		(property "Reference" "MH4"
			(at -0.178 4.025 0)
			(layer "F.SilkS")
			(hide yes)
			(effects
				(font
					(size 0.7 0.7)
					(thickness 0.15)
				)
				(justify left bottom)
			)
		)
		(property "Value" "MP_Pad6mm_Drill3mm"
			(at -0.153 -4.153 0)
			(layer "F.Fab")
			(effects
				(font
					(size 0.7 0.7)
					(thickness 0.15)
				)
				(justify left bottom)
			)
		)
		(property "Description" "Mechanical part"
			(at 0 0 0)
			(layer "F.Fab")
			(hide yes)
			(effects
				(font
					(size 1.27 1.27)
					(thickness 0.15)
				)
			)
		)
		(property "Author" "Antmicro"
			(at 0 0 0)
			(layer "F.Fab")
			(hide yes)
			(effects
				(font
					(size 1 1)
					(thickness 0.15)
				)
			)
		)
		(property "License" "Apache-2.0"
			(at 0 0 0)
			(layer "F.Fab")
			(hide yes)
			(effects
				(font
					(size 1 1)
					(thickness 0.15)
				)
			)
		)
		(property "MPN" ""
			(at 0 0 0)
			(layer "F.Fab")
			(hide yes)
			(effects
				(font
					(size 1 1)
					(thickness 0.15)
				)
			)
		)
		(property "Manufacturer" ""
			(at 0 0 0)
			(layer "F.Fab")
			(hide yes)
			(effects
				(font
					(size 1 1)
					(thickness 0.15)
				)
			)
		)
		(property "exclude_from_bom" ""
			(at 0 0 0)
			(layer "F.Fab")
			(hide yes)
			(effects
				(font
					(size 1 1)
					(thickness 0.15)
				)
			)
		)
		(sheetfile "k410t-devboard.kicad_sch")
		(attr exclude_from_pos_files exclude_from_bom)
		(pad "1" thru_hole circle
			(at 0 0)
			(size 6 6)
			(drill 3)
			(layers "*.Cu" "*.Mask")
			(remove_unused_layers no)
			(net 1 "GND")
			(pintype "passive")
		)
	)
	(footprint "antmicro-footprints:Vishay_PowerPAK_1212-8_Single"
		(layer "F.Cu")
		(at 231.235 157.2)
		(descr "PowerPAK 1212-8 Single")
		(tags "Vishay PowerPAK 1212-8 Single")
		(property "Reference" "Q3"
			(at -2.1 -1.9 0)
			(layer "F.SilkS")
			(effects
				(font
					(size 0.7 0.7)
					(thickness 0.15)
				)
				(justify left bottom)
			)
		)
		(property "Value" "SI7613DN-T1-GE3"
			(at -8 2.7 0)
			(layer "F.Fab")
			(effects
				(font
					(size 0.7 0.7)
					(thickness 0.15)
				)
				(justify left bottom)
			)
		)
		(property "Description" "Power MOSFET, P Channel, 20 V, 35 A, 0.0072 ohm, PowerPAK 1212, Surface Mount"
			(at 0 0 0)
			(layer "F.Fab")
			(hide yes)
			(effects
				(font
					(size 1.27 1.27)
					(thickness 0.15)
				)
			)
		)
		(property "Author" "Antmicro"
			(at 0 0 0)
			(layer "F.Fab")
			(hide yes)
			(effects
				(font
					(size 1 1)
					(thickness 0.15)
				)
			)
		)
		(property "License" "Apache-2.0"
			(at 0 0 0)
			(layer "F.Fab")
			(hide yes)
			(effects
				(font
					(size 1 1)
					(thickness 0.15)
				)
			)
		)
		(property "MPN" "SI7613DN-T1-GE3"
			(at 0 0 0)
			(layer "F.Fab")
			(hide yes)
			(effects
				(font
					(size 1 1)
					(thickness 0.15)
				)
			)
		)
		(property "Manufacturer" "Vishay"
			(at 0 0 0)
			(layer "F.Fab")
			(hide yes)
			(effects
				(font
					(size 1 1)
					(thickness 0.15)
				)
			)
		)
		(sheetname "Power supply")
		(sheetfile "power-supply.kicad_sch")
		(attr smd)
		(fp_line
			(start -1.651 -1.651)
			(end -1.651 -1.317)
			(stroke
				(width 0.15)
				(type solid)
			)
			(layer "F.SilkS")
		)
		(fp_line
			(start -1.651 -1.651)
			(end 1.648 -1.651)
			(stroke
				(width 0.15)
				(type solid)
			)
			(layer "F.SilkS")
		)
		(fp_line
			(start -1.635 1.3)
			(end -1.635 1.634)
			(stroke
				(width 0.15)
				(type solid)
			)
			(layer "F.SilkS")
		)
		(fp_line
			(start -1.635 1.634)
			(end 1.634 1.634)
			(stroke
				(width 0.15)
				(type solid)
			)
			(layer "F.SilkS")
		)
		(fp_line
			(start 1.634 1.3)
			(end 1.634 1.634)
			(stroke
				(width 0.15)
				(type solid)
			)
			(layer "F.SilkS")
		)
		(fp_line
			(start 1.648 -1.651)
			(end 1.648 -1.317)
			(stroke
				(width 0.15)
				(type solid)
			)
			(layer "F.SilkS")
		)
		(fp_circle
			(center -1.9 -1.4)
			(end -1.85 -1.4)
			(stroke
				(width 0.15)
				(type solid)
			)
			(fill yes)
			(layer "F.SilkS")
		)
		(fp_rect
			(start -2 -1.8)
			(end 2 1.798)
			(stroke
				(width 0.05)
				(type solid)
			)
			(fill no)
			(layer "F.CrtYd")
		)
		(fp_line
			(start -1.6425 -1.4175)
			(end -1.4175 -1.6425)
			(stroke
				(width 0.15)
				(type solid)
			)
			(layer "F.Fab")
		)
		(fp_rect
			(start -1.651 -1.651)
			(end 1.648 1.648)
			(stroke
				(width 0.15)
				(type solid)
			)
			(fill no)
			(layer "F.Fab")
		)
		(pad "1" smd rect
			(at -1.436 -0.99)
			(size 0.99 0.405)
			(layers "F.Cu" "F.Mask" "F.Paste")
			(net 5 "/Power supply/PD_VBUS")
			(pinfunction "S")
			(pintype "passive")
		)
		(pad "2" smd rect
			(at -1.436 -0.332)
			(size 0.99 0.405)
			(layers "F.Cu" "F.Mask" "F.Paste")
			(net 5 "/Power supply/PD_VBUS")
			(pinfunction "S")
			(pintype "passive")
		)
		(pad "3" smd rect
			(at -1.436 0.33)
			(size 0.99 0.405)
			(layers "F.Cu" "F.Mask" "F.Paste")
			(net 5 "/Power supply/PD_VBUS")
			(pinfunction "S")
			(pintype "passive")
		)
		(pad "4" smd rect
			(at -1.436 0.988)
			(size 0.99 0.405)
			(layers "F.Cu" "F.Mask" "F.Paste")
			(net 872 "/Power supply/SINK_EN")
			(pinfunction "G")
			(pintype "passive")
		)
		(pad "5" smd custom
			(at 0.557 0)
			(size 1.725 2.235)
			(layers "F.Cu" "F.Mask" "F.Paste")
			(net 704 "/Power supply/USB_DBG_PD.VBUS")
			(pinfunction "D")
			(pintype "passive")
			(zone_connect 2)
			(options
				(clearance outline)
				(anchor rect)
			)
			(primitives
				(gr_poly
					(pts
						(xy 0.8625 0.1275) (xy 0.8625 -0.1275) (xy 1.3725 -0.1275) (xy 1.3725 -0.5325) (xy 0.8625 -0.5325)
						(xy 0.8625 -0.7875) (xy 1.3725 -0.7875) (xy 1.3725 -1.195) (xy 0.6125 -1.195) (xy 0.6125 1.195)
						(xy 1.3725 1.195) (xy 1.3725 0.7875) (xy 0.8625 0.7875) (xy 0.8625 0.5325) (xy 1.3725 0.5325)
						(xy 1.3725 0.1275)
					)
					(width 0)
					(fill yes)
				)
			)
		)
	)
	(footprint "antmicro-footprints:NetTie-2_SMD_Pad0.127mm"
		(layer "F.Cu")
		(at 160.773 145.3)
		(descr "Net tie, 2 pin, 0.127mm  SMD pads")
		(tags "net tie")
		(property "Reference" "NT2"
			(at -0.128 -1.345 0)
			(layer "F.SilkS")
			(hide yes)
			(effects
				(font
					(size 0.7 0.7)
					(thickness 0.15)
				)
				(justify left bottom)
			)
		)
		(property "Value" "Net-Tie_2"
			(at 0 1.199 0)
			(layer "F.Fab")
			(effects
				(font
					(size 0.7 0.7)
					(thickness 0.15)
				)
				(justify left bottom)
			)
		)
		(property "Description" "Net tie, 2 pins"
			(at 0 0 0)
			(layer "F.Fab")
			(hide yes)
			(effects
				(font
					(size 1.27 1.27)
					(thickness 0.15)
				)
			)
		)
		(property "Author" "Antmicro"
			(at 0 0 0)
			(layer "F.Fab")
			(hide yes)
			(effects
				(font
					(size 1 1)
					(thickness 0.15)
				)
			)
		)
		(property "License" "Apache-2.0"
			(at 0 0 0)
			(layer "F.Fab")
			(hide yes)
			(effects
				(font
					(size 1 1)
					(thickness 0.15)
				)
			)
		)
		(property "MPN" ""
			(at 0 0 0)
			(layer "F.Fab")
			(hide yes)
			(effects
				(font
					(size 1 1)
					(thickness 0.15)
				)
			)
		)
		(property "Manufacturer" ""
			(at 0 0 0)
			(layer "F.Fab")
			(hide yes)
			(effects
				(font
					(size 1 1)
					(thickness 0.15)
				)
			)
		)
		(sheetname "DC-DC Converters")
		(sheetfile "dc-dc.kicad_sch")
		(attr exclude_from_pos_files)
		(net_tie_pad_groups "1, 2")
		(fp_poly
			(pts
				(xy -0.0635 -0.0635) (xy 0.0625 -0.0635) (xy 0.0625 0.0635) (xy -0.0635 0.0635)
			)
			(stroke
				(width 0)
				(type solid)
			)
			(fill yes)
			(layer "F.Cu")
		)
		(pad "1" smd roundrect
			(at -0.127 0 180)
			(size 0.127 0.127)
			(layers "F.Cu")
			(roundrect_rratio 0.5)
			(chamfer_ratio 0)
			(chamfer top_left bottom_left)
			(net 1 "GND")
			(pinfunction "1")
			(pintype "passive")
		)
		(pad "2" smd roundrect
			(at 0.126 0)
			(size 0.127 0.127)
			(layers "F.Cu")
			(roundrect_rratio 0.5)
			(chamfer_ratio 0)
			(chamfer top_left bottom_left)
			(net 870 "VREFN")
			(pinfunction "2")
			(pintype "passive")
		)
	)
	(footprint "antmicro-footprints:SW_KMR211NGLFS_SMD"
		(layer "F.Cu")
		(at 266.8 79.4 180)
		(property "Reference" "S2"
			(at 0.7 -2.6 180)
			(layer "F.SilkS")
			(effects
				(font
					(size 0.7 0.7)
					(thickness 0.15)
				)
				(justify left bottom)
			)
		)
		(property "Value" "SW_KMR211NGLFS_SMD"
			(at -3 3 180)
			(layer "F.Fab")
			(effects
				(font
					(size 0.7 0.7)
					(thickness 0.15)
				)
				(justify left bottom)
			)
		)
		(property "Description" "Tactile Switch, KMR 2 Series, Top Actuated, Surface Mount, Oval Button, 120 gf, 50mA at 32VDC"
			(at 0 0 180)
			(layer "F.Fab")
			(hide yes)
			(effects
				(font
					(size 1.27 1.27)
					(thickness 0.15)
				)
			)
		)
		(property "Author" "Antmicro"
			(at 533.6 158.8 0)
			(layer "F.Fab")
			(hide yes)
			(effects
				(font
					(size 1 1)
					(thickness 0.15)
				)
			)
		)
		(property "License" "Apache-2.0"
			(at 533.6 158.8 0)
			(layer "F.Fab")
			(hide yes)
			(effects
				(font
					(size 1 1)
					(thickness 0.15)
				)
			)
		)
		(property "MPN" "KMR211NGLFS"
			(at 533.6 158.8 0)
			(layer "F.Fab")
			(hide yes)
			(effects
				(font
					(size 1 1)
					(thickness 0.15)
				)
			)
		)
		(property "Manufacturer" "C&K"
			(at 533.6 158.8 0)
			(layer "F.Fab")
			(hide yes)
			(effects
				(font
					(size 1 1)
					(thickness 0.15)
				)
			)
		)
		(sheetname "User GPIO + LED + button + DIP switch")
		(sheetfile "user-gpio.kicad_sch")
		(attr smd)
		(fp_line
			(start 2.101 1.601)
			(end 2.101 1.48)
			(stroke
				(width 0.15)
				(type solid)
			)
			(layer "F.SilkS")
		)
		(fp_line
			(start 2.101 1.601)
			(end -2.1 1.601)
			(stroke
				(width 0.15)
				(type solid)
			)
			(layer "F.SilkS")
		)
		(fp_line
			(start 2.101 -1.58)
			(end 2.101 -1.459)
			(stroke
				(width 0.15)
				(type solid)
			)
			(layer "F.SilkS")
		)
		(fp_line
			(start 2.101 -1.6)
			(end -2.1 -1.6)
			(stroke
				(width 0.15)
				(type solid)
			)
			(layer "F.SilkS")
		)
		(fp_line
			(start -2.1 1.601)
			(end -2.1 1.48)
			(stroke
				(width 0.15)
				(type solid)
			)
			(layer "F.SilkS")
		)
		(fp_line
			(start -2.1 -1.6)
			(end -2.1 -1.499)
			(stroke
				(width 0.15)
				(type solid)
			)
			(layer "F.SilkS")
		)
		(fp_rect
			(start 2.751 1.75)
			(end -2.748 -1.749)
			(stroke
				(width 0.05)
				(type solid)
			)
			(fill no)
			(layer "F.CrtYd")
		)
		(fp_line
			(start 2.101 1.601)
			(end 2.101 -1.6)
			(stroke
				(width 0.15)
				(type solid)
			)
			(layer "F.Fab")
		)
		(fp_line
			(start 2.101 -1.6)
			(end -2.1 -1.6)
			(stroke
				(width 0.15)
				(type solid)
			)
			(layer "F.Fab")
		)
		(fp_line
			(start 0.25 0.802)
			(end -0.248 0.802)
			(stroke
				(width 0.15)
				(type solid)
			)
			(layer "F.Fab")
		)
		(fp_line
			(start -0.248 -0.8)
			(end 0.25 -0.8)
			(stroke
				(width 0.15)
				(type solid)
			)
			(layer "F.Fab")
		)
		(fp_line
			(start -2.1 1.601)
			(end 2.101 1.601)
			(stroke
				(width 0.15)
				(type solid)
			)
			(layer "F.Fab")
		)
		(fp_line
			(start -2.1 -1.6)
			(end -2.1 1.601)
			(stroke
				(width 0.15)
				(type solid)
			)
			(layer "F.Fab")
		)
		(fp_arc
			(start 0.25 -0.8)
			(mid 1.051001 0.001)
			(end 0.25 0.802)
			(stroke
				(width 0.15)
				(type solid)
			)
			(layer "F.Fab")
		)
		(fp_arc
			(start -0.248 0.802)
			(mid -1.050001 0.001)
			(end -0.248 -0.8)
			(stroke
				(width 0.15)
				(type solid)
			)
			(layer "F.Fab")
		)
		(pad "1" smd rect
			(at -2.048 -0.8)
			(size 0.9 1)
			(layers "F.Cu" "F.Mask" "F.Paste")
			(net 1228 "/USER_IO.BUTTON0")
			(pinfunction "1")
			(pintype "passive")
		)
		(pad "2" smd rect
			(at 2.05 -0.8)
			(size 0.9 1)
			(layers "F.Cu" "F.Mask" "F.Paste")
			(net 1228 "/USER_IO.BUTTON0")
			(pinfunction "2")
			(pintype "passive")
		)
		(pad "3" smd rect
			(at -2.048 0.802)
			(size 0.9 1)
			(layers "F.Cu" "F.Mask" "F.Paste")
			(net 1 "GND")
			(pinfunction "3")
			(pintype "passive")
		)
		(pad "4" smd rect
			(at 2.05 0.802)
			(size 0.9 1)
			(layers "F.Cu" "F.Mask" "F.Paste")
			(net 1 "GND")
			(pinfunction "4")
			(pintype "passive")
		)
	)
	(footprint "antmicro-footprints:R_0402_1005Metric"
		(layer "F.Cu")
		(at 259.6 126.5 180)
		(descr "Resistor SMD 0402")
		(tags "resistor SMD 0402")
		(property "Reference" "R173"
			(at 1.05 5.7 180)
			(layer "F.SilkS")
			(effects
				(font
					(size 0.7 0.7)
					(thickness 0.15)
				)
				(justify left bottom)
			)
		)
		(property "Value" "R_33R_0402"
			(at 0 1.4 180)
			(layer "F.Fab")
			(effects
				(font
					(size 0.7 0.7)
					(thickness 0.15)
				)
				(justify left bottom)
			)
		)
		(property "Description" "SMD Chip Resistor, 33 ohm, ± 1%, 62.5 mW, 0402 [1005 Metric], Thick Film, General Purpose"
			(at 0 0 180)
			(layer "F.Fab")
			(hide yes)
			(effects
				(font
					(size 1.27 1.27)
					(thickness 0.15)
				)
			)
		)
		(property "Author" "Antmicro"
			(at 519.2 253 0)
			(layer "F.Fab")
			(hide yes)
			(effects
				(font
					(size 1 1)
					(thickness 0.15)
				)
			)
		)
		(property "License" "Apache-2.0"
			(at 519.2 253 0)
			(layer "F.Fab")
			(hide yes)
			(effects
				(font
					(size 1 1)
					(thickness 0.15)
				)
			)
		)
		(property "MPN" "CR0402-FX-33R0GLF"
			(at 519.2 253 0)
			(layer "F.Fab")
			(hide yes)
			(effects
				(font
					(size 1 1)
					(thickness 0.15)
				)
			)
		)
		(property "Manufacturer" "Bourns"
			(at 519.2 253 0)
			(layer "F.Fab")
			(hide yes)
			(effects
				(font
					(size 1 1)
					(thickness 0.15)
				)
			)
		)
		(property "Tolerance" "1%"
			(at 519.2 253 0)
			(layer "F.Fab")
			(hide yes)
			(effects
				(font
					(size 1 1)
					(thickness 0.15)
				)
			)
		)
		(property "Val" "33R"
			(at 519.2 253 0)
			(layer "F.Fab")
			(hide yes)
			(effects
				(font
					(size 1 1)
					(thickness 0.15)
				)
			)
		)
		(sheetname "USB PHY")
		(sheetfile "usb-phy.kicad_sch")
		(attr smd)
		(fp_rect
			(start -0.925 -0.47)
			(end 0.925 0.47)
			(stroke
				(width 0.05)
				(type default)
			)
			(fill no)
			(layer "F.CrtYd")
		)
		(fp_rect
			(start -0.5 -0.25)
			(end 0.5 0.25)
			(stroke
				(width 0.15)
				(type solid)
			)
			(fill no)
			(layer "F.Fab")
		)
		(pad "1" smd roundrect
			(at -0.48 0 180)
			(size 0.59 0.64)
			(layers "F.Cu" "F.Mask" "F.Paste")
			(roundrect_rratio 0.25)
			(net 843 "/USB PHY/USB_USR_CONN_D-")
			(pintype "passive")
		)
		(pad "2" smd roundrect
			(at 0.48 0 180)
			(size 0.59 0.64)
			(layers "F.Cu" "F.Mask" "F.Paste")
			(roundrect_rratio 0.25)
			(net 927 "/USB PHY/USB_USR_D-")
			(pintype "passive")
		)
	)
	(footprint "antmicro-footprints:C_0402_1005Metric"
		(layer "F.Cu")
		(at 233.8 145.4 -90)
		(descr "Capacitor SMD 0402")
		(tags "capacitor SMD 0402")
		(property "Reference" "C244"
			(at 1.4 -1.23 270)
			(layer "F.SilkS")
			(effects
				(font
					(size 0.7 0.7)
					(thickness 0.15)
				)
				(justify left bottom)
			)
		)
		(property "Value" "C_100n_0402"
			(at 0 1.169 270)
			(layer "F.Fab")
			(effects
				(font
					(size 0.7 0.7)
					(thickness 0.15)
				)
				(justify left bottom)
			)
		)
		(property "Description" "SMD Multilayer Ceramic Capacitor, 0.1 µF, 50 V, 0402 [1005 Metric], ± 10%, X5R, GRM Series"
			(at 0 0 270)
			(layer "F.Fab")
			(hide yes)
			(effects
				(font
					(size 1.27 1.27)
					(thickness 0.15)
				)
			)
		)
		(property "Author" "Antmicro"
			(at 88.4 379.2 0)
			(layer "F.Fab")
			(hide yes)
			(effects
				(font
					(size 1 1)
					(thickness 0.15)
				)
			)
		)
		(property "Dielectric" "X5R"
			(at 88.4 379.2 0)
			(layer "F.Fab")
			(hide yes)
			(effects
				(font
					(size 1 1)
					(thickness 0.15)
				)
			)
		)
		(property "License" "Apache-2.0"
			(at 88.4 379.2 0)
			(layer "F.Fab")
			(hide yes)
			(effects
				(font
					(size 1 1)
					(thickness 0.15)
				)
			)
		)
		(property "MPN" "GRM155R61H104KE14D"
			(at 88.4 379.2 0)
			(layer "F.Fab")
			(hide yes)
			(effects
				(font
					(size 1 1)
					(thickness 0.15)
				)
			)
		)
		(property "Manufacturer" "Murata"
			(at 88.4 379.2 0)
			(layer "F.Fab")
			(hide yes)
			(effects
				(font
					(size 1 1)
					(thickness 0.15)
				)
			)
		)
		(property "Val" "100n"
			(at 88.4 379.2 0)
			(layer "F.Fab")
			(hide yes)
			(effects
				(font
					(size 1 1)
					(thickness 0.15)
				)
			)
		)
		(property "Voltage" "50V"
			(at 88.4 379.2 0)
			(layer "F.Fab")
			(hide yes)
			(effects
				(font
					(size 1 1)
					(thickness 0.15)
				)
			)
		)
		(sheetname "USB PHY")
		(sheetfile "usb-phy.kicad_sch")
		(attr smd)
		(fp_rect
			(start -0.925 -0.47)
			(end 0.925 0.47)
			(stroke
				(width 0.05)
				(type default)
			)
			(fill no)
			(layer "F.CrtYd")
		)
		(fp_line
			(start -0.494 0.248)
			(end -0.494 -0.25)
			(stroke
				(width 0.15)
				(type solid)
			)
			(layer "F.Fab")
		)
		(fp_line
			(start 0.504 0.248)
			(end -0.494 0.248)
			(stroke
				(width 0.15)
				(type solid)
			)
			(layer "F.Fab")
		)
		(fp_line
			(start -0.494 -0.25)
			(end 0.504 -0.25)
			(stroke
				(width 0.15)
				(type solid)
			)
			(layer "F.Fab")
		)
		(fp_line
			(start 0.504 -0.25)
			(end 0.504 0.248)
			(stroke
				(width 0.15)
				(type solid)
			)
			(layer "F.Fab")
		)
		(pad "1" smd roundrect
			(at -0.48 0 270)
			(size 0.59 0.64)
			(layers "F.Cu" "F.Mask" "F.Paste")
			(roundrect_rratio 0.25)
			(net 1 "GND")
			(pintype "passive")
		)
		(pad "2" smd roundrect
			(at 0.48 0 270)
			(size 0.59 0.64)
			(layers "F.Cu" "F.Mask" "F.Paste")
			(roundrect_rratio 0.25)
			(net 24 "+3V3")
			(pintype "passive")
		)
	)
	(footprint "antmicro-footprints:C_0402_1005Metric"
		(layer "F.Cu")
		(at 245.6 141.6 90)
		(descr "Capacitor SMD 0402")
		(tags "capacitor SMD 0402")
		(property "Reference" "C233"
			(at -1.7 6.4 90)
			(layer "F.SilkS")
			(effects
				(font
					(size 0.7 0.7)
					(thickness 0.15)
				)
				(justify left bottom)
			)
		)
		(property "Value" "C_100n_0402"
			(at 0 1.169 90)
			(layer "F.Fab")
			(effects
				(font
					(size 0.7 0.7)
					(thickness 0.15)
				)
				(justify left bottom)
			)
		)
		(property "Description" "SMD Multilayer Ceramic Capacitor, 0.1 µF, 50 V, 0402 [1005 Metric], ± 10%, X5R, GRM Series"
			(at 0 0 90)
			(layer "F.Fab")
			(hide yes)
			(effects
				(font
					(size 1.27 1.27)
					(thickness 0.15)
				)
			)
		)
		(property "Author" "Antmicro"
			(at 387.2 -104 0)
			(layer "F.Fab")
			(hide yes)
			(effects
				(font
					(size 1 1)
					(thickness 0.15)
				)
			)
		)
		(property "Dielectric" "X5R"
			(at 387.2 -104 0)
			(layer "F.Fab")
			(hide yes)
			(effects
				(font
					(size 1 1)
					(thickness 0.15)
				)
			)
		)
		(property "License" "Apache-2.0"
			(at 387.2 -104 0)
			(layer "F.Fab")
			(hide yes)
			(effects
				(font
					(size 1 1)
					(thickness 0.15)
				)
			)
		)
		(property "MPN" "GRM155R61H104KE14D"
			(at 387.2 -104 0)
			(layer "F.Fab")
			(hide yes)
			(effects
				(font
					(size 1 1)
					(thickness 0.15)
				)
			)
		)
		(property "Manufacturer" "Murata"
			(at 387.2 -104 0)
			(layer "F.Fab")
			(hide yes)
			(effects
				(font
					(size 1 1)
					(thickness 0.15)
				)
			)
		)
		(property "Val" "100n"
			(at 387.2 -104 0)
			(layer "F.Fab")
			(hide yes)
			(effects
				(font
					(size 1 1)
					(thickness 0.15)
				)
			)
		)
		(property "Voltage" "50V"
			(at 387.2 -104 0)
			(layer "F.Fab")
			(hide yes)
			(effects
				(font
					(size 1 1)
					(thickness 0.15)
				)
			)
		)
		(sheetname "USB PHY")
		(sheetfile "usb-phy.kicad_sch")
		(attr smd)
		(fp_rect
			(start -0.925 -0.47)
			(end 0.925 0.47)
			(stroke
				(width 0.05)
				(type default)
			)
			(fill no)
			(layer "F.CrtYd")
		)
		(fp_line
			(start 0.504 -0.25)
			(end 0.504 0.248)
			(stroke
				(width 0.15)
				(type solid)
			)
			(layer "F.Fab")
		)
		(fp_line
			(start -0.494 -0.25)
			(end 0.504 -0.25)
			(stroke
				(width 0.15)
				(type solid)
			)
			(layer "F.Fab")
		)
		(fp_line
			(start 0.504 0.248)
			(end -0.494 0.248)
			(stroke
				(width 0.15)
				(type solid)
			)
			(layer "F.Fab")
		)
		(fp_line
			(start -0.494 0.248)
			(end -0.494 -0.25)
			(stroke
				(width 0.15)
				(type solid)
			)
			(layer "F.Fab")
		)
		(pad "1" smd roundrect
			(at -0.48 0 90)
			(size 0.59 0.64)
			(layers "F.Cu" "F.Mask" "F.Paste")
			(roundrect_rratio 0.25)
			(net 1 "GND")
			(pintype "passive")
		)
		(pad "2" smd roundrect
			(at 0.48 0 90)
			(size 0.59 0.64)
			(layers "F.Cu" "F.Mask" "F.Paste")
			(roundrect_rratio 0.25)
			(net 707 "/USB PHY/FTDI_3V3")
			(pintype "passive")
		)
	)
	(footprint "antmicro-footprints:FB_0603_1608Metric"
		(layer "F.Cu")
		(at 256.845 135.035 180)
		(property "Reference" "FB6"
			(at 0.795 4.085 180)
			(layer "F.SilkS")
			(effects
				(font
					(size 0.7 0.7)
					(thickness 0.15)
				)
				(justify left bottom)
			)
		)
		(property "Value" "FB_600Z_0.5A_Murata-BLM18AG_0603"
			(at 0 1.7 180)
			(layer "F.Fab")
			(effects
				(font
					(size 0.7 0.7)
					(thickness 0.15)
				)
				(justify left bottom)
			)
		)
		(property "Description" "Ferrite Bead, 0603 [1608 Metric], 600 ohm, 500 mA, BLM18A, 0.38 ohm, ± 25%, General use"
			(at 0 0 180)
			(layer "F.Fab")
			(hide yes)
			(effects
				(font
					(size 1.27 1.27)
					(thickness 0.15)
				)
			)
		)
		(property "Author" "Antmicro"
			(at 513.69 270.07 0)
			(layer "F.Fab")
			(hide yes)
			(effects
				(font
					(size 1 1)
					(thickness 0.15)
				)
			)
		)
		(property "Current" ""
			(at 513.69 270.07 0)
			(layer "F.Fab")
			(hide yes)
			(effects
				(font
					(size 1 1)
					(thickness 0.15)
				)
			)
		)
		(property "License" "Apache-2.0"
			(at 513.69 270.07 0)
			(layer "F.Fab")
			(hide yes)
			(effects
				(font
					(size 1 1)
					(thickness 0.15)
				)
			)
		)
		(property "MPN" "BLM18AG601SN1D"
			(at 513.69 270.07 0)
			(layer "F.Fab")
			(hide yes)
			(effects
				(font
					(size 1 1)
					(thickness 0.15)
				)
			)
		)
		(property "Manufacturer" "Murata"
			(at 513.69 270.07 0)
			(layer "F.Fab")
			(hide yes)
			(effects
				(font
					(size 1 1)
					(thickness 0.15)
				)
			)
		)
		(property "Val" "600Z/0.5A"
			(at 513.69 270.07 0)
			(layer "F.Fab")
			(hide yes)
			(effects
				(font
					(size 1 1)
					(thickness 0.15)
				)
			)
		)
		(sheetname "USB PHY")
		(sheetfile "usb-phy.kicad_sch")
		(attr smd)
		(fp_line
			(start -0.15 0.4)
			(end 0.15 0.4)
			(stroke
				(width 0.15)
				(type solid)
			)
			(layer "F.SilkS")
		)
		(fp_line
			(start -0.15 -0.4)
			(end 0.15 -0.4)
			(stroke
				(width 0.15)
				(type solid)
			)
			(layer "F.SilkS")
		)
		(fp_rect
			(start -1.25 -0.65)
			(end 1.25 0.65)
			(stroke
				(width 0.05)
				(type solid)
			)
			(fill no)
			(layer "F.CrtYd")
		)
		(fp_line
			(start 0.8 0.406)
			(end -0.803 0.406)
			(stroke
				(width 0.15)
				(type solid)
			)
			(layer "F.Fab")
		)
		(fp_line
			(start 0.8 -0.408)
			(end 0.8 0.406)
			(stroke
				(width 0.15)
				(type solid)
			)
			(layer "F.Fab")
		)
		(fp_line
			(start 0.8 -0.408)
			(end -0.803 -0.408)
			(stroke
				(width 0.15)
				(type solid)
			)
			(layer "F.Fab")
		)
		(fp_line
			(start -0.803 0.406)
			(end -0.803 -0.408)
			(stroke
				(width 0.15)
				(type solid)
			)
			(layer "F.Fab")
		)
		(pad "1" smd roundrect
			(at -0.7 0 180)
			(size 0.8 1)
			(layers "F.Cu" "F.Mask" "F.Paste")
			(roundrect_rratio 0.2)
			(net 707 "/USB PHY/FTDI_3V3")
			(pintype "passive")
		)
		(pad "2" smd roundrect
			(at 0.7 0 180)
			(size 0.8 1)
			(layers "F.Cu" "F.Mask" "F.Paste")
			(roundrect_rratio 0.2)
			(net 711 "/USB PHY/FTDI_VPLL")
			(pintype "passive")
		)
	)
	(footprint "antmicro-footprints:C_0603_1608Metric"
		(layer "F.Cu")
		(at 157.95 164.05 180)
		(descr "Capacitor SMD 0603")
		(tags "capacitor 0603")
		(property "Reference" "C326"
			(at 1 -0.4 0)
			(layer "F.SilkS")
			(effects
				(font
					(size 0.7 0.7)
					(thickness 0.15)
				)
				(justify right bottom)
			)
		)
		(property "Value" "C_22u_0603"
			(at 0 1.6 0)
			(layer "F.Fab")
			(effects
				(font
					(size 0.7 0.7)
					(thickness 0.15)
				)
				(justify right bottom)
			)
		)
		(property "Description" "SMD Multilayer Ceramic Capacitor, 22 µF, 6.3 V, 0603 [1608 Metric], ± 20%, X5R, GRM Series"
			(at 0 0 180)
			(layer "F.Fab")
			(hide yes)
			(effects
				(font
					(size 1.27 1.27)
					(thickness 0.15)
				)
			)
		)
		(property "Author" "Antmicro"
			(at 315.9 328.1 0)
			(layer "F.Fab")
			(hide yes)
			(effects
				(font
					(size 1 1)
					(thickness 0.15)
				)
			)
		)
		(property "Dielectric" ""
			(at 315.9 328.1 0)
			(layer "F.Fab")
			(hide yes)
			(effects
				(font
					(size 1 1)
					(thickness 0.15)
				)
			)
		)
		(property "License" "Apache-2.0"
			(at 315.9 328.1 0)
			(layer "F.Fab")
			(hide yes)
			(effects
				(font
					(size 1 1)
					(thickness 0.15)
				)
			)
		)
		(property "MPN" "GRM188R60J226MEA0D"
			(at 315.9 328.1 0)
			(layer "F.Fab")
			(hide yes)
			(effects
				(font
					(size 1 1)
					(thickness 0.15)
				)
			)
		)
		(property "Manufacturer" "Murata"
			(at 315.9 328.1 0)
			(layer "F.Fab")
			(hide yes)
			(effects
				(font
					(size 1 1)
					(thickness 0.15)
				)
			)
		)
		(property "Val" "22u"
			(at 315.9 328.1 0)
			(layer "F.Fab")
			(hide yes)
			(effects
				(font
					(size 1 1)
					(thickness 0.15)
				)
			)
		)
		(property "Voltage" ""
			(at 315.9 328.1 0)
			(layer "F.Fab")
			(hide yes)
			(effects
				(font
					(size 1 1)
					(thickness 0.15)
				)
			)
		)
		(sheetname "DC-DC Converters")
		(sheetfile "dc-dc.kicad_sch")
		(attr smd)
		(fp_line
			(start -0.15 0.4)
			(end 0.15 0.4)
			(stroke
				(width 0.15)
				(type solid)
			)
			(layer "F.SilkS")
		)
		(fp_line
			(start -0.15 -0.4)
			(end 0.15 -0.4)
			(stroke
				(width 0.15)
				(type solid)
			)
			(layer "F.SilkS")
		)
		(fp_rect
			(start -1.25 -0.65)
			(end 1.25 0.65)
			(stroke
				(width 0.05)
				(type solid)
			)
			(fill no)
			(layer "F.CrtYd")
		)
		(fp_rect
			(start -0.8 -0.4)
			(end 0.8 0.4)
			(stroke
				(width 0.15)
				(type solid)
			)
			(fill no)
			(layer "F.Fab")
		)
		(pad "1" smd roundrect
			(at -0.7 0 180)
			(size 0.8 1)
			(layers "F.Cu" "F.Mask" "F.Paste")
			(roundrect_rratio 0.2)
			(net 1 "GND")
			(pintype "passive")
		)
		(pad "2" smd roundrect
			(at 0.7 0 180)
			(size 0.8 1)
			(layers "F.Cu" "F.Mask" "F.Paste")
			(roundrect_rratio 0.2)
			(net 733 "/DC-DC Converters/MGTAVCC_local")
			(pintype "passive")
		)
	)
	(footprint "antmicro-footprints:C_0402_1005Metric"
		(layer "F.Cu")
		(at 156.2 144.665 -90)
		(descr "Capacitor SMD 0402")
		(tags "capacitor SMD 0402")
		(property "Reference" "C352"
			(at 1.085 0.5 90)
			(layer "F.SilkS")
			(effects
				(font
					(size 0.7 0.7)
					(thickness 0.15)
				)
				(justify right bottom)
			)
		)
		(property "Value" "C_1u_0402"
			(at 0 1.4 90)
			(layer "F.Fab")
			(effects
				(font
					(size 0.7 0.7)
					(thickness 0.15)
				)
				(justify right bottom)
			)
		)
		(property "Description" "SMD Multilayer Ceramic Capacitor, 1 µF, 10 V, 0402 [1005 Metric], ± 10%, X6S, C"
			(at 0 0 270)
			(layer "F.Fab")
			(hide yes)
			(effects
				(font
					(size 1.27 1.27)
					(thickness 0.15)
				)
			)
		)
		(property "Author" "Antmicro"
			(at 11.535 300.865 0)
			(layer "F.Fab")
			(hide yes)
			(effects
				(font
					(size 1 1)
					(thickness 0.15)
				)
			)
		)
		(property "Dielectric" ""
			(at 11.535 300.865 0)
			(layer "F.Fab")
			(hide yes)
			(effects
				(font
					(size 1 1)
					(thickness 0.15)
				)
			)
		)
		(property "License" "Apache-2.0"
			(at 11.535 300.865 0)
			(layer "F.Fab")
			(hide yes)
			(effects
				(font
					(size 1 1)
					(thickness 0.15)
				)
			)
		)
		(property "MPN" "C1005X6S1A105K050BC"
			(at 11.535 300.865 0)
			(layer "F.Fab")
			(hide yes)
			(effects
				(font
					(size 1 1)
					(thickness 0.15)
				)
			)
		)
		(property "Manufacturer" "TDK"
			(at 11.535 300.865 0)
			(layer "F.Fab")
			(hide yes)
			(effects
				(font
					(size 1 1)
					(thickness 0.15)
				)
			)
		)
		(property "Val" "1u"
			(at 11.535 300.865 0)
			(layer "F.Fab")
			(hide yes)
			(effects
				(font
					(size 1 1)
					(thickness 0.15)
				)
			)
		)
		(property "Voltage" ""
			(at 11.535 300.865 0)
			(layer "F.Fab")
			(hide yes)
			(effects
				(font
					(size 1 1)
					(thickness 0.15)
				)
			)
		)
		(sheetname "DC-DC Converters")
		(sheetfile "dc-dc.kicad_sch")
		(attr smd)
		(fp_rect
			(start -0.925 -0.47)
			(end 0.925 0.47)
			(stroke
				(width 0.05)
				(type default)
			)
			(fill no)
			(layer "F.CrtYd")
		)
		(fp_line
			(start -0.494 0.248)
			(end -0.494 -0.25)
			(stroke
				(width 0.15)
				(type solid)
			)
			(layer "F.Fab")
		)
		(fp_line
			(start 0.504 0.248)
			(end -0.494 0.248)
			(stroke
				(width 0.15)
				(type solid)
			)
			(layer "F.Fab")
		)
		(fp_line
			(start -0.494 -0.25)
			(end 0.504 -0.25)
			(stroke
				(width 0.15)
				(type solid)
			)
			(layer "F.Fab")
		)
		(fp_line
			(start 0.504 -0.25)
			(end 0.504 0.248)
			(stroke
				(width 0.15)
				(type solid)
			)
			(layer "F.Fab")
		)
		(pad "1" smd roundrect
			(at -0.48 0 270)
			(size 0.59 0.64)
			(layers "F.Cu" "F.Mask" "F.Paste")
			(roundrect_rratio 0.25)
			(net 1 "GND")
			(pintype "passive")
		)
		(pad "2" smd roundrect
			(at 0.48 0 270)
			(size 0.59 0.64)
			(layers "F.Cu" "F.Mask" "F.Paste")
			(roundrect_rratio 0.25)
			(net 747 "/DC-DC Converters/1V85_OUT")
			(pintype "passive")
		)
	)
	(footprint "antmicro-footprints:C_0402_1005Metric"
		(layer "F.Cu")
		(at 173.570001 108.063751 180)
		(descr "Capacitor SMD 0402")
		(tags "capacitor SMD 0402")
		(property "Reference" "C300"
			(at -3.729999 -0.383749 0)
			(layer "F.SilkS")
			(effects
				(font
					(size 0.7 0.7)
					(thickness 0.15)
				)
				(justify right bottom)
			)
		)
		(property "Value" "C_100n_0402"
			(at 0 1.4 0)
			(layer "F.Fab")
			(effects
				(font
					(size 0.7 0.7)
					(thickness 0.15)
				)
				(justify right bottom)
			)
		)
		(property "Description" "SMD Multilayer Ceramic Capacitor, 0.1 µF, 50 V, 0402 [1005 Metric], ± 10%, X5R, GRM Series"
			(at 0 0 180)
			(layer "F.Fab")
			(hide yes)
			(effects
				(font
					(size 1.27 1.27)
					(thickness 0.15)
				)
			)
		)
		(property "Author" "Antmicro"
			(at 347.140002 216.127502 0)
			(layer "F.Fab")
			(hide yes)
			(effects
				(font
					(size 1 1)
					(thickness 0.15)
				)
			)
		)
		(property "Dielectric" "X5R"
			(at 347.140002 216.127502 0)
			(layer "F.Fab")
			(hide yes)
			(effects
				(font
					(size 1 1)
					(thickness 0.15)
				)
			)
		)
		(property "License" "Apache-2.0"
			(at 347.140002 216.127502 0)
			(layer "F.Fab")
			(hide yes)
			(effects
				(font
					(size 1 1)
					(thickness 0.15)
				)
			)
		)
		(property "MPN" "GRM155R61H104KE14D"
			(at 347.140002 216.127502 0)
			(layer "F.Fab")
			(hide yes)
			(effects
				(font
					(size 1 1)
					(thickness 0.15)
				)
			)
		)
		(property "Manufacturer" "Murata"
			(at 347.140002 216.127502 0)
			(layer "F.Fab")
			(hide yes)
			(effects
				(font
					(size 1 1)
					(thickness 0.15)
				)
			)
		)
		(property "Val" "100n"
			(at 347.140002 216.127502 0)
			(layer "F.Fab")
			(hide yes)
			(effects
				(font
					(size 1 1)
					(thickness 0.15)
				)
			)
		)
		(property "Voltage" "50V"
			(at 347.140002 216.127502 0)
			(layer "F.Fab")
			(hide yes)
			(effects
				(font
					(size 1 1)
					(thickness 0.15)
				)
			)
		)
		(sheetname "FMC+ HSPC")
		(sheetfile "fmc-hspc.kicad_sch")
		(attr smd)
		(fp_rect
			(start -0.925 -0.47)
			(end 0.925 0.47)
			(stroke
				(width 0.05)
				(type default)
			)
			(fill no)
			(layer "F.CrtYd")
		)
		(fp_line
			(start 0.504 0.248)
			(end -0.494 0.248)
			(stroke
				(width 0.15)
				(type solid)
			)
			(layer "F.Fab")
		)
		(fp_line
			(start 0.504 -0.25)
			(end 0.504 0.248)
			(stroke
				(width 0.15)
				(type solid)
			)
			(layer "F.Fab")
		)
		(fp_line
			(start -0.494 0.248)
			(end -0.494 -0.25)
			(stroke
				(width 0.15)
				(type solid)
			)
			(layer "F.Fab")
		)
		(fp_line
			(start -0.494 -0.25)
			(end 0.504 -0.25)
			(stroke
				(width 0.15)
				(type solid)
			)
			(layer "F.Fab")
		)
		(pad "1" smd roundrect
			(at -0.48 0 180)
			(size 0.59 0.64)
			(layers "F.Cu" "F.Mask" "F.Paste")
			(roundrect_rratio 0.25)
			(net 65 "/FMC+ HSPC/GTX116.TX2_P")
			(pintype "passive")
		)
		(pad "2" smd roundrect
			(at 0.48 0 180)
			(size 0.59 0.64)
			(layers "F.Cu" "F.Mask" "F.Paste")
			(roundrect_rratio 0.25)
			(net 64 "/FMC+ HSPC/GTX_TX1_C_P")
			(pintype "passive")
		)
	)
	(footprint "antmicro-footprints:R_0402_1005Metric"
		(layer "F.Cu")
		(at 238.65 141.7 90)
		(descr "Resistor SMD 0402")
		(tags "resistor SMD 0402")
		(property "Reference" "R180"
			(at -3.85 4.9 90)
			(layer "F.SilkS")
			(effects
				(font
					(size 0.7 0.7)
					(thickness 0.15)
				)
				(justify left bottom)
			)
		)
		(property "Value" "R_0R_0402"
			(at 0 1.4 90)
			(layer "F.Fab")
			(effects
				(font
					(size 0.7 0.7)
					(thickness 0.15)
				)
				(justify left bottom)
			)
		)
		(property "Description" "SMD Chip Resistor, Jumper, 0 ohm, 100 mW, 0402 [1005 Metric], Thick Film, General Purpose"
			(at 0 0 90)
			(layer "F.Fab")
			(hide yes)
			(effects
				(font
					(size 1.27 1.27)
					(thickness 0.15)
				)
			)
		)
		(property "Author" "Antmicro"
			(at 380.35 -96.95 0)
			(layer "F.Fab")
			(hide yes)
			(effects
				(font
					(size 1 1)
					(thickness 0.15)
				)
			)
		)
		(property "Current" "1A"
			(at 380.35 -96.95 0)
			(layer "F.Fab")
			(hide yes)
			(effects
				(font
					(size 1 1)
					(thickness 0.15)
				)
			)
		)
		(property "License" "Apache-2.0"
			(at 380.35 -96.95 0)
			(layer "F.Fab")
			(hide yes)
			(effects
				(font
					(size 1 1)
					(thickness 0.15)
				)
			)
		)
		(property "MPN" "ERJ2GE0R00X"
			(at 380.35 -96.95 0)
			(layer "F.Fab")
			(hide yes)
			(effects
				(font
					(size 1 1)
					(thickness 0.15)
				)
			)
		)
		(property "Manufacturer" "Panasonic"
			(at 380.35 -96.95 0)
			(layer "F.Fab")
			(hide yes)
			(effects
				(font
					(size 1 1)
					(thickness 0.15)
				)
			)
		)
		(property "Tolerance" ""
			(at 380.35 -96.95 0)
			(layer "F.Fab")
			(hide yes)
			(effects
				(font
					(size 1 1)
					(thickness 0.15)
				)
			)
		)
		(property "Val" "0R"
			(at 380.35 -96.95 0)
			(layer "F.Fab")
			(hide yes)
			(effects
				(font
					(size 1 1)
					(thickness 0.15)
				)
			)
		)
		(sheetname "USB PHY")
		(sheetfile "usb-phy.kicad_sch")
		(attr smd)
		(fp_rect
			(start -0.925 -0.47)
			(end 0.925 0.47)
			(stroke
				(width 0.05)
				(type default)
			)
			(fill no)
			(layer "F.CrtYd")
		)
		(fp_rect
			(start -0.5 -0.25)
			(end 0.5 0.25)
			(stroke
				(width 0.15)
				(type solid)
			)
			(fill no)
			(layer "F.Fab")
		)
		(pad "1" smd roundrect
			(at -0.48 0 90)
			(size 0.59 0.64)
			(layers "F.Cu" "F.Mask" "F.Paste")
			(roundrect_rratio 0.25)
			(net 372 "Net-(U23-OE)")
			(pintype "passive")
		)
		(pad "2" smd roundrect
			(at 0.48 0 90)
			(size 0.59 0.64)
			(layers "F.Cu" "F.Mask" "F.Paste")
			(roundrect_rratio 0.25)
			(net 878 "/USB PHY/~{BDBUS3}")
			(pintype "passive")
		)
	)
	(footprint "antmicro-footprints:R_0402_1005Metric"
		(layer "F.Cu")
		(at 256.13 184.26 90)
		(descr "Resistor SMD 0402")
		(tags "resistor SMD 0402")
		(property "Reference" "R46"
			(at 0.76 0.42 90)
			(layer "F.SilkS")
			(effects
				(font
					(size 0.7 0.7)
					(thickness 0.15)
				)
				(justify left bottom)
			)
		)
		(property "Value" "R_47k_0402"
			(at 0 1.4 90)
			(layer "F.Fab")
			(effects
				(font
					(size 0.7 0.7)
					(thickness 0.15)
				)
				(justify left bottom)
			)
		)
		(property "Description" "SMD Chip Resistor, 47 kohm, ± 1%, 62.5 mW, 0402 [1005 Metric], Thick Film, General Purpose"
			(at 0 0 90)
			(layer "F.Fab")
			(hide yes)
			(effects
				(font
					(size 1.27 1.27)
					(thickness 0.15)
				)
			)
		)
		(property "Author" "Antmicro"
			(at 440.39 -71.87 0)
			(layer "F.Fab")
			(hide yes)
			(effects
				(font
					(size 1 1)
					(thickness 0.15)
				)
			)
		)
		(property "License" "Apache-2.0"
			(at 440.39 -71.87 0)
			(layer "F.Fab")
			(hide yes)
			(effects
				(font
					(size 1 1)
					(thickness 0.15)
				)
			)
		)
		(property "MPN" "CR0402-FX-4702GLF"
			(at 440.39 -71.87 0)
			(layer "F.Fab")
			(hide yes)
			(effects
				(font
					(size 1 1)
					(thickness 0.15)
				)
			)
		)
		(property "Manufacturer" "Bourns"
			(at 440.39 -71.87 0)
			(layer "F.Fab")
			(hide yes)
			(effects
				(font
					(size 1 1)
					(thickness 0.15)
				)
			)
		)
		(property "Tolerance" "1%"
			(at 440.39 -71.87 0)
			(layer "F.Fab")
			(hide yes)
			(effects
				(font
					(size 1 1)
					(thickness 0.15)
				)
			)
		)
		(property "Val" "47k"
			(at 440.39 -71.87 0)
			(layer "F.Fab")
			(hide yes)
			(effects
				(font
					(size 1 1)
					(thickness 0.15)
				)
			)
		)
		(sheetname "Power supply")
		(sheetfile "power-supply.kicad_sch")
		(attr smd)
		(fp_rect
			(start -0.925 -0.47)
			(end 0.925 0.47)
			(stroke
				(width 0.05)
				(type default)
			)
			(fill no)
			(layer "F.CrtYd")
		)
		(fp_rect
			(start -0.5 -0.25)
			(end 0.5 0.25)
			(stroke
				(width 0.15)
				(type solid)
			)
			(fill no)
			(layer "F.Fab")
		)
		(pad "1" smd roundrect
			(at -0.48 0 90)
			(size 0.59 0.64)
			(layers "F.Cu" "F.Mask" "F.Paste")
			(roundrect_rratio 0.25)
			(net 18 "Net-(D9-A)")
			(pintype "passive")
		)
		(pad "2" smd roundrect
			(at 0.48 0 90)
			(size 0.59 0.64)
			(layers "F.Cu" "F.Mask" "F.Paste")
			(roundrect_rratio 0.25)
			(net 698 "/Power supply/VDD")
			(pintype "passive")
		)
	)
	(footprint "antmicro-footprints:X1QFN-16-1EP_2.5x2.5mm"
		(layer "F.Cu")
		(at 262.5 134.75 90)
		(property "Reference" "U18"
			(at 1.6 -0.6 0)
			(unlocked yes)
			(layer "F.SilkS")
			(effects
				(font
					(size 0.7 0.7)
					(thickness 0.15)
				)
				(justify left bottom)
			)
		)
		(property "Value" "SN74HC595B"
			(at -6.9 2.69 90)
			(unlocked yes)
			(layer "F.Fab")
			(effects
				(font
					(size 0.7 0.7)
					(thickness 0.15)
				)
				(justify left bottom)
			)
		)
		(property "Description" "Shift Register, 74HC595, Serial to Parallel, 1 Element, 8 bit, X1QFN, 16 Pins"
			(at 0 0 90)
			(layer "F.Fab")
			(hide yes)
			(effects
				(font
					(size 1.27 1.27)
					(thickness 0.15)
				)
			)
		)
		(property "Author" "Antmicro"
			(at 397.25 -127.75 0)
			(layer "F.Fab")
			(hide yes)
			(effects
				(font
					(size 1 1)
					(thickness 0.15)
				)
			)
		)
		(property "License" "Apache-2.0"
			(at 397.25 -127.75 0)
			(layer "F.Fab")
			(hide yes)
			(effects
				(font
					(size 1 1)
					(thickness 0.15)
				)
			)
		)
		(property "MPN" "SN74HC595BRWNR"
			(at 397.25 -127.75 0)
			(layer "F.Fab")
			(hide yes)
			(effects
				(font
					(size 1 1)
					(thickness 0.15)
				)
			)
		)
		(property "Manufacturer" "Texas Instruments"
			(at 397.25 -127.75 0)
			(layer "F.Fab")
			(hide yes)
			(effects
				(font
					(size 1 1)
					(thickness 0.15)
				)
			)
		)
		(sheetname "USB PHY")
		(sheetfile "usb-phy.kicad_sch")
		(attr smd)
		(fp_line
			(start 1.35 -1.351)
			(end 1.35 -0.803)
			(stroke
				(width 0.15)
				(type solid)
			)
			(layer "F.SilkS")
		)
		(fp_line
			(start 0.8 -1.351)
			(end 1.35 -1.351)
			(stroke
				(width 0.15)
				(type solid)
			)
			(layer "F.SilkS")
		)
		(fp_line
			(start -1.351 -1.351)
			(end -0.803 -1.351)
			(stroke
				(width 0.15)
				(type solid)
			)
			(layer "F.SilkS")
		)
		(fp_line
			(start 1.35 0.8)
			(end 1.35 1.35)
			(stroke
				(width 0.15)
				(type solid)
			)
			(layer "F.SilkS")
		)
		(fp_line
			(start 1.35 1.35)
			(end 0.8 1.35)
			(stroke
				(width 0.15)
				(type solid)
			)
			(layer "F.SilkS")
		)
		(fp_line
			(start -0.803 1.35)
			(end -1.351 1.35)
			(stroke
				(width 0.15)
				(type solid)
			)
			(layer "F.SilkS")
		)
		(fp_line
			(start -1.351 1.35)
			(end -1.351 0.8)
			(stroke
				(width 0.15)
				(type solid)
			)
			(layer "F.SilkS")
		)
		(fp_circle
			(center -1.752 -0.6)
			(end -1.702 -0.6)
			(stroke
				(width 0.15)
				(type solid)
			)
			(fill yes)
			(layer "F.SilkS")
		)
		(fp_rect
			(start -1.75 -1.75)
			(end 1.749 1.749)
			(stroke
				(width 0.05)
				(type solid)
			)
			(fill no)
			(layer "F.CrtYd")
		)
		(fp_line
			(start -1.25 -1.05)
			(end -1.05 -1.25)
			(stroke
				(width 0.15)
				(type solid)
			)
			(layer "F.Fab")
		)
		(fp_rect
			(start -1.25 -1.25)
			(end 1.249 1.249)
			(stroke
				(width 0.15)
				(type solid)
			)
			(fill no)
			(layer "F.Fab")
		)
		(pad "1" smd roundrect
			(at -1.151 -0.6 90)
			(size 0.6 0.2)
			(layers "F.Cu" "F.Mask" "F.Paste")
			(roundrect_rratio 0.25)
			(net 1160 "unconnected-(U18-QB-Pad1)")
			(pinfunction "QB")
			(pintype "output+no_connect")
		)
		(pad "2" smd roundrect
			(at -1.151 -0.203 90)
			(size 0.6 0.2)
			(layers "F.Cu" "F.Mask" "F.Paste")
			(roundrect_rratio 0.25)
			(net 1161 "unconnected-(U18-QC-Pad2)")
			(pinfunction "QC")
			(pintype "output+no_connect")
		)
		(pad "3" smd roundrect
			(at -1.151 0.2 90)
			(size 0.6 0.2)
			(layers "F.Cu" "F.Mask" "F.Paste")
			(roundrect_rratio 0.25)
			(net 1162 "unconnected-(U18-QD-Pad3)")
			(pinfunction "QD")
			(pintype "output+no_connect")
		)
		(pad "4" smd roundrect
			(at -1.151 0.597 90)
			(size 0.6 0.2)
			(layers "F.Cu" "F.Mask" "F.Paste")
			(roundrect_rratio 0.25)
			(net 912 "/USB PHY/LED_TX0")
			(pinfunction "QE")
			(pintype "output")
		)
		(pad "5" smd roundrect
			(at -0.6 1.148 180)
			(size 0.6 0.2)
			(layers "F.Cu" "F.Mask" "F.Paste")
			(roundrect_rratio 0.25)
			(net 913 "/USB PHY/LED_RX0")
			(pinfunction "QF")
			(pintype "output")
		)
		(pad "6" smd roundrect
			(at -0.203 1.148 180)
			(size 0.6 0.2)
			(layers "F.Cu" "F.Mask" "F.Paste")
			(roundrect_rratio 0.25)
			(net 914 "/USB PHY/LED_TX1")
			(pinfunction "QG")
			(pintype "output")
		)
		(pad "7" smd roundrect
			(at 0.2 1.148 180)
			(size 0.6 0.2)
			(layers "F.Cu" "F.Mask" "F.Paste")
			(roundrect_rratio 0.25)
			(net 915 "/USB PHY/LED_RX1")
			(pinfunction "QH")
			(pintype "output")
		)
		(pad "8" smd roundrect
			(at 0.597 1.148 180)
			(size 0.6 0.2)
			(layers "F.Cu" "F.Mask" "F.Paste")
			(roundrect_rratio 0.25)
			(net 1 "GND")
			(pinfunction "GND")
			(pintype "power_in")
		)
		(pad "9" smd roundrect
			(at 1.148 0.597 90)
			(size 0.6 0.2)
			(layers "F.Cu" "F.Mask" "F.Paste")
			(roundrect_rratio 0.25)
			(net 1163 "unconnected-(U18-QH'-Pad9)")
			(pinfunction "QH'")
			(pintype "output+no_connect")
		)
		(pad "10" smd roundrect
			(at 1.148 0.2 90)
			(size 0.6 0.2)
			(layers "F.Cu" "F.Mask" "F.Paste")
			(roundrect_rratio 0.25)
			(net 707 "/USB PHY/FTDI_3V3")
			(pinfunction "~{SRCLR}")
			(pintype "input")
		)
		(pad "11" smd roundrect
			(at 1.148 -0.203 90)
			(size 0.6 0.2)
			(layers "F.Cu" "F.Mask" "F.Paste")
			(roundrect_rratio 0.25)
			(net 996 "/USB PHY/FTDI_EECLK")
			(pinfunction "SRCLK")
			(pintype "input")
		)
		(pad "12" smd roundrect
			(at 1.148 -0.6 90)
			(size 0.6 0.2)
			(layers "F.Cu" "F.Mask" "F.Paste")
			(roundrect_rratio 0.25)
			(net 997 "/USB PHY/FTDI_EECS")
			(pinfunction "RCLK")
			(pintype "input")
		)
		(pad "13" smd roundrect
			(at 0.597 -1.151 180)
			(size 0.6 0.2)
			(layers "F.Cu" "F.Mask" "F.Paste")
			(roundrect_rratio 0.25)
			(net 918 "/USB PHY/FTDI_PWREN")
			(pinfunction "~{OE}")
			(pintype "input")
		)
		(pad "14" smd roundrect
			(at 0.2 -1.151 180)
			(size 0.6 0.2)
			(layers "F.Cu" "F.Mask" "F.Paste")
			(roundrect_rratio 0.25)
			(net 998 "/USB PHY/FTDI_EEDAT")
			(pinfunction "SER")
			(pintype "input")
		)
		(pad "15" smd roundrect
			(at -0.203 -1.151 180)
			(size 0.6 0.2)
			(layers "F.Cu" "F.Mask" "F.Paste")
			(roundrect_rratio 0.25)
			(net 1164 "unconnected-(U18-QA-Pad15)")
			(pinfunction "QA")
			(pintype "output+no_connect")
		)
		(pad "16" smd roundrect
			(at -0.6 -1.151 180)
			(size 0.6 0.2)
			(layers "F.Cu" "F.Mask" "F.Paste")
			(roundrect_rratio 0.25)
			(net 707 "/USB PHY/FTDI_3V3")
			(pinfunction "VCC")
			(pintype "power_in")
		)
		(pad "17" smd roundrect
			(at 0 0 180)
			(size 1.2 1.2)
			(layers "F.Cu" "F.Mask" "F.Paste")
			(roundrect_rratio 0.04166666667)
			(net 1165 "unconnected-(U18-EP-Pad17)")
			(pinfunction "EP")
			(pintype "no_connect")
		)
	)
	(footprint "antmicro-footprints:R_0402_1005Metric"
		(layer "F.Cu")
		(at 235.9 111.625 180)
		(descr "Resistor SMD 0402")
		(tags "resistor SMD 0402")
		(property "Reference" "R104"
			(at -0.8 -0.375 180)
			(layer "F.SilkS")
			(effects
				(font
					(size 0.7 0.7)
					(thickness 0.15)
				)
				(justify left bottom)
			)
		)
		(property "Value" "R_0R_0402"
			(at 0 1.4 180)
			(layer "F.Fab")
			(effects
				(font
					(size 0.7 0.7)
					(thickness 0.15)
				)
				(justify left bottom)
			)
		)
		(property "Description" "SMD Chip Resistor, Jumper, 0 ohm, 100 mW, 0402 [1005 Metric], Thick Film, General Purpose"
			(at 0 0 180)
			(layer "F.Fab")
			(hide yes)
			(effects
				(font
					(size 1.27 1.27)
					(thickness 0.15)
				)
			)
		)
		(property "Author" "Antmicro"
			(at 471.8 223.25 0)
			(layer "F.Fab")
			(hide yes)
			(effects
				(font
					(size 1 1)
					(thickness 0.15)
				)
			)
		)
		(property "Current" "1A"
			(at 471.8 223.25 0)
			(layer "F.Fab")
			(hide yes)
			(effects
				(font
					(size 1 1)
					(thickness 0.15)
				)
			)
		)
		(property "License" "Apache-2.0"
			(at 471.8 223.25 0)
			(layer "F.Fab")
			(hide yes)
			(effects
				(font
					(size 1 1)
					(thickness 0.15)
				)
			)
		)
		(property "MPN" "ERJ2GE0R00X"
			(at 471.8 223.25 0)
			(layer "F.Fab")
			(hide yes)
			(effects
				(font
					(size 1 1)
					(thickness 0.15)
				)
			)
		)
		(property "Manufacturer" "Panasonic"
			(at 471.8 223.25 0)
			(layer "F.Fab")
			(hide yes)
			(effects
				(font
					(size 1 1)
					(thickness 0.15)
				)
			)
		)
		(property "Tolerance" ""
			(at 471.8 223.25 0)
			(layer "F.Fab")
			(hide yes)
			(effects
				(font
					(size 1 1)
					(thickness 0.15)
				)
			)
		)
		(property "Val" "0R"
			(at 471.8 223.25 0)
			(layer "F.Fab")
			(hide yes)
			(effects
				(font
					(size 1 1)
					(thickness 0.15)
				)
			)
		)
		(sheetname "SPI Flash + SD Card")
		(sheetfile "spi-flash.kicad_sch")
		(attr smd)
		(fp_rect
			(start -0.925 -0.47)
			(end 0.925 0.47)
			(stroke
				(width 0.05)
				(type default)
			)
			(fill no)
			(layer "F.CrtYd")
		)
		(fp_rect
			(start -0.5 -0.25)
			(end 0.5 0.25)
			(stroke
				(width 0.15)
				(type solid)
			)
			(fill no)
			(layer "F.Fab")
		)
		(pad "1" smd roundrect
			(at -0.48 0 180)
			(size 0.59 0.64)
			(layers "F.Cu" "F.Mask" "F.Paste")
			(roundrect_rratio 0.25)
			(net 417 "/FPGA Bank 16 & 17/USR_FLASH_1.DQ3")
			(pintype "passive")
		)
		(pad "2" smd roundrect
			(at 0.48 0 180)
			(size 0.59 0.64)
			(layers "F.Cu" "F.Mask" "F.Paste")
			(roundrect_rratio 0.25)
			(net 911 "/SPI Flash + SD Card/USR_FLASH_1_DQ3")
			(pintype "passive")
		)
	)
	(footprint "antmicro-footprints:C_0402_1005Metric"
		(layer "F.Cu")
		(at 162.2 149.6 90)
		(descr "Capacitor SMD 0402")
		(tags "capacitor SMD 0402")
		(property "Reference" "C177"
			(at -1.5 1.25 90)
			(layer "F.SilkS")
			(effects
				(font
					(size 0.7 0.7)
					(thickness 0.15)
				)
				(justify left bottom)
			)
		)
		(property "Value" "C_100n_0402"
			(at 0 1.169 90)
			(layer "F.Fab")
			(effects
				(font
					(size 0.7 0.7)
					(thickness 0.15)
				)
				(justify left bottom)
			)
		)
		(property "Description" "SMD Multilayer Ceramic Capacitor, 0.1 µF, 50 V, 0402 [1005 Metric], ± 10%, X5R, GRM Series"
			(at 0 0 90)
			(layer "F.Fab")
			(hide yes)
			(effects
				(font
					(size 1.27 1.27)
					(thickness 0.15)
				)
			)
		)
		(property "Author" "Antmicro"
			(at 311.8 -12.6 0)
			(layer "F.Fab")
			(hide yes)
			(effects
				(font
					(size 1 1)
					(thickness 0.15)
				)
			)
		)
		(property "Dielectric" "X5R"
			(at 311.8 -12.6 0)
			(layer "F.Fab")
			(hide yes)
			(effects
				(font
					(size 1 1)
					(thickness 0.15)
				)
			)
		)
		(property "License" "Apache-2.0"
			(at 311.8 -12.6 0)
			(layer "F.Fab")
			(hide yes)
			(effects
				(font
					(size 1 1)
					(thickness 0.15)
				)
			)
		)
		(property "MPN" "GRM155R61H104KE14D"
			(at 311.8 -12.6 0)
			(layer "F.Fab")
			(hide yes)
			(effects
				(font
					(size 1 1)
					(thickness 0.15)
				)
			)
		)
		(property "Manufacturer" "Murata"
			(at 311.8 -12.6 0)
			(layer "F.Fab")
			(hide yes)
			(effects
				(font
					(size 1 1)
					(thickness 0.15)
				)
			)
		)
		(property "Val" "100n"
			(at 311.8 -12.6 0)
			(layer "F.Fab")
			(hide yes)
			(effects
				(font
					(size 1 1)
					(thickness 0.15)
				)
			)
		)
		(property "Voltage" "50V"
			(at 311.8 -12.6 0)
			(layer "F.Fab")
			(hide yes)
			(effects
				(font
					(size 1 1)
					(thickness 0.15)
				)
			)
		)
		(sheetname "DRAM + SRAM")
		(sheetfile "ram.kicad_sch")
		(attr smd)
		(fp_rect
			(start -0.925 -0.47)
			(end 0.925 0.47)
			(stroke
				(width 0.05)
				(type default)
			)
			(fill no)
			(layer "F.CrtYd")
		)
		(fp_line
			(start 0.504 -0.25)
			(end 0.504 0.248)
			(stroke
				(width 0.15)
				(type solid)
			)
			(layer "F.Fab")
		)
		(fp_line
			(start -0.494 -0.25)
			(end 0.504 -0.25)
			(stroke
				(width 0.15)
				(type solid)
			)
			(layer "F.Fab")
		)
		(fp_line
			(start 0.504 0.248)
			(end -0.494 0.248)
			(stroke
				(width 0.15)
				(type solid)
			)
			(layer "F.Fab")
		)
		(fp_line
			(start -0.494 0.248)
			(end -0.494 -0.25)
			(stroke
				(width 0.15)
				(type solid)
			)
			(layer "F.Fab")
		)
		(pad "1" smd roundrect
			(at -0.48 0 90)
			(size 0.59 0.64)
			(layers "F.Cu" "F.Mask" "F.Paste")
			(roundrect_rratio 0.25)
			(net 1 "GND")
			(pintype "passive")
		)
		(pad "2" smd roundrect
			(at 0.48 0 90)
			(size 0.59 0.64)
			(layers "F.Cu" "F.Mask" "F.Paste")
			(roundrect_rratio 0.25)
			(net 25 "+1V35")
			(pintype "passive")
		)
	)
	(footprint "antmicro-footprints:R_0402_1005Metric"
		(layer "F.Cu")
		(at 173.570001 85.210001)
		(descr "Resistor SMD 0402")
		(tags "resistor SMD 0402")
		(property "Reference" "R270"
			(at 0.929999 0.342499 0)
			(layer "F.SilkS")
			(effects
				(font
					(size 0.7 0.7)
					(thickness 0.15)
				)
				(justify left bottom)
			)
		)
		(property "Value" "R_33R_0402"
			(at 0 1.4 0)
			(layer "F.Fab")
			(effects
				(font
					(size 0.7 0.7)
					(thickness 0.15)
				)
				(justify left bottom)
			)
		)
		(property "Description" "SMD Chip Resistor, 33 ohm, ± 1%, 62.5 mW, 0402 [1005 Metric], Thick Film, General Purpose"
			(at 0 0 0)
			(layer "F.Fab")
			(hide yes)
			(effects
				(font
					(size 1.27 1.27)
					(thickness 0.15)
				)
			)
		)
		(property "Author" "Antmicro"
			(at 0 0 0)
			(layer "F.Fab")
			(hide yes)
			(effects
				(font
					(size 1 1)
					(thickness 0.15)
				)
			)
		)
		(property "License" "Apache-2.0"
			(at 0 0 0)
			(layer "F.Fab")
			(hide yes)
			(effects
				(font
					(size 1 1)
					(thickness 0.15)
				)
			)
		)
		(property "MPN" "CR0402-FX-33R0GLF"
			(at 0 0 0)
			(layer "F.Fab")
			(hide yes)
			(effects
				(font
					(size 1 1)
					(thickness 0.15)
				)
			)
		)
		(property "Manufacturer" "Bourns"
			(at 0 0 0)
			(layer "F.Fab")
			(hide yes)
			(effects
				(font
					(size 1 1)
					(thickness 0.15)
				)
			)
		)
		(property "Tolerance" "1%"
			(at 0 0 0)
			(layer "F.Fab")
			(hide yes)
			(effects
				(font
					(size 1 1)
					(thickness 0.15)
				)
			)
		)
		(property "Val" "33R"
			(at 0 0 0)
			(layer "F.Fab")
			(hide yes)
			(effects
				(font
					(size 1 1)
					(thickness 0.15)
				)
			)
		)
		(sheetname "FMC+ HSPC")
		(sheetfile "fmc-hspc.kicad_sch")
		(attr smd)
		(fp_rect
			(start -0.925 -0.47)
			(end 0.925 0.47)
			(stroke
				(width 0.05)
				(type default)
			)
			(fill no)
			(layer "F.CrtYd")
		)
		(fp_rect
			(start -0.5 -0.25)
			(end 0.5 0.25)
			(stroke
				(width 0.15)
				(type solid)
			)
			(fill no)
			(layer "F.Fab")
		)
		(pad "1" smd roundrect
			(at -0.48 0)
			(size 0.59 0.64)
			(layers "F.Cu" "F.Mask" "F.Paste")
			(roundrect_rratio 0.25)
			(net 629 "/FMC+ HSPC/GTR_REFCLK0_R_N")
			(pintype "passive")
		)
		(pad "2" smd roundrect
			(at 0.48 0)
			(size 0.59 0.64)
			(layers "F.Cu" "F.Mask" "F.Paste")
			(roundrect_rratio 0.25)
			(net 630 "/FMC+ HSPC/GTX115.REFCLK0_N")
			(pintype "passive")
		)
	)
	(footprint "antmicro-footprints:C_0402_1005Metric"
		(layer "F.Cu")
		(at 221.5 145.7)
		(descr "Capacitor SMD 0402")
		(tags "capacitor SMD 0402")
		(property "Reference" "C253"
			(at 0.75 0.4 0)
			(layer "F.SilkS")
			(effects
				(font
					(size 0.7 0.7)
					(thickness 0.15)
				)
				(justify left bottom)
			)
		)
		(property "Value" "C_10u_0402"
			(at 0 1.4 0)
			(layer "F.Fab")
			(effects
				(font
					(size 0.7 0.7)
					(thickness 0.15)
				)
				(justify left bottom)
			)
		)
		(property "Description" "SMD Multilayer Ceramic Capacitor, 10 µF, 6.3 V, 0402 [1005 Metric], ± 20%, X5R, CC Series"
			(at 0 0 0)
			(layer "F.Fab")
			(hide yes)
			(effects
				(font
					(size 1.27 1.27)
					(thickness 0.15)
				)
			)
		)
		(property "Author" "Antmicro"
			(at 0 0 0)
			(layer "F.Fab")
			(hide yes)
			(effects
				(font
					(size 1 1)
					(thickness 0.15)
				)
			)
		)
		(property "Dielectric" ""
			(at 0 0 0)
			(layer "F.Fab")
			(hide yes)
			(effects
				(font
					(size 1 1)
					(thickness 0.15)
				)
			)
		)
		(property "License" "Apache-2.0"
			(at 0 0 0)
			(layer "F.Fab")
			(hide yes)
			(effects
				(font
					(size 1 1)
					(thickness 0.15)
				)
			)
		)
		(property "MPN" "CC0402MRX5R5BB106"
			(at 0 0 0)
			(layer "F.Fab")
			(hide yes)
			(effects
				(font
					(size 1 1)
					(thickness 0.15)
				)
			)
		)
		(property "Manufacturer" "YAGEO"
			(at 0 0 0)
			(layer "F.Fab")
			(hide yes)
			(effects
				(font
					(size 1 1)
					(thickness 0.15)
				)
			)
		)
		(property "Val" "10u"
			(at 0 0 0)
			(layer "F.Fab")
			(hide yes)
			(effects
				(font
					(size 1 1)
					(thickness 0.15)
				)
			)
		)
		(property "Voltage" ""
			(at 0 0 0)
			(layer "F.Fab")
			(hide yes)
			(effects
				(font
					(size 1 1)
					(thickness 0.15)
				)
			)
		)
		(sheetname "HDMI + Ethernet")
		(sheetfile "hdmi-ethernet.kicad_sch")
		(attr smd)
		(fp_rect
			(start -0.925 -0.47)
			(end 0.925 0.47)
			(stroke
				(width 0.05)
				(type default)
			)
			(fill no)
			(layer "F.CrtYd")
		)
		(fp_line
			(start -0.494 -0.25)
			(end 0.504 -0.25)
			(stroke
				(width 0.15)
				(type solid)
			)
			(layer "F.Fab")
		)
		(fp_line
			(start -0.494 0.248)
			(end -0.494 -0.25)
			(stroke
				(width 0.15)
				(type solid)
			)
			(layer "F.Fab")
		)
		(fp_line
			(start 0.504 -0.25)
			(end 0.504 0.248)
			(stroke
				(width 0.15)
				(type solid)
			)
			(layer "F.Fab")
		)
		(fp_line
			(start 0.504 0.248)
			(end -0.494 0.248)
			(stroke
				(width 0.15)
				(type solid)
			)
			(layer "F.Fab")
		)
		(pad "1" smd roundrect
			(at -0.48 0)
			(size 0.59 0.64)
			(layers "F.Cu" "F.Mask" "F.Paste")
			(roundrect_rratio 0.25)
			(net 1 "GND")
			(pintype "passive")
		)
		(pad "2" smd roundrect
			(at 0.48 0)
			(size 0.59 0.64)
			(layers "F.Cu" "F.Mask" "F.Paste")
			(roundrect_rratio 0.25)
			(net 26 "+1V8")
			(pintype "passive")
		)
	)
	(footprint "antmicro-footprints:C_0402_1005Metric"
		(layer "F.Cu")
		(at 201.6625 88.3365 -90)
		(descr "Capacitor SMD 0402")
		(tags "capacitor SMD 0402")
		(property "Reference" "C281"
			(at -0.8865 -0.3875 270)
			(layer "F.SilkS")
			(effects
				(font
					(size 0.7 0.7)
					(thickness 0.15)
				)
				(justify left bottom)
			)
		)
		(property "Value" "C_100n_0402"
			(at 0 1.169 270)
			(layer "F.Fab")
			(effects
				(font
					(size 0.7 0.7)
					(thickness 0.15)
				)
				(justify left bottom)
			)
		)
		(property "Description" "SMD Multilayer Ceramic Capacitor, 0.1 µF, 50 V, 0402 [1005 Metric], ± 10%, X5R, GRM Series"
			(at 0 0 270)
			(layer "F.Fab")
			(hide yes)
			(effects
				(font
					(size 1.27 1.27)
					(thickness 0.15)
				)
			)
		)
		(property "Author" "Antmicro"
			(at 113.326 289.999 0)
			(layer "F.Fab")
			(hide yes)
			(effects
				(font
					(size 1 1)
					(thickness 0.15)
				)
			)
		)
		(property "Dielectric" "X5R"
			(at 113.326 289.999 0)
			(layer "F.Fab")
			(hide yes)
			(effects
				(font
					(size 1 1)
					(thickness 0.15)
				)
			)
		)
		(property "License" "Apache-2.0"
			(at 113.326 289.999 0)
			(layer "F.Fab")
			(hide yes)
			(effects
				(font
					(size 1 1)
					(thickness 0.15)
				)
			)
		)
		(property "MPN" "GRM155R61H104KE14D"
			(at 113.326 289.999 0)
			(layer "F.Fab")
			(hide yes)
			(effects
				(font
					(size 1 1)
					(thickness 0.15)
				)
			)
		)
		(property "Manufacturer" "Murata"
			(at 113.326 289.999 0)
			(layer "F.Fab")
			(hide yes)
			(effects
				(font
					(size 1 1)
					(thickness 0.15)
				)
			)
		)
		(property "Val" "100n"
			(at 113.326 289.999 0)
			(layer "F.Fab")
			(hide yes)
			(effects
				(font
					(size 1 1)
					(thickness 0.15)
				)
			)
		)
		(property "Voltage" "50V"
			(at 113.326 289.999 0)
			(layer "F.Fab")
			(hide yes)
			(effects
				(font
					(size 1 1)
					(thickness 0.15)
				)
			)
		)
		(sheetname "HDMI + Ethernet")
		(sheetfile "hdmi-ethernet.kicad_sch")
		(attr smd)
		(fp_rect
			(start -0.925 -0.47)
			(end 0.925 0.47)
			(stroke
				(width 0.05)
				(type default)
			)
			(fill no)
			(layer "F.CrtYd")
		)
		(fp_line
			(start -0.494 0.248)
			(end -0.494 -0.25)
			(stroke
				(width 0.15)
				(type solid)
			)
			(layer "F.Fab")
		)
		(fp_line
			(start 0.504 0.248)
			(end -0.494 0.248)
			(stroke
				(width 0.15)
				(type solid)
			)
			(layer "F.Fab")
		)
		(fp_line
			(start -0.494 -0.25)
			(end 0.504 -0.25)
			(stroke
				(width 0.15)
				(type solid)
			)
			(layer "F.Fab")
		)
		(fp_line
			(start 0.504 -0.25)
			(end 0.504 0.248)
			(stroke
				(width 0.15)
				(type solid)
			)
			(layer "F.Fab")
		)
		(pad "1" smd roundrect
			(at -0.48 0 270)
			(size 0.59 0.64)
			(layers "F.Cu" "F.Mask" "F.Paste")
			(roundrect_rratio 0.25)
			(net 1 "GND")
			(pintype "passive")
		)
		(pad "2" smd roundrect
			(at 0.48 0 270)
			(size 0.59 0.64)
			(layers "F.Cu" "F.Mask" "F.Paste")
			(roundrect_rratio 0.25)
			(net 727 "+1V2")
			(pintype "passive")
		)
	)
	(footprint "antmicro-footprints:SC70-3"
		(layer "F.Cu")
		(at 258.4 91)
		(property "Reference" "Q11"
			(at -1.6 1.1 90)
			(layer "F.SilkS")
			(effects
				(font
					(size 0.7 0.7)
					(thickness 0.15)
				)
				(justify left bottom)
			)
		)
		(property "Value" "BSS138PW"
			(at 0 2.3 0)
			(layer "F.Fab")
			(effects
				(font
					(size 0.7 0.7)
					(thickness 0.15)
				)
				(justify left bottom)
			)
		)
		(property "Description" "Power MOSFET, N Channel, 60 V, 320 mA, 0.9 ohm, SOT-323, Surface Mount"
			(at 0 0 0)
			(layer "F.Fab")
			(hide yes)
			(effects
				(font
					(size 1.27 1.27)
					(thickness 0.15)
				)
			)
		)
		(property "Author" "Antmicro"
			(at 0 0 0)
			(layer "F.Fab")
			(hide yes)
			(effects
				(font
					(size 1 1)
					(thickness 0.15)
				)
			)
		)
		(property "License" "Apache-2.0"
			(at 0 0 0)
			(layer "F.Fab")
			(hide yes)
			(effects
				(font
					(size 1 1)
					(thickness 0.15)
				)
			)
		)
		(property "MPN" "BSS138PW"
			(at 0 0 0)
			(layer "F.Fab")
			(hide yes)
			(effects
				(font
					(size 1 1)
					(thickness 0.15)
				)
			)
		)
		(property "Manufacturer" "Nexperia"
			(at 0 0 0)
			(layer "F.Fab")
			(hide yes)
			(effects
				(font
					(size 1 1)
					(thickness 0.15)
				)
			)
		)
		(sheetname "User GPIO + LED + button + DIP switch")
		(sheetfile "user-gpio.kicad_sch")
		(attr smd)
		(fp_line
			(start -0.3 -1)
			(end 0.627 -0.999)
			(stroke
				(width 0.15)
				(type solid)
			)
			(layer "F.SilkS")
		)
		(fp_line
			(start -0.3 1)
			(end 0.627 1.001)
			(stroke
				(width 0.15)
				(type solid)
			)
			(layer "F.SilkS")
		)
		(fp_line
			(start 0.627 -0.6)
			(end 0.627 -0.999)
			(stroke
				(width 0.15)
				(type solid)
			)
			(layer "F.SilkS")
		)
		(fp_line
			(start 0.627 0.6)
			(end 0.627 1.001)
			(stroke
				(width 0.15)
				(type solid)
			)
			(layer "F.SilkS")
		)
		(fp_line
			(start -1.4 1)
			(end -1.4 -1)
			(stroke
				(width 0.05)
				(type solid)
			)
			(layer "F.CrtYd")
		)
		(fp_line
			(start -0.9 -1.3)
			(end -0.9 -1)
			(stroke
				(width 0.05)
				(type solid)
			)
			(layer "F.CrtYd")
		)
		(fp_line
			(start -0.9 -1.3)
			(end 0.9 -1.3)
			(stroke
				(width 0.05)
				(type solid)
			)
			(layer "F.CrtYd")
		)
		(fp_line
			(start -0.9 -1)
			(end -1.4 -1)
			(stroke
				(width 0.05)
				(type solid)
			)
			(layer "F.CrtYd")
		)
		(fp_line
			(start -0.9 1)
			(end -1.4 1)
			(stroke
				(width 0.05)
				(type solid)
			)
			(layer "F.CrtYd")
		)
		(fp_line
			(start -0.9 1.3)
			(end -0.9 1)
			(stroke
				(width 0.05)
				(type solid)
			)
			(layer "F.CrtYd")
		)
		(fp_line
			(start 0.9 -1.3)
			(end 0.9 -0.4)
			(stroke
				(width 0.05)
				(type solid)
			)
			(layer "F.CrtYd")
		)
		(fp_line
			(start 0.9 -0.4)
			(end 1.4 -0.4)
			(stroke
				(width 0.05)
				(type solid)
			)
			(layer "F.CrtYd")
		)
		(fp_line
			(start 0.9 0.4)
			(end 0.9 1.3)
			(stroke
				(width 0.05)
				(type solid)
			)
			(layer "F.CrtYd")
		)
		(fp_line
			(start 0.9 1.3)
			(end -0.9 1.3)
			(stroke
				(width 0.05)
				(type solid)
			)
			(layer "F.CrtYd")
		)
		(fp_line
			(start 1.4 -0.4)
			(end 1.4 0.4)
			(stroke
				(width 0.05)
				(type solid)
			)
			(layer "F.CrtYd")
		)
		(fp_line
			(start 1.4 0.4)
			(end 0.9 0.4)
			(stroke
				(width 0.05)
				(type solid)
			)
			(layer "F.CrtYd")
		)
		(fp_rect
			(start -0.623 -0.999)
			(end 0.627 1.001)
			(stroke
				(width 0.15)
				(type solid)
			)
			(fill no)
			(layer "F.Fab")
		)
		(pad "1" smd rect
			(at -1.051 -0.65 90)
			(size 0.6 0.6)
			(layers "F.Cu" "F.Mask" "F.Paste")
			(net 1302 "/USER_IO.LED_GREEN3")
			(pinfunction "G")
			(pintype "passive")
		)
		(pad "2" smd rect
			(at -1.051 0.65 90)
			(size 0.6 0.6)
			(layers "F.Cu" "F.Mask" "F.Paste")
			(net 1 "GND")
			(pinfunction "S")
			(pintype "passive")
		)
		(pad "3" smd rect
			(at 1.05 0 90)
			(size 0.6 0.6)
			(layers "F.Cu" "F.Mask" "F.Paste")
			(net 23 "Net-(D21-C)")
			(pinfunction "D")
			(pintype "passive")
		)
	)
	(footprint "antmicro-footprints:QFN-2L_1.6x1x0.55mm"
		(layer "F.Cu")
		(at 232 159.8 180)
		(property "Reference" "D8"
			(at 1.05 -0.35 0)
			(layer "F.SilkS")
			(effects
				(font
					(size 0.7 0.7)
					(thickness 0.15)
				)
				(justify right bottom)
			)
		)
		(property "Value" "ESDA25P35-1U1M"
			(at 0 1.7 0)
			(layer "F.Fab")
			(effects
				(font
					(size 0.7 0.7)
					(thickness 0.15)
				)
				(justify right bottom)
			)
		)
		(property "Description" "Unidirectional TVS, 30 kV, QFN-2L, 22 V, 195 pF"
			(at 0 0 180)
			(layer "F.Fab")
			(hide yes)
			(effects
				(font
					(size 1.27 1.27)
					(thickness 0.15)
				)
			)
		)
		(property "Author" "Antmicro"
			(at 464 319.6 0)
			(layer "F.Fab")
			(hide yes)
			(effects
				(font
					(size 1 1)
					(thickness 0.15)
				)
			)
		)
		(property "License" "Apache-2.0"
			(at 464 319.6 0)
			(layer "F.Fab")
			(hide yes)
			(effects
				(font
					(size 1 1)
					(thickness 0.15)
				)
			)
		)
		(property "MPN" "ESDA25P35-1U1M"
			(at 464 319.6 0)
			(layer "F.Fab")
			(hide yes)
			(effects
				(font
					(size 1 1)
					(thickness 0.15)
				)
			)
		)
		(property "Manufacturer" "STMicroelectronics"
			(at 464 319.6 0)
			(layer "F.Fab")
			(hide yes)
			(effects
				(font
					(size 1 1)
					(thickness 0.15)
				)
			)
		)
		(property "Public" "False"
			(at 464 319.6 0)
			(layer "F.Fab")
			(hide yes)
			(effects
				(font
					(size 1 1)
					(thickness 0.15)
				)
			)
		)
		(sheetname "Power supply")
		(sheetfile "power-supply.kicad_sch")
		(attr smd)
		(fp_line
			(start 0.27 0.3)
			(end -0.27 0.3)
			(stroke
				(width 0.15)
				(type solid)
			)
			(layer "F.SilkS")
		)
		(fp_line
			(start 0.27 -0.3)
			(end -0.27 -0.3)
			(stroke
				(width 0.15)
				(type solid)
			)
			(layer "F.SilkS")
		)
		(fp_line
			(start -1.2 -0.4)
			(end -1.2 0.4)
			(stroke
				(width 0.15)
				(type solid)
			)
			(layer "F.SilkS")
		)
		(fp_rect
			(start 1.25 0.65)
			(end -1.25 -0.65)
			(stroke
				(width 0.05)
				(type solid)
			)
			(fill no)
			(layer "F.CrtYd")
		)
		(fp_line
			(start 0.599 0)
			(end 0.201 0)
			(stroke
				(width 0.15)
				(type solid)
			)
			(layer "F.Fab")
		)
		(fp_line
			(start 0.201 0.2)
			(end 0.201 0)
			(stroke
				(width 0.15)
				(type solid)
			)
			(layer "F.Fab")
		)
		(fp_line
			(start 0.201 0)
			(end 0.201 -0.202)
			(stroke
				(width 0.15)
				(type solid)
			)
			(layer "F.Fab")
		)
		(fp_line
			(start 0.201 -0.202)
			(end -0.101 0)
			(stroke
				(width 0.15)
				(type solid)
			)
			(layer "F.Fab")
		)
		(fp_line
			(start -0.101 0)
			(end 0.201 0.2)
			(stroke
				(width 0.15)
				(type solid)
			)
			(layer "F.Fab")
		)
		(fp_line
			(start -0.199 0.2)
			(end -0.199 0.1)
			(stroke
				(width 0.15)
				(type solid)
			)
			(layer "F.Fab")
		)
		(fp_line
			(start -0.199 0)
			(end -0.597 0)
			(stroke
				(width 0.15)
				(type solid)
			)
			(layer "F.Fab")
		)
		(fp_line
			(start -0.199 -0.202)
			(end -0.199 0.1)
			(stroke
				(width 0.15)
				(type solid)
			)
			(layer "F.Fab")
		)
		(fp_rect
			(start 0.848 0.4)
			(end -0.85 -0.402)
			(stroke
				(width 0.15)
				(type solid)
			)
			(fill no)
			(layer "F.Fab")
		)
		(pad "1" smd roundrect
			(at -0.7 0)
			(size 0.8 1)
			(layers "F.Cu" "F.Mask" "F.Paste")
			(roundrect_rratio 0.2)
			(net 704 "/Power supply/USB_DBG_PD.VBUS")
			(pinfunction "C")
			(pintype "passive")
		)
		(pad "2" smd roundrect
			(at 0.7 0)
			(size 0.8 1)
			(layers "F.Cu" "F.Mask" "F.Paste")
			(roundrect_rratio 0.2)
			(net 1 "GND")
			(pinfunction "A")
			(pintype "passive")
		)
	)
	(footprint "antmicro-footprints:C_0402_1005Metric"
		(layer "F.Cu")
		(at 164.7 139)
		(descr "Capacitor SMD 0402")
		(tags "capacitor SMD 0402")
		(property "Reference" "C188"
			(at -0.95 -1.45 0)
			(layer "F.SilkS")
			(effects
				(font
					(size 0.7 0.7)
					(thickness 0.15)
				)
				(justify left bottom)
			)
		)
		(property "Value" "C_10u_0402"
			(at 0 1.4 0)
			(layer "F.Fab")
			(effects
				(font
					(size 0.7 0.7)
					(thickness 0.15)
				)
				(justify left bottom)
			)
		)
		(property "Description" "SMD Multilayer Ceramic Capacitor, 10 µF, 6.3 V, 0402 [1005 Metric], ± 20%, X5R, CC Series"
			(at 0 0 0)
			(layer "F.Fab")
			(hide yes)
			(effects
				(font
					(size 1.27 1.27)
					(thickness 0.15)
				)
			)
		)
		(property "Author" "Antmicro"
			(at 0 0 0)
			(layer "F.Fab")
			(hide yes)
			(effects
				(font
					(size 1 1)
					(thickness 0.15)
				)
			)
		)
		(property "Dielectric" ""
			(at 0 0 0)
			(layer "F.Fab")
			(hide yes)
			(effects
				(font
					(size 1 1)
					(thickness 0.15)
				)
			)
		)
		(property "License" "Apache-2.0"
			(at 0 0 0)
			(layer "F.Fab")
			(hide yes)
			(effects
				(font
					(size 1 1)
					(thickness 0.15)
				)
			)
		)
		(property "MPN" "CC0402MRX5R5BB106"
			(at 0 0 0)
			(layer "F.Fab")
			(hide yes)
			(effects
				(font
					(size 1 1)
					(thickness 0.15)
				)
			)
		)
		(property "Manufacturer" "YAGEO"
			(at 0 0 0)
			(layer "F.Fab")
			(hide yes)
			(effects
				(font
					(size 1 1)
					(thickness 0.15)
				)
			)
		)
		(property "Val" "10u"
			(at 0 0 0)
			(layer "F.Fab")
			(hide yes)
			(effects
				(font
					(size 1 1)
					(thickness 0.15)
				)
			)
		)
		(property "Voltage" ""
			(at 0 0 0)
			(layer "F.Fab")
			(hide yes)
			(effects
				(font
					(size 1 1)
					(thickness 0.15)
				)
			)
		)
		(sheetname "DRAM + SRAM")
		(sheetfile "ram.kicad_sch")
		(attr smd)
		(fp_rect
			(start -0.925 -0.47)
			(end 0.925 0.47)
			(stroke
				(width 0.05)
				(type default)
			)
			(fill no)
			(layer "F.CrtYd")
		)
		(fp_line
			(start -0.494 -0.25)
			(end 0.504 -0.25)
			(stroke
				(width 0.15)
				(type solid)
			)
			(layer "F.Fab")
		)
		(fp_line
			(start -0.494 0.248)
			(end -0.494 -0.25)
			(stroke
				(width 0.15)
				(type solid)
			)
			(layer "F.Fab")
		)
		(fp_line
			(start 0.504 -0.25)
			(end 0.504 0.248)
			(stroke
				(width 0.15)
				(type solid)
			)
			(layer "F.Fab")
		)
		(fp_line
			(start 0.504 0.248)
			(end -0.494 0.248)
			(stroke
				(width 0.15)
				(type solid)
			)
			(layer "F.Fab")
		)
		(pad "1" smd roundrect
			(at -0.48 0)
			(size 0.59 0.64)
			(layers "F.Cu" "F.Mask" "F.Paste")
			(roundrect_rratio 0.25)
			(net 1 "GND")
			(pintype "passive")
		)
		(pad "2" smd roundrect
			(at 0.48 0)
			(size 0.59 0.64)
			(layers "F.Cu" "F.Mask" "F.Paste")
			(roundrect_rratio 0.25)
			(net 25 "+1V35")
			(pintype "passive")
		)
	)
	(footprint "antmicro-footprints:R_0402_1005Metric"
		(layer "F.Cu")
		(at 225.1 113.2)
		(descr "Resistor SMD 0402")
		(tags "resistor SMD 0402")
		(property "Reference" "R102"
			(at -3.65 0.4 0)
			(layer "F.SilkS")
			(effects
				(font
					(size 0.7 0.7)
					(thickness 0.15)
				)
				(justify left bottom)
			)
		)
		(property "Value" "R_0R_0402"
			(at 0 1.4 0)
			(layer "F.Fab")
			(effects
				(font
					(size 0.7 0.7)
					(thickness 0.15)
				)
				(justify left bottom)
			)
		)
		(property "Description" "SMD Chip Resistor, Jumper, 0 ohm, 100 mW, 0402 [1005 Metric], Thick Film, General Purpose"
			(at 0 0 0)
			(layer "F.Fab")
			(hide yes)
			(effects
				(font
					(size 1.27 1.27)
					(thickness 0.15)
				)
			)
		)
		(property "Author" "Antmicro"
			(at 0 0 0)
			(layer "F.Fab")
			(hide yes)
			(effects
				(font
					(size 1 1)
					(thickness 0.15)
				)
			)
		)
		(property "Current" "1A"
			(at 0 0 0)
			(layer "F.Fab")
			(hide yes)
			(effects
				(font
					(size 1 1)
					(thickness 0.15)
				)
			)
		)
		(property "License" "Apache-2.0"
			(at 0 0 0)
			(layer "F.Fab")
			(hide yes)
			(effects
				(font
					(size 1 1)
					(thickness 0.15)
				)
			)
		)
		(property "MPN" "ERJ2GE0R00X"
			(at 0 0 0)
			(layer "F.Fab")
			(hide yes)
			(effects
				(font
					(size 1 1)
					(thickness 0.15)
				)
			)
		)
		(property "Manufacturer" "Panasonic"
			(at 0 0 0)
			(layer "F.Fab")
			(hide yes)
			(effects
				(font
					(size 1 1)
					(thickness 0.15)
				)
			)
		)
		(property "Tolerance" ""
			(at 0 0 0)
			(layer "F.Fab")
			(hide yes)
			(effects
				(font
					(size 1 1)
					(thickness 0.15)
				)
			)
		)
		(property "Val" "0R"
			(at 0 0 0)
			(layer "F.Fab")
			(hide yes)
			(effects
				(font
					(size 1 1)
					(thickness 0.15)
				)
			)
		)
		(sheetname "SPI Flash + SD Card")
		(sheetfile "spi-flash.kicad_sch")
		(attr smd)
		(fp_rect
			(start -0.925 -0.47)
			(end 0.925 0.47)
			(stroke
				(width 0.05)
				(type default)
			)
			(fill no)
			(layer "F.CrtYd")
		)
		(fp_rect
			(start -0.5 -0.25)
			(end 0.5 0.25)
			(stroke
				(width 0.15)
				(type solid)
			)
			(fill no)
			(layer "F.Fab")
		)
		(pad "1" smd roundrect
			(at -0.48 0)
			(size 0.59 0.64)
			(layers "F.Cu" "F.Mask" "F.Paste")
			(roundrect_rratio 0.25)
			(net 430 "/FPGA Bank 16 & 17/USR_FLASH_1.DQ1")
			(pintype "passive")
		)
		(pad "2" smd roundrect
			(at 0.48 0)
			(size 0.59 0.64)
			(layers "F.Cu" "F.Mask" "F.Paste")
			(roundrect_rratio 0.25)
			(net 909 "/SPI Flash + SD Card/USR_FLASH_1_DQ1")
			(pintype "passive")
		)
	)
	(footprint "antmicro-footprints:BarrelJack_Pin2mm_MJ-179PH"
		(locked yes)
		(layer "F.Cu")
		(at 258.44 177.32)
		(property "Reference" "J2"
			(at -0.01 -6.28 0)
			(layer "F.SilkS")
			(effects
				(font
					(size 0.7 0.7)
					(thickness 0.15)
				)
				(justify left bottom)
			)
		)
		(property "Value" "BarrelJack_Pin2mm_MJ-179PH"
			(at 0 6.1 0)
			(layer "F.Fab")
			(effects
				(font
					(size 0.7 0.7)
					(thickness 0.15)
				)
				(justify left bottom)
			)
		)
		(property "Description" "DC Power Connector, Jack, 4 A, 1.95 mm, PCB Mount, Through Hole"
			(at 0 0 0)
			(layer "F.Fab")
			(hide yes)
			(effects
				(font
					(size 1.27 1.27)
					(thickness 0.15)
				)
			)
		)
		(property "Author" "Antmicro"
			(at 0 0 0)
			(layer "F.Fab")
			(hide yes)
			(effects
				(font
					(size 1 1)
					(thickness 0.15)
				)
			)
		)
		(property "License" "Apache-2.0"
			(at 0 0 0)
			(layer "F.Fab")
			(hide yes)
			(effects
				(font
					(size 1 1)
					(thickness 0.15)
				)
			)
		)
		(property "MPN" "MJ-179PH"
			(at 0 0 0)
			(layer "F.Fab")
			(hide yes)
			(effects
				(font
					(size 1 1)
					(thickness 0.15)
				)
			)
		)
		(property "Manufacturer" "Multicomp Pro"
			(at 0 0 0)
			(layer "F.Fab")
			(hide yes)
			(effects
				(font
					(size 1 1)
					(thickness 0.15)
				)
			)
		)
		(sheetname "Power supply")
		(sheetfile "power-supply.kicad_sch")
		(attr through_hole)
		(fp_line
			(start -0.1 -4.8)
			(end 0.8255 -4.8)
			(stroke
				(width 0.15)
				(type solid)
			)
			(layer "F.SilkS")
		)
		(fp_line
			(start -0.1 -2.4)
			(end -0.1 -4.8)
			(stroke
				(width 0.15)
				(type solid)
			)
			(layer "F.SilkS")
		)
		(fp_line
			(start -0.1 4.8)
			(end -0.1 2.4)
			(stroke
				(width 0.15)
				(type solid)
			)
			(layer "F.SilkS")
		)
		(fp_line
			(start 10.1 4.8)
			(end 10.1 -4.8)
			(stroke
				(width 0.15)
				(type solid)
			)
			(layer "F.SilkS")
		)
		(fp_line
			(start 14 -4.8)
			(end 5.1 -4.8)
			(stroke
				(width 0.15)
				(type solid)
			)
			(layer "F.SilkS")
		)
		(fp_line
			(start 14 4.8)
			(end -0.1 4.8)
			(stroke
				(width 0.15)
				(type solid)
			)
			(layer "F.SilkS")
		)
		(fp_line
			(start 14 4.8)
			(end 14 -4.8)
			(stroke
				(width 0.15)
				(type solid)
			)
			(layer "F.SilkS")
		)
		(fp_line
			(start -1.3 -2.5)
			(end -1.3 2.5)
			(stroke
				(width 0.05)
				(type solid)
			)
			(layer "F.CrtYd")
		)
		(fp_line
			(start -1.3 2.5)
			(end -0.4 2.5)
			(stroke
				(width 0.05)
				(type solid)
			)
			(layer "F.CrtYd")
		)
		(fp_line
			(start -0.4 -5.1)
			(end -0.4 -2.5)
			(stroke
				(width 0.05)
				(type solid)
			)
			(layer "F.CrtYd")
		)
		(fp_line
			(start -0.4 -2.5)
			(end -1.3 -2.5)
			(stroke
				(width 0.05)
				(type solid)
			)
			(layer "F.CrtYd")
		)
		(fp_line
			(start -0.4 2.5)
			(end -0.4 5.1)
			(stroke
				(width 0.05)
				(type solid)
			)
			(layer "F.CrtYd")
		)
		(fp_line
			(start -0.4 5.1)
			(end 14.3 5.1)
			(stroke
				(width 0.05)
				(type solid)
			)
			(layer "F.CrtYd")
		)
		(fp_line
			(start 0.7 -6.1)
			(end 0.7 -5.1)
			(stroke
				(width 0.05)
				(type solid)
			)
			(layer "F.CrtYd")
		)
		(fp_line
			(start 0.7 -5.1)
			(end -0.4 -5.1)
			(stroke
				(width 0.05)
				(type solid)
			)
			(layer "F.CrtYd")
		)
		(fp_line
			(start 5.2 -6.1)
			(end 0.7 -6.1)
			(stroke
				(width 0.05)
				(type solid)
			)
			(layer "F.CrtYd")
		)
		(fp_line
			(start 5.2 -5.1)
			(end 5.2 -6.1)
			(stroke
				(width 0.05)
				(type solid)
			)
			(layer "F.CrtYd")
		)
		(fp_line
			(start 14.3 -5.1)
			(end 5.2 -5.1)
			(stroke
				(width 0.05)
				(type solid)
			)
			(layer "F.CrtYd")
		)
		(fp_line
			(start 14.3 5.1)
			(end 14.3 -5.1)
			(stroke
				(width 0.05)
				(type solid)
			)
			(layer "F.CrtYd")
		)
		(fp_line
			(start -0.4 3.6)
			(end 0.5 4.5)
			(stroke
				(width 0.15)
				(type solid)
			)
			(layer "F.Fab")
		)
		(fp_rect
			(start -0.4 4.5)
			(end 13.7 -5.111)
			(stroke
				(width 0.15)
				(type solid)
			)
			(fill no)
			(layer "F.Fab")
		)
		(pad "1" thru_hole oval
			(at 0 0)
			(size 2 4.5)
			(drill oval 1 3.5)
			(layers "*.Cu" "*.Mask")
			(remove_unused_layers no)
			(net 1192 "Net-(F1-Pad1)")
			(pinfunction "1")
			(pintype "passive")
		)
		(pad "2" thru_hole oval
			(at 2.948 -4.879 270)
			(size 1.99 4)
			(drill oval 1 3)
			(layers "*.Cu" "*.Mask")
			(remove_unused_layers no)
			(net 1 "GND")
			(pinfunction "2")
			(pintype "passive")
		)
		(pad "3" thru_hole oval
			(at 5.999 0 180)
			(size 2 4)
			(drill oval 1 3)
			(layers "*.Cu" "*.Mask")
			(remove_unused_layers no)
			(net 1 "GND")
			(pinfunction "3")
			(pintype "passive")
		)
	)
	(footprint "antmicro-footprints:C_0402_1005Metric"
		(layer "F.Cu")
		(at 238.6 140.2)
		(descr "Capacitor SMD 0402")
		(tags "capacitor SMD 0402")
		(property "Reference" "C250"
			(at 1.55 2.25 0)
			(layer "F.SilkS")
			(effects
				(font
					(size 0.7 0.7)
					(thickness 0.15)
				)
				(justify left bottom)
			)
		)
		(property "Value" "C_100n_0402"
			(at 0 1.169 0)
			(layer "F.Fab")
			(effects
				(font
					(size 0.7 0.7)
					(thickness 0.15)
				)
				(justify left bottom)
			)
		)
		(property "Description" "SMD Multilayer Ceramic Capacitor, 0.1 µF, 50 V, 0402 [1005 Metric], ± 10%, X5R, GRM Series"
			(at 0 0 0)
			(layer "F.Fab")
			(hide yes)
			(effects
				(font
					(size 1.27 1.27)
					(thickness 0.15)
				)
			)
		)
		(property "Author" "Antmicro"
			(at 0 0 0)
			(layer "F.Fab")
			(hide yes)
			(effects
				(font
					(size 1 1)
					(thickness 0.15)
				)
			)
		)
		(property "Dielectric" "X5R"
			(at 0 0 0)
			(layer "F.Fab")
			(hide yes)
			(effects
				(font
					(size 1 1)
					(thickness 0.15)
				)
			)
		)
		(property "License" "Apache-2.0"
			(at 0 0 0)
			(layer "F.Fab")
			(hide yes)
			(effects
				(font
					(size 1 1)
					(thickness 0.15)
				)
			)
		)
		(property "MPN" "GRM155R61H104KE14D"
			(at 0 0 0)
			(layer "F.Fab")
			(hide yes)
			(effects
				(font
					(size 1 1)
					(thickness 0.15)
				)
			)
		)
		(property "Manufacturer" "Murata"
			(at 0 0 0)
			(layer "F.Fab")
			(hide yes)
			(effects
				(font
					(size 1 1)
					(thickness 0.15)
				)
			)
		)
		(property "Val" "100n"
			(at 0 0 0)
			(layer "F.Fab")
			(hide yes)
			(effects
				(font
					(size 1 1)
					(thickness 0.15)
				)
			)
		)
		(property "Voltage" "50V"
			(at 0 0 0)
			(layer "F.Fab")
			(hide yes)
			(effects
				(font
					(size 1 1)
					(thickness 0.15)
				)
			)
		)
		(sheetname "USB PHY")
		(sheetfile "usb-phy.kicad_sch")
		(attr smd)
		(fp_rect
			(start -0.925 -0.47)
			(end 0.925 0.47)
			(stroke
				(width 0.05)
				(type default)
			)
			(fill no)
			(layer "F.CrtYd")
		)
		(fp_line
			(start -0.494 -0.25)
			(end 0.504 -0.25)
			(stroke
				(width 0.15)
				(type solid)
			)
			(layer "F.Fab")
		)
		(fp_line
			(start -0.494 0.248)
			(end -0.494 -0.25)
			(stroke
				(width 0.15)
				(type solid)
			)
			(layer "F.Fab")
		)
		(fp_line
			(start 0.504 -0.25)
			(end 0.504 0.248)
			(stroke
				(width 0.15)
				(type solid)
			)
			(layer "F.Fab")
		)
		(fp_line
			(start 0.504 0.248)
			(end -0.494 0.248)
			(stroke
				(width 0.15)
				(type solid)
			)
			(layer "F.Fab")
		)
		(pad "1" smd roundrect
			(at -0.48 0)
			(size 0.59 0.64)
			(layers "F.Cu" "F.Mask" "F.Paste")
			(roundrect_rratio 0.25)
			(net 1 "GND")
			(pintype "passive")
		)
		(pad "2" smd roundrect
			(at 0.48 0)
			(size 0.59 0.64)
			(layers "F.Cu" "F.Mask" "F.Paste")
			(roundrect_rratio 0.25)
			(net 24 "+3V3")
			(pintype "passive")
		)
	)
	(footprint "antmicro-footprints:USB-C_Receptacle_GCT_USB4105-GF-A"
		(locked yes)
		(layer "F.Cu")
		(at 267.11 127 90)
		(property "Reference" "J14"
			(at 5.3 -1.31 180)
			(layer "F.SilkS")
			(effects
				(font
					(size 0.7 0.7)
					(thickness 0.15)
				)
				(justify left bottom)
			)
		)
		(property "Value" "USB-C_GCT_USB4105-GF-A"
			(at 0 5 90)
			(layer "F.Fab")
			(effects
				(font
					(size 0.7 0.7)
					(thickness 0.15)
				)
				(justify left bottom)
			)
		)
		(property "Description" "USB-C (USB TYPE-C) USB 2.0 Receptacle Connector 24 (16+8 Dummy) Position Surface Mount, Right Angle"
			(at 0 0 90)
			(layer "F.Fab")
			(hide yes)
			(effects
				(font
					(size 1.27 1.27)
					(thickness 0.15)
				)
			)
		)
		(property "Author" "Antmicro"
			(at 394.11 -140.11 0)
			(layer "F.Fab")
			(hide yes)
			(effects
				(font
					(size 1 1)
					(thickness 0.15)
				)
			)
		)
		(property "License" "Apache-2.0"
			(at 394.11 -140.11 0)
			(layer "F.Fab")
			(hide yes)
			(effects
				(font
					(size 1 1)
					(thickness 0.15)
				)
			)
		)
		(property "MPN" "USB4105-GF-A"
			(at 394.11 -140.11 0)
			(layer "F.Fab")
			(hide yes)
			(effects
				(font
					(size 1 1)
					(thickness 0.15)
				)
			)
		)
		(property "Manufacturer" "GCT"
			(at 394.11 -140.11 0)
			(layer "F.Fab")
			(hide yes)
			(effects
				(font
					(size 1 1)
					(thickness 0.15)
				)
			)
		)
		(property "VSD_Class" "USB-C"
			(at 394.11 -140.11 0)
			(layer "F.Fab")
			(hide yes)
			(effects
				(font
					(size 1 1)
					(thickness 0.15)
				)
			)
		)
		(sheetname "USB PHY")
		(sheetfile "usb-phy.kicad_sch")
		(attr smd)
		(fp_line
			(start 4.788 -1.395)
			(end 4.788 -0.145)
			(stroke
				(width 0.15)
				(type solid)
			)
			(layer "F.SilkS")
		)
		(fp_line
			(start -4.79 -1.395)
			(end -4.79 -0.145)
			(stroke
				(width 0.15)
				(type solid)
			)
			(layer "F.SilkS")
		)
		(fp_line
			(start -4.79 2.575)
			(end -4.79 3.854)
			(stroke
				(width 0.15)
				(type solid)
			)
			(layer "F.SilkS")
		)
		(fp_line
			(start 4.788 3.854)
			(end 4.788 2.575)
			(stroke
				(width 0.15)
				(type solid)
			)
			(layer "F.SilkS")
		)
		(fp_line
			(start -4.79 3.854)
			(end 4.788 3.854)
			(stroke
				(width 0.15)
				(type solid)
			)
			(layer "F.SilkS")
		)
		(fp_circle
			(center -3.8 -4.27071)
			(end -3.75 -4.22071)
			(stroke
				(width 0.15)
				(type solid)
			)
			(fill yes)
			(layer "F.SilkS")
		)
		(fp_rect
			(start -5.1 -4.4)
			(end 5.1 3.9)
			(stroke
				(width 0.05)
				(type solid)
			)
			(fill no)
			(layer "F.CrtYd")
		)
		(fp_line
			(start 4.788 -3.676)
			(end 4.788 3.854)
			(stroke
				(width 0.15)
				(type solid)
			)
			(layer "F.Fab")
		)
		(fp_line
			(start -4.79 -3.676)
			(end 4.788 -3.676)
			(stroke
				(width 0.15)
				(type solid)
			)
			(layer "F.Fab")
		)
		(fp_line
			(start 4.788 3.854)
			(end -4.79 3.854)
			(stroke
				(width 0.15)
				(type solid)
			)
			(layer "F.Fab")
		)
		(fp_line
			(start -4.702 3.854)
			(end 4.788 3.854)
			(stroke
				(width 0.15)
				(type solid)
			)
			(layer "F.Fab")
		)
		(fp_line
			(start -4.79 3.854)
			(end -4.79 -3.676)
			(stroke
				(width 0.15)
				(type solid)
			)
			(layer "F.Fab")
		)
		(pad "" np_thru_hole circle
			(at -2.891 -2.426 90)
			(size 0.65 0.65)
			(drill 0.65)
			(layers "*.Cu" "*.Mask")
		)
		(pad "" np_thru_hole circle
			(at 2.89 -2.426 90)
			(size 0.65 0.65)
			(drill 0.65)
			(layers "*.Cu" "*.Mask")
		)
		(pad "A1" smd roundrect
			(at -3.202 -3.5 90)
			(size 0.6 1.15)
			(layers "F.Cu" "F.Mask" "F.Paste")
			(roundrect_rratio 0.25)
			(net 1 "GND")
			(pinfunction "GND")
			(pintype "power_in")
		)
		(pad "A4" smd roundrect
			(at -2.4 -3.5 90)
			(size 0.6 1.15)
			(layers "F.Cu" "F.Mask" "F.Paste")
			(roundrect_rratio 0.25)
			(net 715 "/USB PHY/USB_USR_VBUS")
			(pinfunction "VBUS")
			(pintype "passive")
		)
		(pad "A5" smd roundrect
			(at -1.25 -3.5 90)
			(size 0.3 1.15)
			(layers "F.Cu" "F.Mask" "F.Paste")
			(roundrect_rratio 0.25)
			(net 841 "/USB PHY/USB_USR_CC1")
			(pinfunction "CC_{1}")
			(pintype "bidirectional")
		)
		(pad "A6" smd roundrect
			(at -0.25 -3.5 90)
			(size 0.3 1.15)
			(layers "F.Cu" "F.Mask" "F.Paste")
			(roundrect_rratio 0.25)
			(net 842 "/USB PHY/USB_USR_CONN_D+")
			(pinfunction "D_{A}+")
			(pintype "bidirectional")
		)
		(pad "A7" smd roundrect
			(at 0.248 -3.5 90)
			(size 0.3 1.15)
			(layers "F.Cu" "F.Mask" "F.Paste")
			(roundrect_rratio 0.25)
			(net 843 "/USB PHY/USB_USR_CONN_D-")
			(pinfunction "D_{A}-")
			(pintype "bidirectional")
		)
		(pad "A8" smd roundrect
			(at 1.249 -3.5 90)
			(size 0.3 1.15)
			(layers "F.Cu" "F.Mask" "F.Paste")
			(roundrect_rratio 0.25)
			(net 34 "unconnected-(J14-SBU_{1}-PadA8)")
			(pinfunction "SBU_{1}")
			(pintype "bidirectional+no_connect")
		)
		(pad "A9" smd roundrect
			(at 2.398 -3.5 90)
			(size 0.6 1.15)
			(layers "F.Cu" "F.Mask" "F.Paste")
			(roundrect_rratio 0.25)
			(net 715 "/USB PHY/USB_USR_VBUS")
			(pinfunction "VBUS")
			(pintype "passive")
		)
		(pad "A12" smd roundrect
			(at 3.2 -3.5 90)
			(size 0.6 1.15)
			(layers "F.Cu" "F.Mask" "F.Paste")
			(roundrect_rratio 0.25)
			(net 1 "GND")
			(pinfunction "GND")
			(pintype "passive")
		)
		(pad "B1" smd roundrect
			(at 3.2 -3.5 90)
			(size 0.6 1.15)
			(layers "F.Cu" "F.Mask" "F.Paste")
			(roundrect_rratio 0.25)
			(net 1 "GND")
			(pinfunction "GND")
			(pintype "passive")
		)
		(pad "B4" smd roundrect
			(at 2.398 -3.5 90)
			(size 0.6 1.15)
			(layers "F.Cu" "F.Mask" "F.Paste")
			(roundrect_rratio 0.25)
			(net 715 "/USB PHY/USB_USR_VBUS")
			(pinfunction "VBUS")
			(pintype "passive")
		)
		(pad "B5" smd roundrect
			(at 1.749 -3.5 90)
			(size 0.3 1.15)
			(layers "F.Cu" "F.Mask" "F.Paste")
			(roundrect_rratio 0.25)
			(net 844 "/USB PHY/USB_USR_CC2")
			(pinfunction "CC_{2}")
			(pintype "bidirectional")
		)
		(pad "B6" smd roundrect
			(at 0.748 -3.5 90)
			(size 0.3 1.15)
			(layers "F.Cu" "F.Mask" "F.Paste")
			(roundrect_rratio 0.25)
			(net 842 "/USB PHY/USB_USR_CONN_D+")
			(pinfunction "D_{B}+")
			(pintype "bidirectional")
		)
		(pad "B7" smd roundrect
			(at -0.75 -3.5 90)
			(size 0.3 1.15)
			(layers "F.Cu" "F.Mask" "F.Paste")
			(roundrect_rratio 0.25)
			(net 843 "/USB PHY/USB_USR_CONN_D-")
			(pinfunction "D_{B}-")
			(pintype "bidirectional")
		)
		(pad "B8" smd roundrect
			(at -1.75 -3.5 90)
			(size 0.3 1.15)
			(layers "F.Cu" "F.Mask" "F.Paste")
			(roundrect_rratio 0.25)
			(net 35 "unconnected-(J14-SBU_{2}-PadB8)")
			(pinfunction "SBU_{2}")
			(pintype "bidirectional+no_connect")
		)
		(pad "B9" smd roundrect
			(at -2.4 -3.5 90)
			(size 0.6 1.15)
			(layers "F.Cu" "F.Mask" "F.Paste")
			(roundrect_rratio 0.25)
			(net 715 "/USB PHY/USB_USR_VBUS")
			(pinfunction "VBUS")
			(pintype "passive")
		)
		(pad "B12" smd roundrect
			(at -3.202 -3.5 90)
			(size 0.6 1.15)
			(layers "F.Cu" "F.Mask" "F.Paste")
			(roundrect_rratio 0.25)
			(net 1 "GND")
			(pinfunction "GND")
			(pintype "passive")
		)
		(pad "SH" thru_hole oval
			(at -4.321 -2.926 90)
			(size 1.05 2.1)
			(drill oval 0.6 1.7)
			(layers "*.Cu" "*.Mask")
			(remove_unused_layers no)
			(net 1 "GND")
			(pinfunction "SH")
			(pintype "passive")
		)
		(pad "SH" thru_hole oval
			(at -4.321 1.255 90)
			(size 1 2)
			(drill oval 0.6 1.4)
			(layers "*.Cu" "*.Mask")
			(remove_unused_layers no)
			(net 1 "GND")
			(pinfunction "SH")
			(pintype "passive")
		)
		(pad "SH" thru_hole oval
			(at 4.32 -2.926 90)
			(size 1.05 2.1)
			(drill oval 0.6 1.7)
			(layers "*.Cu" "*.Mask")
			(remove_unused_layers no)
			(net 1 "GND")
			(pinfunction "SH")
			(pintype "passive")
		)
		(pad "SH" thru_hole oval
			(at 4.32 1.255 90)
			(size 1 2)
			(drill oval 0.6 1.4)
			(layers "*.Cu" "*.Mask")
			(remove_unused_layers no)
			(net 1 "GND")
			(pinfunction "SH")
			(pintype "passive")
		)
	)
	(footprint "antmicro-footprints:LED_0603_1608Metric_G"
		(layer "F.Cu")
		(at 261.5 91)
		(descr "LED SMD 0603 Green")
		(tags "LED SMD 0603 Green")
		(property "Reference" "D21"
			(at -1.05 1.55 0)
			(layer "F.SilkS")
			(effects
				(font
					(size 0.7 0.7)
					(thickness 0.15)
				)
				(justify left bottom)
			)
		)
		(property "Value" "LED_G_0603_KP-1608CGCK"
			(at 0 1.6 0)
			(layer "F.Fab")
			(effects
				(font
					(size 0.7 0.7)
					(thickness 0.15)
				)
				(justify left bottom)
			)
		)
		(property "Description" "LED, Green, SMD, 0603, 20 mA, 2.1 V, 570 nm"
			(at 0 0 0)
			(layer "F.Fab")
			(hide yes)
			(effects
				(font
					(size 1.27 1.27)
					(thickness 0.15)
				)
			)
		)
		(property "Author" "Antmicro"
			(at 0 0 0)
			(layer "F.Fab")
			(hide yes)
			(effects
				(font
					(size 1 1)
					(thickness 0.15)
				)
			)
		)
		(property "Color" "Green"
			(at 0 0 0)
			(layer "F.Fab")
			(hide yes)
			(effects
				(font
					(size 1 1)
					(thickness 0.15)
				)
			)
		)
		(property "License" "Apache-2.0"
			(at 0 0 0)
			(layer "F.Fab")
			(hide yes)
			(effects
				(font
					(size 1 1)
					(thickness 0.15)
				)
			)
		)
		(property "MPN" "KP-1608CGCK"
			(at 0 0 0)
			(layer "F.Fab")
			(hide yes)
			(effects
				(font
					(size 1 1)
					(thickness 0.15)
				)
			)
		)
		(property "Manufacturer" "Kingbright"
			(at 0 0 0)
			(layer "F.Fab")
			(hide yes)
			(effects
				(font
					(size 1 1)
					(thickness 0.15)
				)
			)
		)
		(sheetname "User GPIO + LED + button + DIP switch")
		(sheetfile "user-gpio.kicad_sch")
		(attr smd)
		(fp_line
			(start -1.18 -0.319)
			(end -1.18 0.321)
			(stroke
				(width 0.15)
				(type solid)
			)
			(layer "F.SilkS")
		)
		(fp_line
			(start -0.094672 0.001008)
			(end -0.24 0.001008)
			(stroke
				(width 0.1)
				(type solid)
			)
			(layer "F.SilkS")
		)
		(fp_line
			(start -0.094672 0.001008)
			(end 0.105328 -0.198992)
			(stroke
				(width 0.1)
				(type solid)
			)
			(layer "F.SilkS")
		)
		(fp_line
			(start -0.094672 0.201008)
			(end -0.094672 -0.198992)
			(stroke
				(width 0.1)
				(type solid)
			)
			(layer "F.SilkS")
		)
		(fp_line
			(start 0.105328 0.001008)
			(end 0.24 0.001)
			(stroke
				(width 0.1)
				(type solid)
			)
			(layer "F.SilkS")
		)
		(fp_line
			(start 0.105328 0.201008)
			(end -0.094672 0.001008)
			(stroke
				(width 0.1)
				(type solid)
			)
			(layer "F.SilkS")
		)
		(fp_line
			(start 0.105328 0.201008)
			(end 0.105328 -0.198992)
			(stroke
				(width 0.1)
				(type solid)
			)
			(layer "F.SilkS")
		)
		(fp_line
			(start 0.22 -0.35)
			(end -0.22 -0.35)
			(stroke
				(width 0.15)
				(type solid)
			)
			(layer "F.SilkS")
		)
		(fp_line
			(start 0.22 0.35)
			(end -0.22 0.35)
			(stroke
				(width 0.15)
				(type solid)
			)
			(layer "F.SilkS")
		)
		(fp_rect
			(start 1.25 0.65)
			(end -1.25 -0.65)
			(stroke
				(width 0.05)
				(type solid)
			)
			(fill no)
			(layer "F.CrtYd")
		)
		(fp_line
			(start -0.199 -0.202)
			(end -0.199 0.1)
			(stroke
				(width 0.15)
				(type solid)
			)
			(layer "F.Fab")
		)
		(fp_line
			(start -0.199 0)
			(end -0.597 0)
			(stroke
				(width 0.15)
				(type solid)
			)
			(layer "F.Fab")
		)
		(fp_line
			(start -0.199 0.2)
			(end -0.199 0.1)
			(stroke
				(width 0.15)
				(type solid)
			)
			(layer "F.Fab")
		)
		(fp_line
			(start -0.101 0)
			(end 0.201 0.2)
			(stroke
				(width 0.15)
				(type solid)
			)
			(layer "F.Fab")
		)
		(fp_line
			(start 0.201 -0.202)
			(end -0.101 0)
			(stroke
				(width 0.15)
				(type solid)
			)
			(layer "F.Fab")
		)
		(fp_line
			(start 0.201 0)
			(end 0.201 -0.202)
			(stroke
				(width 0.15)
				(type solid)
			)
			(layer "F.Fab")
		)
		(fp_line
			(start 0.201 0.2)
			(end 0.201 0)
			(stroke
				(width 0.15)
				(type solid)
			)
			(layer "F.Fab")
		)
		(fp_line
			(start 0.599 0)
			(end 0.201 0)
			(stroke
				(width 0.15)
				(type solid)
			)
			(layer "F.Fab")
		)
		(fp_rect
			(start 0.848 0.4)
			(end -0.85 -0.402)
			(stroke
				(width 0.15)
				(type solid)
			)
			(fill no)
			(layer "F.Fab")
		)
		(pad "1" smd roundrect
			(at -0.7 0 180)
			(size 0.8 1)
			(layers "F.Cu" "F.Mask" "F.Paste")
			(roundrect_rratio 0.2)
			(net 23 "Net-(D21-C)")
			(pinfunction "C")
			(pintype "passive")
		)
		(pad "2" smd roundrect
			(at 0.7 0 180)
			(size 0.8 1)
			(layers "F.Cu" "F.Mask" "F.Paste")
			(roundrect_rratio 0.2)
			(net 781 "Net-(D21-A)")
			(pinfunction "A")
			(pintype "passive")
		)
	)
	(footprint "antmicro-footprints:C_0402_1005Metric"
		(layer "F.Cu")
		(at 243.6 141.6 90)
		(descr "Capacitor SMD 0402")
		(tags "capacitor SMD 0402")
		(property "Reference" "C234"
			(at -1.7 6.5 90)
			(layer "F.SilkS")
			(effects
				(font
					(size 0.7 0.7)
					(thickness 0.15)
				)
				(justify left bottom)
			)
		)
		(property "Value" "C_10u_0402"
			(at 0 1.4 90)
			(layer "F.Fab")
			(effects
				(font
					(size 0.7 0.7)
					(thickness 0.15)
				)
				(justify left bottom)
			)
		)
		(property "Description" "SMD Multilayer Ceramic Capacitor, 10 µF, 6.3 V, 0402 [1005 Metric], ± 20%, X5R, CC Series"
			(at 0 0 90)
			(layer "F.Fab")
			(hide yes)
			(effects
				(font
					(size 1.27 1.27)
					(thickness 0.15)
				)
			)
		)
		(property "Author" "Antmicro"
			(at 385.2 -102 0)
			(layer "F.Fab")
			(hide yes)
			(effects
				(font
					(size 1 1)
					(thickness 0.15)
				)
			)
		)
		(property "Dielectric" ""
			(at 385.2 -102 0)
			(layer "F.Fab")
			(hide yes)
			(effects
				(font
					(size 1 1)
					(thickness 0.15)
				)
			)
		)
		(property "License" "Apache-2.0"
			(at 385.2 -102 0)
			(layer "F.Fab")
			(hide yes)
			(effects
				(font
					(size 1 1)
					(thickness 0.15)
				)
			)
		)
		(property "MPN" "CC0402MRX5R5BB106"
			(at 385.2 -102 0)
			(layer "F.Fab")
			(hide yes)
			(effects
				(font
					(size 1 1)
					(thickness 0.15)
				)
			)
		)
		(property "Manufacturer" "YAGEO"
			(at 385.2 -102 0)
			(layer "F.Fab")
			(hide yes)
			(effects
				(font
					(size 1 1)
					(thickness 0.15)
				)
			)
		)
		(property "Val" "10u"
			(at 385.2 -102 0)
			(layer "F.Fab")
			(hide yes)
			(effects
				(font
					(size 1 1)
					(thickness 0.15)
				)
			)
		)
		(property "Voltage" ""
			(at 385.2 -102 0)
			(layer "F.Fab")
			(hide yes)
			(effects
				(font
					(size 1 1)
					(thickness 0.15)
				)
			)
		)
		(sheetname "USB PHY")
		(sheetfile "usb-phy.kicad_sch")
		(attr smd)
		(fp_rect
			(start -0.925 -0.47)
			(end 0.925 0.47)
			(stroke
				(width 0.05)
				(type default)
			)
			(fill no)
			(layer "F.CrtYd")
		)
		(fp_line
			(start 0.504 -0.25)
			(end 0.504 0.248)
			(stroke
				(width 0.15)
				(type solid)
			)
			(layer "F.Fab")
		)
		(fp_line
			(start -0.494 -0.25)
			(end 0.504 -0.25)
			(stroke
				(width 0.15)
				(type solid)
			)
			(layer "F.Fab")
		)
		(fp_line
			(start 0.504 0.248)
			(end -0.494 0.248)
			(stroke
				(width 0.15)
				(type solid)
			)
			(layer "F.Fab")
		)
		(fp_line
			(start -0.494 0.248)
			(end -0.494 -0.25)
			(stroke
				(width 0.15)
				(type solid)
			)
			(layer "F.Fab")
		)
		(pad "1" smd roundrect
			(at -0.48 0 90)
			(size 0.59 0.64)
			(layers "F.Cu" "F.Mask" "F.Paste")
			(roundrect_rratio 0.25)
			(net 1 "GND")
			(pintype "passive")
		)
		(pad "2" smd roundrect
			(at 0.48 0 90)
			(size 0.59 0.64)
			(layers "F.Cu" "F.Mask" "F.Paste")
			(roundrect_rratio 0.25)
			(net 712 "/USB PHY/FTDI_VCORE")
			(pintype "passive")
		)
	)
	(footprint "antmicro-footprints:R_0402_1005Metric"
		(layer "F.Cu")
		(at 213.9 165.4 90)
		(descr "Resistor SMD 0402")
		(tags "resistor SMD 0402")
		(property "Reference" "R67"
			(at -0.4 -5.25 90)
			(layer "F.SilkS")
			(effects
				(font
					(size 0.7 0.7)
					(thickness 0.15)
				)
				(justify left bottom)
			)
		)
		(property "Value" "R_10k_0402"
			(at 0 1.4 90)
			(layer "F.Fab")
			(effects
				(font
					(size 0.7 0.7)
					(thickness 0.15)
				)
				(justify left bottom)
			)
		)
		(property "Description" "SMD Chip Resistor, 10 kohm, ± 1%, 62.5 mW, 0402 [1005 Metric], Thick Film, General Purpose"
			(at 0 0 90)
			(layer "F.Fab")
			(hide yes)
			(effects
				(font
					(size 1.27 1.27)
					(thickness 0.15)
				)
			)
		)
		(property "Author" "Antmicro"
			(at 379.3 -48.5 0)
			(layer "F.Fab")
			(hide yes)
			(effects
				(font
					(size 1 1)
					(thickness 0.15)
				)
			)
		)
		(property "License" "Apache-2.0"
			(at 379.3 -48.5 0)
			(layer "F.Fab")
			(hide yes)
			(effects
				(font
					(size 1 1)
					(thickness 0.15)
				)
			)
		)
		(property "MPN" "CR0402-FX-1002GLF"
			(at 379.3 -48.5 0)
			(layer "F.Fab")
			(hide yes)
			(effects
				(font
					(size 1 1)
					(thickness 0.15)
				)
			)
		)
		(property "Manufacturer" "Bourns"
			(at 379.3 -48.5 0)
			(layer "F.Fab")
			(hide yes)
			(effects
				(font
					(size 1 1)
					(thickness 0.15)
				)
			)
		)
		(property "Tolerance" "1%"
			(at 379.3 -48.5 0)
			(layer "F.Fab")
			(hide yes)
			(effects
				(font
					(size 1 1)
					(thickness 0.15)
				)
			)
		)
		(property "Val" "10k"
			(at 379.3 -48.5 0)
			(layer "F.Fab")
			(hide yes)
			(effects
				(font
					(size 1 1)
					(thickness 0.15)
				)
			)
		)
		(sheetname "SPI Flash + SD Card")
		(sheetfile "spi-flash.kicad_sch")
		(attr smd)
		(fp_rect
			(start -0.925 -0.47)
			(end 0.925 0.47)
			(stroke
				(width 0.05)
				(type default)
			)
			(fill no)
			(layer "F.CrtYd")
		)
		(fp_rect
			(start -0.5 -0.25)
			(end 0.5 0.25)
			(stroke
				(width 0.15)
				(type solid)
			)
			(fill no)
			(layer "F.Fab")
		)
		(pad "1" smd roundrect
			(at -0.48 0 90)
			(size 0.59 0.64)
			(layers "F.Cu" "F.Mask" "F.Paste")
			(roundrect_rratio 0.25)
			(net 404 "/FPGA Bank 33 & 34/USR_FLASH_0.DQ2")
			(pintype "passive")
		)
		(pad "2" smd roundrect
			(at 0.48 0 90)
			(size 0.59 0.64)
			(layers "F.Cu" "F.Mask" "F.Paste")
			(roundrect_rratio 0.25)
			(net 26 "+1V8")
			(pintype "passive")
		)
	)
	(footprint "antmicro-footprints:FB_0603_1608Metric"
		(layer "F.Cu")
		(at 256.845 136.535 180)
		(property "Reference" "FB5"
			(at 0.795 4.535 180)
			(layer "F.SilkS")
			(effects
				(font
					(size 0.7 0.7)
					(thickness 0.15)
				)
				(justify left bottom)
			)
		)
		(property "Value" "FB_600Z_0.5A_Murata-BLM18AG_0603"
			(at 0 1.7 180)
			(layer "F.Fab")
			(effects
				(font
					(size 0.7 0.7)
					(thickness 0.15)
				)
				(justify left bottom)
			)
		)
		(property "Description" "Ferrite Bead, 0603 [1608 Metric], 600 ohm, 500 mA, BLM18A, 0.38 ohm, ± 25%, General use"
			(at 0 0 180)
			(layer "F.Fab")
			(hide yes)
			(effects
				(font
					(size 1.27 1.27)
					(thickness 0.15)
				)
			)
		)
		(property "Author" "Antmicro"
			(at 513.69 273.07 0)
			(layer "F.Fab")
			(hide yes)
			(effects
				(font
					(size 1 1)
					(thickness 0.15)
				)
			)
		)
		(property "Current" ""
			(at 513.69 273.07 0)
			(layer "F.Fab")
			(hide yes)
			(effects
				(font
					(size 1 1)
					(thickness 0.15)
				)
			)
		)
		(property "License" "Apache-2.0"
			(at 513.69 273.07 0)
			(layer "F.Fab")
			(hide yes)
			(effects
				(font
					(size 1 1)
					(thickness 0.15)
				)
			)
		)
		(property "MPN" "BLM18AG601SN1D"
			(at 513.69 273.07 0)
			(layer "F.Fab")
			(hide yes)
			(effects
				(font
					(size 1 1)
					(thickness 0.15)
				)
			)
		)
		(property "Manufacturer" "Murata"
			(at 513.69 273.07 0)
			(layer "F.Fab")
			(hide yes)
			(effects
				(font
					(size 1 1)
					(thickness 0.15)
				)
			)
		)
		(property "Val" "600Z/0.5A"
			(at 513.69 273.07 0)
			(layer "F.Fab")
			(hide yes)
			(effects
				(font
					(size 1 1)
					(thickness 0.15)
				)
			)
		)
		(sheetname "USB PHY")
		(sheetfile "usb-phy.kicad_sch")
		(attr smd)
		(fp_line
			(start -0.15 0.4)
			(end 0.15 0.4)
			(stroke
				(width 0.15)
				(type solid)
			)
			(layer "F.SilkS")
		)
		(fp_line
			(start -0.15 -0.4)
			(end 0.15 -0.4)
			(stroke
				(width 0.15)
				(type solid)
			)
			(layer "F.SilkS")
		)
		(fp_rect
			(start -1.25 -0.65)
			(end 1.25 0.65)
			(stroke
				(width 0.05)
				(type solid)
			)
			(fill no)
			(layer "F.CrtYd")
		)
		(fp_line
			(start 0.8 0.406)
			(end -0.803 0.406)
			(stroke
				(width 0.15)
				(type solid)
			)
			(layer "F.Fab")
		)
		(fp_line
			(start 0.8 -0.408)
			(end 0.8 0.406)
			(stroke
				(width 0.15)
				(type solid)
			)
			(layer "F.Fab")
		)
		(fp_line
			(start 0.8 -0.408)
			(end -0.803 -0.408)
			(stroke
				(width 0.15)
				(type solid)
			)
			(layer "F.Fab")
		)
		(fp_line
			(start -0.803 0.406)
			(end -0.803 -0.408)
			(stroke
				(width 0.15)
				(type solid)
			)
			(layer "F.Fab")
		)
		(pad "1" smd roundrect
			(at -0.7 0 180)
			(size 0.8 1)
			(layers "F.Cu" "F.Mask" "F.Paste")
			(roundrect_rratio 0.2)
			(net 707 "/USB PHY/FTDI_3V3")
			(pintype "passive")
		)
		(pad "2" smd roundrect
			(at 0.7 0 180)
			(size 0.8 1)
			(layers "F.Cu" "F.Mask" "F.Paste")
			(roundrect_rratio 0.2)
			(net 714 "/USB PHY/FTDI_VPHY")
			(pintype "passive")
		)
	)
	(footprint "antmicro-footprints:ULS-12_5-D48N-C"
		(layer "F.Cu")
		(at 228 185.428 180)
		(property "Reference" "U8"
			(at -3.5 17.428 270)
			(layer "F.SilkS")
			(effects
				(font
					(size 0.7 0.7)
					(thickness 0.15)
				)
				(justify left bottom)
			)
		)
		(property "Value" "ULS-12_8.3-D48N-C"
			(at 0 20 180)
			(layer "F.Fab")
			(effects
				(font
					(size 0.7 0.7)
					(thickness 0.15)
				)
				(justify left bottom)
			)
		)
		(property "Description" "DC/DC converter"
			(at 0 0 180)
			(layer "F.Fab")
			(hide yes)
			(effects
				(font
					(size 1.27 1.27)
					(thickness 0.15)
				)
			)
		)
		(property "Author" "Antmicro"
			(at 456 370.856 0)
			(layer "F.Fab")
			(hide yes)
			(effects
				(font
					(size 1 1)
					(thickness 0.15)
				)
			)
		)
		(property "License" "Apache-2.0"
			(at 456 370.856 0)
			(layer "F.Fab")
			(hide yes)
			(effects
				(font
					(size 1 1)
					(thickness 0.15)
				)
			)
		)
		(property "MPN" "ULS-12/8.3-D48N-C"
			(at 456 370.856 0)
			(layer "F.Fab")
			(hide yes)
			(effects
				(font
					(size 1 1)
					(thickness 0.15)
				)
			)
		)
		(property "Manufacturer" "Murata"
			(at 456 370.856 0)
			(layer "F.Fab")
			(hide yes)
			(effects
				(font
					(size 1 1)
					(thickness 0.15)
				)
			)
		)
		(sheetname "Power supply")
		(sheetfile "power-supply.kicad_sch")
		(attr through_hole)
		(fp_line
			(start 30.499 18.818)
			(end -2.5 18.818)
			(stroke
				(width 0.15)
				(type solid)
			)
			(layer "F.SilkS")
		)
		(fp_line
			(start 30.499 -4.08)
			(end 30.499 18.818)
			(stroke
				(width 0.15)
				(type solid)
			)
			(layer "F.SilkS")
		)
		(fp_line
			(start -2.5 18.818)
			(end -2.5 -4.08)
			(stroke
				(width 0.15)
				(type solid)
			)
			(layer "F.SilkS")
		)
		(fp_line
			(start -2.5 -4.08)
			(end 30.499 -4.08)
			(stroke
				(width 0.15)
				(type solid)
			)
			(layer "F.SilkS")
		)
		(fp_circle
			(center -1.9 0)
			(end -1.85 0.05)
			(stroke
				(width 0.15)
				(type solid)
			)
			(fill yes)
			(layer "F.SilkS")
		)
		(fp_rect
			(start -3.507 -4.858)
			(end 31.513 20.002)
			(stroke
				(width 0.05)
				(type solid)
			)
			(fill no)
			(layer "F.CrtYd")
		)
		(fp_line
			(start 30.499 18.818)
			(end -2.5 18.818)
			(stroke
				(width 0.15)
				(type solid)
			)
			(layer "F.Fab")
		)
		(fp_line
			(start 30.499 -4.08)
			(end 30.499 18.818)
			(stroke
				(width 0.15)
				(type solid)
			)
			(layer "F.Fab")
		)
		(fp_line
			(start -0.1 -4.05)
			(end 30.499 -4.08)
			(stroke
				(width 0.15)
				(type solid)
			)
			(layer "F.Fab")
		)
		(fp_line
			(start -2.5 18.818)
			(end -2.5 -1.65)
			(stroke
				(width 0.15)
				(type solid)
			)
			(layer "F.Fab")
		)
		(fp_line
			(start -2.5 -1.65)
			(end -0.1 -4.05)
			(stroke
				(width 0.15)
				(type solid)
			)
			(layer "F.Fab")
		)
		(pad "1" thru_hole rect
			(at 0 0 180)
			(size 2.54 2.54)
			(drill 1.4)
			(layers "*.Cu" "*.Mask")
			(remove_unused_layers no)
			(net 698 "/Power supply/VDD")
			(pinfunction "VIN+")
			(pintype "power_in")
		)
		(pad "2" thru_hole circle
			(at 0 7.618 180)
			(size 2.54 2.54)
			(drill 1.4)
			(layers "*.Cu" "*.Mask")
			(remove_unused_layers no)
			(net 798 "/Power supply/POE_ACTIVE")
			(pinfunction "CTRL")
			(pintype "input")
		)
		(pad "3" thru_hole circle
			(at 0 15.239 180)
			(size 2.54 2.54)
			(drill 1.4)
			(layers "*.Cu" "*.Mask")
			(remove_unused_layers no)
			(net 699 "GNDD")
			(pinfunction "VIN-")
			(pintype "power_in")
		)
		(pad "4" thru_hole circle
			(at 27.938 15.239 180)
			(size 2.54 2.54)
			(drill 1.956)
			(layers "*.Cu" "*.Mask")
			(remove_unused_layers no)
			(net 1 "GND")
			(pinfunction "VOUT-")
			(pintype "power_out")
		)
		(pad "5" thru_hole circle
			(at 27.938 11.429 180)
			(size 2.54 2.54)
			(drill 1.4)
			(layers "*.Cu" "*.Mask")
			(remove_unused_layers no)
			(net 1 "GND")
			(pinfunction "SENSE-")
			(pintype "passive")
		)
		(pad "6" thru_hole circle
			(at 27.938 7.618 180)
			(size 2.54 2.54)
			(drill 1.4)
			(layers "*.Cu" "*.Mask")
			(remove_unused_layers no)
			(net 365 "Net-(U8-TRIM)")
			(pinfunction "TRIM")
			(pintype "input")
		)
		(pad "7" thru_hole circle
			(at 27.938 3.809 180)
			(size 2.54 2.54)
			(drill 1.4)
			(layers "*.Cu" "*.Mask")
			(remove_unused_layers no)
			(net 956 "/DC-DC Converters/POE_DC")
			(pinfunction "SENSE+")
			(pintype "passive")
		)
		(pad "8" thru_hole circle
			(at 27.938 0 180)
			(size 2.54 2.54)
			(drill 1.956)
			(layers "*.Cu" "*.Mask")
			(remove_unused_layers no)
			(net 956 "/DC-DC Converters/POE_DC")
			(pinfunction "VOUT+")
			(pintype "power_out")
		)
	)
	(footprint "antmicro-footprints:R_0402_1005Metric"
		(layer "F.Cu")
		(at 254.445 136.835 180)
		(descr "Resistor SMD 0402")
		(tags "resistor SMD 0402")
		(property "Reference" "R160"
			(at 1.395 4.835 180)
			(layer "F.SilkS")
			(effects
				(font
					(size 0.7 0.7)
					(thickness 0.15)
				)
				(justify left bottom)
			)
		)
		(property "Value" "R_12k_0402"
			(at 0 1.4 180)
			(layer "F.Fab")
			(effects
				(font
					(size 0.7 0.7)
					(thickness 0.15)
				)
				(justify left bottom)
			)
		)
		(property "Description" "SMD Chip Resistor, 12 kohm, ± 1%, 62.5 mW, 0402 [1005 Metric], Thick Film, General Purpose"
			(at 0 0 180)
			(layer "F.Fab")
			(hide yes)
			(effects
				(font
					(size 1.27 1.27)
					(thickness 0.15)
				)
			)
		)
		(property "Author" "Antmicro"
			(at 508.89 273.67 0)
			(layer "F.Fab")
			(hide yes)
			(effects
				(font
					(size 1 1)
					(thickness 0.15)
				)
			)
		)
		(property "License" "Apache-2.0"
			(at 508.89 273.67 0)
			(layer "F.Fab")
			(hide yes)
			(effects
				(font
					(size 1 1)
					(thickness 0.15)
				)
			)
		)
		(property "MPN" "CR0402-FX-1202GLF"
			(at 508.89 273.67 0)
			(layer "F.Fab")
			(hide yes)
			(effects
				(font
					(size 1 1)
					(thickness 0.15)
				)
			)
		)
		(property "Manufacturer" "Bourns"
			(at 508.89 273.67 0)
			(layer "F.Fab")
			(hide yes)
			(effects
				(font
					(size 1 1)
					(thickness 0.15)
				)
			)
		)
		(property "Tolerance" "1%"
			(at 508.89 273.67 0)
			(layer "F.Fab")
			(hide yes)
			(effects
				(font
					(size 1 1)
					(thickness 0.15)
				)
			)
		)
		(property "Val" "12k"
			(at 508.89 273.67 0)
			(layer "F.Fab")
			(hide yes)
			(effects
				(font
					(size 1 1)
					(thickness 0.15)
				)
			)
		)
		(sheetname "USB PHY")
		(sheetfile "usb-phy.kicad_sch")
		(attr smd)
		(fp_rect
			(start -0.925 -0.47)
			(end 0.925 0.47)
			(stroke
				(width 0.05)
				(type default)
			)
			(fill no)
			(layer "F.CrtYd")
		)
		(fp_rect
			(start -0.5 -0.25)
			(end 0.5 0.25)
			(stroke
				(width 0.15)
				(type solid)
			)
			(fill no)
			(layer "F.Fab")
		)
		(pad "1" smd roundrect
			(at -0.48 0 180)
			(size 0.59 0.64)
			(layers "F.Cu" "F.Mask" "F.Paste")
			(roundrect_rratio 0.25)
			(net 1 "GND")
			(pintype "passive")
		)
		(pad "2" smd roundrect
			(at 0.48 0 180)
			(size 0.59 0.64)
			(layers "F.Cu" "F.Mask" "F.Paste")
			(roundrect_rratio 0.25)
			(net 920 "/USB PHY/FTDI_REF")
			(pintype "passive")
		)
	)
	(footprint "antmicro-footprints:R_Array_4x0201_Panasonic_EXB18V"
		(layer "F.Cu")
		(at 245.9 144.302)
		(property "Reference" "R41"
			(at -11.7 -41.852 0)
			(layer "F.SilkS")
			(effects
				(font
					(size 0.7 0.7)
					(thickness 0.15)
				)
				(justify right bottom)
			)
		)
		(property "Value" "R_4x33R_0201_array"
			(at -1.1 1.8 0)
			(layer "F.Fab")
			(effects
				(font
					(size 0.7 0.7)
					(thickness 0.15)
				)
				(justify left bottom)
			)
		)
		(property "Description" "Fixed Network Resistor, 33 ohm, Isolated, 4 Resistors, 0502 [1406 Metric], Flat, ± 5%"
			(at 0 0 0)
			(layer "F.Fab")
			(hide yes)
			(effects
				(font
					(size 1.27 1.27)
					(thickness 0.15)
				)
			)
		)
		(property "Author" "Antmicro"
			(at 0 0 0)
			(layer "F.Fab")
			(hide yes)
			(effects
				(font
					(size 1 1)
					(thickness 0.15)
				)
			)
		)
		(property "License" "Apache-2.0"
			(at 0 0 0)
			(layer "F.Fab")
			(hide yes)
			(effects
				(font
					(size 1 1)
					(thickness 0.15)
				)
			)
		)
		(property "MPN" "EXB-18V330JX"
			(at 0 0 0)
			(layer "F.Fab")
			(hide yes)
			(effects
				(font
					(size 1 1)
					(thickness 0.15)
				)
			)
		)
		(property "Manufacturer" "Panasonic"
			(at 0 0 0)
			(layer "F.Fab")
			(hide yes)
			(effects
				(font
					(size 1 1)
					(thickness 0.15)
				)
			)
		)
		(property "Val" "R_4x33R_0201"
			(at 0 0 0)
			(layer "F.Fab")
			(hide yes)
			(effects
				(font
					(size 1 1)
					(thickness 0.15)
				)
			)
		)
		(sheetname "Supervisior MCU")
		(sheetfile "supervisor-mcu.kicad_sch")
		(attr smd)
		(fp_line
			(start -0.8 -0.45)
			(end -0.8 0.45)
			(stroke
				(width 0.12)
				(type solid)
			)
			(layer "F.SilkS")
		)
		(fp_line
			(start 0.8 -0.45)
			(end 0.8 0.45)
			(stroke
				(width 0.12)
				(type solid)
			)
			(layer "F.SilkS")
		)
		(fp_rect
			(start -0.898 -0.66)
			(end 0.898 0.65)
			(stroke
				(width 0.05)
				(type solid)
			)
			(fill no)
			(layer "F.CrtYd")
		)
		(pad "1" smd roundrect
			(at -0.6 0.298)
			(size 0.2 0.4)
			(layers "F.Cu" "F.Mask" "F.Paste")
			(roundrect_rratio 0.25)
			(net 1098 "/Supervisior MCU/USB_D1")
			(pinfunction "R1.1")
			(pintype "passive")
		)
		(pad "2" smd roundrect
			(at -0.202 0.298)
			(size 0.2 0.4)
			(layers "F.Cu" "F.Mask" "F.Paste")
			(roundrect_rratio 0.25)
			(net 1110 "/Supervisior MCU/USB_D4")
			(pinfunction "R2.1")
			(pintype "passive")
		)
		(pad "3" smd roundrect
			(at 0.2 0.298)
			(size 0.2 0.4)
			(layers "F.Cu" "F.Mask" "F.Paste")
			(roundrect_rratio 0.25)
			(net 1111 "/Supervisior MCU/USB_D5")
			(pinfunction "R3.1")
			(pintype "passive")
		)
		(pad "4" smd roundrect
			(at 0.598 0.298)
			(size 0.2 0.4)
			(layers "F.Cu" "F.Mask" "F.Paste")
			(roundrect_rratio 0.25)
			(net 1102 "/Supervisior MCU/SCL0")
			(pinfunction "R4.1")
			(pintype "passive")
		)
		(pad "5" smd roundrect
			(at 0.598 -0.3)
			(size 0.2 0.4)
			(layers "F.Cu" "F.Mask" "F.Paste")
			(roundrect_rratio 0.25)
			(net 1339 "/SUP_MCU.SCL")
			(pinfunction "R4.2")
			(pintype "passive")
		)
		(pad "6" smd roundrect
			(at 0.2 -0.3)
			(size 0.2 0.4)
			(layers "F.Cu" "F.Mask" "F.Paste")
			(roundrect_rratio 0.25)
			(net 1380 "/SUP_MCU.D5")
			(pinfunction "R3.2")
			(pintype "passive")
		)
		(pad "7" smd roundrect
			(at -0.202 -0.3)
			(size 0.2 0.4)
			(layers "F.Cu" "F.Mask" "F.Paste")
			(roundrect_rratio 0.25)
			(net 1381 "/SUP_MCU.D4")
			(pinfunction "R2.2")
			(pintype "passive")
		)
		(pad "8" smd roundrect
			(at -0.6 -0.3)
			(size 0.2 0.4)
			(layers "F.Cu" "F.Mask" "F.Paste")
			(roundrect_rratio 0.25)
			(net 1382 "/SUP_MCU.D1")
			(pinfunction "R1.2")
			(pintype "passive")
		)
	)
	(footprint "antmicro-footprints:R_0402_1005Metric"
		(layer "F.Cu")
		(at 203.653752 100.5365)
		(descr "Resistor SMD 0402")
		(tags "resistor SMD 0402")
		(property "Reference" "R242"
			(at 5.346248 8.2635 0)
			(layer "F.SilkS")
			(effects
				(font
					(size 0.7 0.7)
					(thickness 0.15)
				)
				(justify left bottom)
			)
		)
		(property "Value" "R_1M_0402"
			(at 0 1.4 0)
			(layer "F.Fab")
			(effects
				(font
					(size 0.7 0.7)
					(thickness 0.15)
				)
				(justify left bottom)
			)
		)
		(property "Description" "SMD Chip Resistor, 1 Mohm, ± 1%, 62.5 mW, 0402 [1005 Metric], Thick Film, General Purpose"
			(at 0 0 0)
			(layer "F.Fab")
			(hide yes)
			(effects
				(font
					(size 1.27 1.27)
					(thickness 0.15)
				)
			)
		)
		(property "Author" "Antmicro"
			(at 0 0 0)
			(layer "F.Fab")
			(hide yes)
			(effects
				(font
					(size 1 1)
					(thickness 0.15)
				)
			)
		)
		(property "License" "Apache-2.0"
			(at 0 0 0)
			(layer "F.Fab")
			(hide yes)
			(effects
				(font
					(size 1 1)
					(thickness 0.15)
				)
			)
		)
		(property "MPN" "CR0402-FX-1004GLF"
			(at 0 0 0)
			(layer "F.Fab")
			(hide yes)
			(effects
				(font
					(size 1 1)
					(thickness 0.15)
				)
			)
		)
		(property "Manufacturer" "Bourns"
			(at 0 0 0)
			(layer "F.Fab")
			(hide yes)
			(effects
				(font
					(size 1 1)
					(thickness 0.15)
				)
			)
		)
		(property "Tolerance" "1%"
			(at 0 0 0)
			(layer "F.Fab")
			(hide yes)
			(effects
				(font
					(size 1 1)
					(thickness 0.15)
				)
			)
		)
		(property "Val" "1M"
			(at 0 0 0)
			(layer "F.Fab")
			(hide yes)
			(effects
				(font
					(size 1 1)
					(thickness 0.15)
				)
			)
		)
		(sheetname "HDMI + Ethernet")
		(sheetfile "hdmi-ethernet.kicad_sch")
		(attr smd)
		(fp_rect
			(start -0.925 -0.47)
			(end 0.925 0.47)
			(stroke
				(width 0.05)
				(type default)
			)
			(fill no)
			(layer "F.CrtYd")
		)
		(fp_rect
			(start -0.5 -0.25)
			(end 0.5 0.25)
			(stroke
				(width 0.15)
				(type solid)
			)
			(fill no)
			(layer "F.Fab")
		)
		(pad "1" smd roundrect
			(at -0.48 0)
			(size 0.59 0.64)
			(layers "F.Cu" "F.Mask" "F.Paste")
			(roundrect_rratio 0.25)
			(net 720 "/HDMI + Ethernet/GBE_XO")
			(pintype "passive")
		)
		(pad "2" smd roundrect
			(at 0.48 0)
			(size 0.59 0.64)
			(layers "F.Cu" "F.Mask" "F.Paste")
			(roundrect_rratio 0.25)
			(net 718 "/HDMI + Ethernet/GBE_XI")
			(pintype "passive")
		)
	)
	(footprint "antmicro-footprints:PinHeader_2x10_P1.27mm_SMD_Shrouded"
		(layer "F.Cu")
		(at 190.000001 82.288501)
		(property "Reference" "J10"
			(at -9.700001 3.711499 0)
			(layer "F.SilkS")
			(effects
				(font
					(size 0.7 0.7)
					(thickness 0.15)
				)
				(justify left bottom)
			)
		)
		(property "Value" "PinHeader_2x10_P1.27mm_SMD_Shrouded"
			(at -3.65 0.37 0)
			(layer "F.Fab")
			(effects
				(font
					(size 0.7 0.7)
					(thickness 0.15)
				)
				(justify left bottom)
			)
		)
		(property "Description" "Pin Header, Wire-to-Board, 1.27 mm, 2 Rows, 20 Contacts, Surface Mount Straight, WR-BHD"
			(at 0 0 0)
			(layer "F.Fab")
			(hide yes)
			(effects
				(font
					(size 1.27 1.27)
					(thickness 0.15)
				)
			)
		)
		(property "Author" "Antmicro"
			(at 0 0 0)
			(layer "F.Fab")
			(hide yes)
			(effects
				(font
					(size 1 1)
					(thickness 0.15)
				)
			)
		)
		(property "License" "Apache-2.0"
			(at 0 0 0)
			(layer "F.Fab")
			(hide yes)
			(effects
				(font
					(size 1 1)
					(thickness 0.15)
				)
			)
		)
		(property "MPN" "62732020621"
			(at 0 0 0)
			(layer "F.Fab")
			(hide yes)
			(effects
				(font
					(size 1 1)
					(thickness 0.15)
				)
			)
		)
		(property "Manufacturer" "Würth Elektronik"
			(at 0 0 0)
			(layer "F.Fab")
			(hide yes)
			(effects
				(font
					(size 1 1)
					(thickness 0.15)
				)
			)
		)
		(sheetname "User GPIO + LED + button + DIP switch")
		(sheetfile "user-gpio.kicad_sch")
		(attr smd)
		(fp_line
			(start -9.6 -2.601)
			(end -9.6 2.6)
			(stroke
				(width 0.15)
				(type solid)
			)
			(layer "F.SilkS")
		)
		(fp_line
			(start -9.6 -2.601)
			(end -6.3 -2.601)
			(stroke
				(width 0.15)
				(type solid)
			)
			(layer "F.SilkS")
		)
		(fp_line
			(start -9.6 2.6)
			(end -6.3 2.6)
			(stroke
				(width 0.15)
				(type solid)
			)
			(layer "F.SilkS")
		)
		(fp_line
			(start 6.299 -2.601)
			(end 9.598 -2.601)
			(stroke
				(width 0.15)
				(type solid)
			)
			(layer "F.SilkS")
		)
		(fp_line
			(start 6.299 2.6)
			(end 9.598 2.6)
			(stroke
				(width 0.15)
				(type solid)
			)
			(layer "F.SilkS")
		)
		(fp_line
			(start 9.598 -2.601)
			(end 9.598 2.6)
			(stroke
				(width 0.15)
				(type solid)
			)
			(layer "F.SilkS")
		)
		(fp_circle
			(center -6.4 3.01)
			(end -6.35 3.01)
			(stroke
				(width 0.15)
				(type solid)
			)
			(fill yes)
			(layer "F.SilkS")
		)
		(fp_rect
			(start -9.9 -3.5)
			(end 9.91 3.5)
			(stroke
				(width 0.05)
				(type solid)
			)
			(fill no)
			(layer "F.CrtYd")
		)
		(fp_line
			(start -9.51 2.59)
			(end -9.31 2.79)
			(stroke
				(width 0.15)
				(type solid)
			)
			(layer "F.Fab")
		)
		(fp_rect
			(start -9.526 -2.806)
			(end 9.525 2.805)
			(stroke
				(width 0.15)
				(type solid)
			)
			(fill no)
			(layer "F.Fab")
		)
		(pad "1" smd rect
			(at -5.715 1.999)
			(size 0.74 2.8)
			(layers "F.Cu" "F.Mask" "F.Paste")
			(net 820 "unconnected-(J10-Pad1)")
			(pintype "passive+no_connect")
		)
		(pad "2" smd rect
			(at -5.715 -2)
			(size 0.74 2.8)
			(layers "F.Cu" "F.Mask" "F.Paste")
			(net 1 "GND")
			(pintype "passive")
		)
		(pad "3" smd rect
			(at -4.446 1.999)
			(size 0.74 2.8)
			(layers "F.Cu" "F.Mask" "F.Paste")
			(net 821 "unconnected-(J10-Pad3)")
			(pintype "passive+no_connect")
		)
		(pad "4" smd rect
			(at -4.446 -2)
			(size 0.74 2.8)
			(layers "F.Cu" "F.Mask" "F.Paste")
			(net 822 "/User GPIO + LED + button + DIP switch/CW_20PIN_HS1")
			(pintype "passive")
		)
		(pad "5" smd rect
			(at -3.177 1.999)
			(size 0.74 2.8)
			(layers "F.Cu" "F.Mask" "F.Paste")
			(net 823 "/User GPIO + LED + button + DIP switch/CW_20PIN_RST")
			(pintype "passive")
		)
		(pad "6" smd rect
			(at -3.177 -2)
			(size 0.74 2.8)
			(layers "F.Cu" "F.Mask" "F.Paste")
			(net 824 "/User GPIO + LED + button + DIP switch/CW_20PIN_HS2")
			(pintype "passive")
		)
		(pad "7" smd rect
			(at -1.905 1.999)
			(size 0.74 2.8)
			(layers "F.Cu" "F.Mask" "F.Paste")
			(net 825 "/User GPIO + LED + button + DIP switch/CW_20PIN_MISO")
			(pintype "passive")
		)
		(pad "8" smd rect
			(at -1.905 -2)
			(size 0.74 2.8)
			(layers "F.Cu" "F.Mask" "F.Paste")
			(net 24 "+3V3")
			(pintype "passive")
		)
		(pad "9" smd rect
			(at -0.635 1.999)
			(size 0.74 2.8)
			(layers "F.Cu" "F.Mask" "F.Paste")
			(net 826 "/User GPIO + LED + button + DIP switch/CW_20PIN_MOSI")
			(pintype "passive")
		)
		(pad "10" smd rect
			(at -0.635 -2)
			(size 0.74 2.8)
			(layers "F.Cu" "F.Mask" "F.Paste")
			(net 827 "/User GPIO + LED + button + DIP switch/CW_20PIN_IO1")
			(pintype "passive")
		)
		(pad "11" smd rect
			(at 0.631 1.999)
			(size 0.74 2.8)
			(layers "F.Cu" "F.Mask" "F.Paste")
			(net 828 "/User GPIO + LED + button + DIP switch/CW_20PIN_TSCK")
			(pintype "passive")
		)
		(pad "12" smd rect
			(at 0.631 -2)
			(size 0.74 2.8)
			(layers "F.Cu" "F.Mask" "F.Paste")
			(net 829 "/User GPIO + LED + button + DIP switch/CW_20PIN_IO2")
			(pintype "passive")
		)
		(pad "13" smd rect
			(at 1.902 1.999)
			(size 0.74 2.8)
			(layers "F.Cu" "F.Mask" "F.Paste")
			(net 830 "/User GPIO + LED + button + DIP switch/CW_20PIN_TPDIC")
			(pintype "passive")
		)
		(pad "14" smd rect
			(at 1.902 -2)
			(size 0.74 2.8)
			(layers "F.Cu" "F.Mask" "F.Paste")
			(net 831 "/User GPIO + LED + button + DIP switch/CW_20PIN_IO3")
			(pintype "passive")
		)
		(pad "15" smd rect
			(at 3.172 1.999)
			(size 0.74 2.8)
			(layers "F.Cu" "F.Mask" "F.Paste")
			(net 832 "/User GPIO + LED + button + DIP switch/CW_20PIN_TPDID")
			(pintype "passive")
		)
		(pad "16" smd rect
			(at 3.172 -2)
			(size 0.74 2.8)
			(layers "F.Cu" "F.Mask" "F.Paste")
			(net 1145 "/User GPIO + LED + button + DIP switch/CW_20PIN_IO4")
			(pintype "passive")
		)
		(pad "17" smd rect
			(at 4.445 1.999)
			(size 0.74 2.8)
			(layers "F.Cu" "F.Mask" "F.Paste")
			(net 1 "GND")
			(pintype "passive")
		)
		(pad "18" smd rect
			(at 4.445 -2)
			(size 0.74 2.8)
			(layers "F.Cu" "F.Mask" "F.Paste")
			(net 833 "unconnected-(J10-Pad18)")
			(pintype "passive+no_connect")
		)
		(pad "19" smd rect
			(at 5.714 1.999)
			(size 0.74 2.8)
			(layers "F.Cu" "F.Mask" "F.Paste")
			(net 1 "GND")
			(pintype "passive")
		)
		(pad "20" smd rect
			(at 5.714 -2)
			(size 0.74 2.8)
			(layers "F.Cu" "F.Mask" "F.Paste")
			(net 834 "unconnected-(J10-Pad20)")
			(pintype "passive+no_connect")
		)
	)
	(footprint "antmicro-footprints:C_0603_1608Metric"
		(layer "F.Cu")
		(at 154.0125 172.7 -90)
		(descr "Capacitor SMD 0603")
		(tags "capacitor 0603")
		(property "Reference" "C329"
			(at -1.025 -0.1125 315)
			(unlocked yes)
			(layer "F.SilkS")
			(effects
				(font
					(size 0.7 0.7)
					(thickness 0.15)
				)
				(justify right bottom)
			)
		)
		(property "Value" "C_22u_0603"
			(at 0 1.6 90)
			(layer "F.Fab")
			(effects
				(font
					(size 0.7 0.7)
					(thickness 0.15)
				)
				(justify right bottom)
			)
		)
		(property "Description" "SMD Multilayer Ceramic Capacitor, 22 µF, 6.3 V, 0603 [1608 Metric], ± 20%, X5R, GRM Series"
			(at 0 0 270)
			(layer "F.Fab")
			(hide yes)
			(effects
				(font
					(size 1.27 1.27)
					(thickness 0.15)
				)
			)
		)
		(property "Author" "Antmicro"
			(at -18.6875 326.7125 0)
			(layer "F.Fab")
			(hide yes)
			(effects
				(font
					(size 1 1)
					(thickness 0.15)
				)
			)
		)
		(property "Dielectric" ""
			(at -18.6875 326.7125 0)
			(layer "F.Fab")
			(hide yes)
			(effects
				(font
					(size 1 1)
					(thickness 0.15)
				)
			)
		)
		(property "License" "Apache-2.0"
			(at -18.6875 326.7125 0)
			(layer "F.Fab")
			(hide yes)
			(effects
				(font
					(size 1 1)
					(thickness 0.15)
				)
			)
		)
		(property "MPN" "GRM188R60J226MEA0D"
			(at -18.6875 326.7125 0)
			(layer "F.Fab")
			(hide yes)
			(effects
				(font
					(size 1 1)
					(thickness 0.15)
				)
			)
		)
		(property "Manufacturer" "Murata"
			(at -18.6875 326.7125 0)
			(layer "F.Fab")
			(hide yes)
			(effects
				(font
					(size 1 1)
					(thickness 0.15)
				)
			)
		)
		(property "Val" "22u"
			(at -18.6875 326.7125 0)
			(layer "F.Fab")
			(hide yes)
			(effects
				(font
					(size 1 1)
					(thickness 0.15)
				)
			)
		)
		(property "Voltage" ""
			(at -18.6875 326.7125 0)
			(layer "F.Fab")
			(hide yes)
			(effects
				(font
					(size 1 1)
					(thickness 0.15)
				)
			)
		)
		(sheetname "DC-DC Converters")
		(sheetfile "dc-dc.kicad_sch")
		(attr smd)
		(fp_line
			(start -0.15 0.4)
			(end 0.15 0.4)
			(stroke
				(width 0.15)
				(type solid)
			)
			(layer "F.SilkS")
		)
		(fp_line
			(start -0.15 -0.4)
			(end 0.15 -0.4)
			(stroke
				(width 0.15)
				(type solid)
			)
			(layer "F.SilkS")
		)
		(fp_rect
			(start -1.25 -0.65)
			(end 1.25 0.65)
			(stroke
				(width 0.05)
				(type solid)
			)
			(fill no)
			(layer "F.CrtYd")
		)
		(fp_rect
			(start -0.8 -0.4)
			(end 0.8 0.4)
			(stroke
				(width 0.15)
				(type solid)
			)
			(fill no)
			(layer "F.Fab")
		)
		(pad "1" smd roundrect
			(at -0.7 0 270)
			(size 0.8 1)
			(layers "F.Cu" "F.Mask" "F.Paste")
			(roundrect_rratio 0.2)
			(net 1 "GND")
			(pintype "passive")
		)
		(pad "2" smd roundrect
			(at 0.7 0 270)
			(size 0.8 1)
			(layers "F.Cu" "F.Mask" "F.Paste")
			(roundrect_rratio 0.2)
			(net 738 "/DC-DC Converters/1V7_local")
			(pintype "passive")
		)
	)
	(footprint "antmicro-footprints:C_0402_1005Metric"
		(layer "F.Cu")
		(at 219.2 139.975 180)
		(descr "Capacitor SMD 0402")
		(tags "capacitor SMD 0402")
		(property "Reference" "C373"
			(at 0.8 -0.375 0)
			(layer "F.SilkS")
			(effects
				(font
					(size 0.7 0.7)
					(thickness 0.15)
				)
				(justify right bottom)
			)
		)
		(property "Value" "C_10u_0402"
			(at 0 1.4 0)
			(layer "F.Fab")
			(effects
				(font
					(size 0.7 0.7)
					(thickness 0.15)
				)
				(justify right bottom)
			)
		)
		(property "Description" "SMD Multilayer Ceramic Capacitor, 10 µF, 6.3 V, 0402 [1005 Metric], ± 20%, X5R, CC Series"
			(at 0 0 180)
			(layer "F.Fab")
			(hide yes)
			(effects
				(font
					(size 1.27 1.27)
					(thickness 0.15)
				)
			)
		)
		(property "Author" "Antmicro"
			(at 438.4 279.95 0)
			(layer "F.Fab")
			(hide yes)
			(effects
				(font
					(size 1 1)
					(thickness 0.15)
				)
			)
		)
		(property "Dielectric" ""
			(at 438.4 279.95 0)
			(layer "F.Fab")
			(hide yes)
			(effects
				(font
					(size 1 1)
					(thickness 0.15)
				)
			)
		)
		(property "License" "Apache-2.0"
			(at 438.4 279.95 0)
			(layer "F.Fab")
			(hide yes)
			(effects
				(font
					(size 1 1)
					(thickness 0.15)
				)
			)
		)
		(property "MPN" "CC0402MRX5R5BB106"
			(at 438.4 279.95 0)
			(layer "F.Fab")
			(hide yes)
			(effects
				(font
					(size 1 1)
					(thickness 0.15)
				)
			)
		)
		(property "Manufacturer" "YAGEO"
			(at 438.4 279.95 0)
			(layer "F.Fab")
			(hide yes)
			(effects
				(font
					(size 1 1)
					(thickness 0.15)
				)
			)
		)
		(property "Val" "10u"
			(at 438.4 279.95 0)
			(layer "F.Fab")
			(hide yes)
			(effects
				(font
					(size 1 1)
					(thickness 0.15)
				)
			)
		)
		(property "Voltage" ""
			(at 438.4 279.95 0)
			(layer "F.Fab")
			(hide yes)
			(effects
				(font
					(size 1 1)
					(thickness 0.15)
				)
			)
		)
		(sheetname "Clocks")
		(sheetfile "clocks.kicad_sch")
		(attr smd)
		(fp_rect
			(start -0.925 -0.47)
			(end 0.925 0.47)
			(stroke
				(width 0.05)
				(type default)
			)
			(fill no)
			(layer "F.CrtYd")
		)
		(fp_line
			(start 0.504 0.248)
			(end -0.494 0.248)
			(stroke
				(width 0.15)
				(type solid)
			)
			(layer "F.Fab")
		)
		(fp_line
			(start 0.504 -0.25)
			(end 0.504 0.248)
			(stroke
				(width 0.15)
				(type solid)
			)
			(layer "F.Fab")
		)
		(fp_line
			(start -0.494 0.248)
			(end -0.494 -0.25)
			(stroke
				(width 0.15)
				(type solid)
			)
			(layer "F.Fab")
		)
		(fp_line
			(start -0.494 -0.25)
			(end 0.504 -0.25)
			(stroke
				(width 0.15)
				(type solid)
			)
			(layer "F.Fab")
		)
		(pad "1" smd roundrect
			(at -0.48 0 180)
			(size 0.59 0.64)
			(layers "F.Cu" "F.Mask" "F.Paste")
			(roundrect_rratio 0.25)
			(net 1 "GND")
			(pintype "passive")
		)
		(pad "2" smd roundrect
			(at 0.48 0 180)
			(size 0.59 0.64)
			(layers "F.Cu" "F.Mask" "F.Paste")
			(roundrect_rratio 0.25)
			(net 24 "+3V3")
			(pintype "passive")
		)
	)
	(footprint "antmicro-footprints:C_0402_1005Metric"
		(layer "F.Cu")
		(at 173.570001 123.970001 180)
		(descr "Capacitor SMD 0402")
		(tags "capacitor SMD 0402")
		(property "Reference" "C306"
			(at -3.729999 -0.329999 0)
			(layer "F.SilkS")
			(effects
				(font
					(size 0.7 0.7)
					(thickness 0.15)
				)
				(justify right bottom)
			)
		)
		(property "Value" "C_100n_0402"
			(at 0 1.4 0)
			(layer "F.Fab")
			(effects
				(font
					(size 0.7 0.7)
					(thickness 0.15)
				)
				(justify right bottom)
			)
		)
		(property "Description" "SMD Multilayer Ceramic Capacitor, 0.1 µF, 50 V, 0402 [1005 Metric], ± 10%, X5R, GRM Series"
			(at 0 0 180)
			(layer "F.Fab")
			(hide yes)
			(effects
				(font
					(size 1.27 1.27)
					(thickness 0.15)
				)
			)
		)
		(property "Author" "Antmicro"
			(at 347.140002 247.940002 0)
			(layer "F.Fab")
			(hide yes)
			(effects
				(font
					(size 1 1)
					(thickness 0.15)
				)
			)
		)
		(property "Dielectric" "X5R"
			(at 347.140002 247.940002 0)
			(layer "F.Fab")
			(hide yes)
			(effects
				(font
					(size 1 1)
					(thickness 0.15)
				)
			)
		)
		(property "License" "Apache-2.0"
			(at 347.140002 247.940002 0)
			(layer "F.Fab")
			(hide yes)
			(effects
				(font
					(size 1 1)
					(thickness 0.15)
				)
			)
		)
		(property "MPN" "GRM155R61H104KE14D"
			(at 347.140002 247.940002 0)
			(layer "F.Fab")
			(hide yes)
			(effects
				(font
					(size 1 1)
					(thickness 0.15)
				)
			)
		)
		(property "Manufacturer" "Murata"
			(at 347.140002 247.940002 0)
			(layer "F.Fab")
			(hide yes)
			(effects
				(font
					(size 1 1)
					(thickness 0.15)
				)
			)
		)
		(property "Val" "100n"
			(at 347.140002 247.940002 0)
			(layer "F.Fab")
			(hide yes)
			(effects
				(font
					(size 1 1)
					(thickness 0.15)
				)
			)
		)
		(property "Voltage" "50V"
			(at 347.140002 247.940002 0)
			(layer "F.Fab")
			(hide yes)
			(effects
				(font
					(size 1 1)
					(thickness 0.15)
				)
			)
		)
		(sheetname "FMC+ HSPC")
		(sheetfile "fmc-hspc.kicad_sch")
		(attr smd)
		(fp_rect
			(start -0.925 -0.47)
			(end 0.925 0.47)
			(stroke
				(width 0.05)
				(type default)
			)
			(fill no)
			(layer "F.CrtYd")
		)
		(fp_line
			(start 0.504 0.248)
			(end -0.494 0.248)
			(stroke
				(width 0.15)
				(type solid)
			)
			(layer "F.Fab")
		)
		(fp_line
			(start 0.504 -0.25)
			(end 0.504 0.248)
			(stroke
				(width 0.15)
				(type solid)
			)
			(layer "F.Fab")
		)
		(fp_line
			(start -0.494 0.248)
			(end -0.494 -0.25)
			(stroke
				(width 0.15)
				(type solid)
			)
			(layer "F.Fab")
		)
		(fp_line
			(start -0.494 -0.25)
			(end 0.504 -0.25)
			(stroke
				(width 0.15)
				(type solid)
			)
			(layer "F.Fab")
		)
		(pad "1" smd roundrect
			(at -0.48 0 180)
			(size 0.59 0.64)
			(layers "F.Cu" "F.Mask" "F.Paste")
			(roundrect_rratio 0.25)
			(net 87 "/FMC+ HSPC/GTX115.TX3_P")
			(pintype "passive")
		)
		(pad "2" smd roundrect
			(at 0.48 0 180)
			(size 0.59 0.64)
			(layers "F.Cu" "F.Mask" "F.Paste")
			(roundrect_rratio 0.25)
			(net 83 "/FMC+ HSPC/GTX_TX4_C_P")
			(pintype "passive")
		)
	)
	(footprint "antmicro-footprints:C_0402_1005Metric"
		(layer "F.Cu")
		(at 201.703752 101.9115)
		(descr "Capacitor SMD 0402")
		(tags "capacitor SMD 0402")
		(property "Reference" "C293"
			(at 4.296248 8.1885 0)
			(layer "F.SilkS")
			(effects
				(font
					(size 0.7 0.7)
					(thickness 0.15)
				)
				(justify left bottom)
			)
		)
		(property "Value" "C_10u_0402"
			(at 0 1.4 0)
			(layer "F.Fab")
			(effects
				(font
					(size 0.7 0.7)
					(thickness 0.15)
				)
				(justify left bottom)
			)
		)
		(property "Description" "SMD Multilayer Ceramic Capacitor, 10 µF, 6.3 V, 0402 [1005 Metric], ± 20%, X5R, CC Series"
			(at 0 0 0)
			(layer "F.Fab")
			(hide yes)
			(effects
				(font
					(size 1.27 1.27)
					(thickness 0.15)
				)
			)
		)
		(property "Author" "Antmicro"
			(at 0 0 0)
			(layer "F.Fab")
			(hide yes)
			(effects
				(font
					(size 1 1)
					(thickness 0.15)
				)
			)
		)
		(property "Dielectric" ""
			(at 0 0 0)
			(layer "F.Fab")
			(hide yes)
			(effects
				(font
					(size 1 1)
					(thickness 0.15)
				)
			)
		)
		(property "License" "Apache-2.0"
			(at 0 0 0)
			(layer "F.Fab")
			(hide yes)
			(effects
				(font
					(size 1 1)
					(thickness 0.15)
				)
			)
		)
		(property "MPN" "CC0402MRX5R5BB106"
			(at 0 0 0)
			(layer "F.Fab")
			(hide yes)
			(effects
				(font
					(size 1 1)
					(thickness 0.15)
				)
			)
		)
		(property "Manufacturer" "YAGEO"
			(at 0 0 0)
			(layer "F.Fab")
			(hide yes)
			(effects
				(font
					(size 1 1)
					(thickness 0.15)
				)
			)
		)
		(property "Val" "10u"
			(at 0 0 0)
			(layer "F.Fab")
			(hide yes)
			(effects
				(font
					(size 1 1)
					(thickness 0.15)
				)
			)
		)
		(property "Voltage" ""
			(at 0 0 0)
			(layer "F.Fab")
			(hide yes)
			(effects
				(font
					(size 1 1)
					(thickness 0.15)
				)
			)
		)
		(sheetname "HDMI + Ethernet")
		(sheetfile "hdmi-ethernet.kicad_sch")
		(attr smd)
		(fp_rect
			(start -0.925 -0.47)
			(end 0.925 0.47)
			(stroke
				(width 0.05)
				(type default)
			)
			(fill no)
			(layer "F.CrtYd")
		)
		(fp_line
			(start -0.494 -0.25)
			(end 0.504 -0.25)
			(stroke
				(width 0.15)
				(type solid)
			)
			(layer "F.Fab")
		)
		(fp_line
			(start -0.494 0.248)
			(end -0.494 -0.25)
			(stroke
				(width 0.15)
				(type solid)
			)
			(layer "F.Fab")
		)
		(fp_line
			(start 0.504 -0.25)
			(end 0.504 0.248)
			(stroke
				(width 0.15)
				(type solid)
			)
			(layer "F.Fab")
		)
		(fp_line
			(start 0.504 0.248)
			(end -0.494 0.248)
			(stroke
				(width 0.15)
				(type solid)
			)
			(layer "F.Fab")
		)
		(pad "1" smd roundrect
			(at -0.48 0)
			(size 0.59 0.64)
			(layers "F.Cu" "F.Mask" "F.Paste")
			(roundrect_rratio 0.25)
			(net 1 "GND")
			(pintype "passive")
		)
		(pad "2" smd roundrect
			(at 0.48 0)
			(size 0.59 0.64)
			(layers "F.Cu" "F.Mask" "F.Paste")
			(roundrect_rratio 0.25)
			(net 728 "/HDMI + Ethernet/GBE_AVDDL{slash}PLL")
			(pintype "passive")
		)
	)
	(footprint "antmicro-footprints:DHVQFN-14-1EP_2.5x3mm"
		(layer "F.Cu")
		(at 239.25 144.7 180)
		(property "Reference" "U23"
			(at -2.6 -0.45 270)
			(layer "F.SilkS")
			(effects
				(font
					(size 0.7 0.7)
					(thickness 0.15)
				)
				(justify left bottom)
			)
		)
		(property "Value" "TXU0304BQAR"
			(at 0 2.898 180)
			(layer "F.Fab")
			(effects
				(font
					(size 0.7 0.7)
					(thickness 0.15)
				)
				(justify left bottom)
			)
		)
		(property "Description" "Logic translator/level shifter"
			(at 0 0 180)
			(layer "F.Fab")
			(hide yes)
			(effects
				(font
					(size 1.27 1.27)
					(thickness 0.15)
				)
			)
		)
		(property "Author" "Antmicro"
			(at 478.5 289.4 0)
			(layer "F.Fab")
			(hide yes)
			(effects
				(font
					(size 1 1)
					(thickness 0.15)
				)
			)
		)
		(property "License" "Apache-2.0"
			(at 478.5 289.4 0)
			(layer "F.Fab")
			(hide yes)
			(effects
				(font
					(size 1 1)
					(thickness 0.15)
				)
			)
		)
		(property "MPN" "TXU0304BQAR"
			(at 478.5 289.4 0)
			(layer "F.Fab")
			(hide yes)
			(effects
				(font
					(size 1 1)
					(thickness 0.15)
				)
			)
		)
		(property "Manufacturer" "Texas Instruments"
			(at 478.5 289.4 0)
			(layer "F.Fab")
			(hide yes)
			(effects
				(font
					(size 1 1)
					(thickness 0.15)
				)
			)
		)
		(sheetname "USB PHY")
		(sheetfile "usb-phy.kicad_sch")
		(attr smd)
		(fp_line
			(start 1.35 1.6)
			(end 1.35 1.249)
			(stroke
				(width 0.15)
				(type solid)
			)
			(layer "F.SilkS")
		)
		(fp_line
			(start 1.35 -1.601)
			(end 1.35 -1.25)
			(stroke
				(width 0.15)
				(type solid)
			)
			(layer "F.SilkS")
		)
		(fp_line
			(start 1.35 -1.601)
			(end 0.494 -1.601)
			(stroke
				(width 0.15)
				(type solid)
			)
			(layer "F.SilkS")
		)
		(fp_line
			(start 0.494 1.6)
			(end 1.35 1.6)
			(stroke
				(width 0.15)
				(type solid)
			)
			(layer "F.SilkS")
		)
		(fp_line
			(start -1.35 -1.601)
			(end -1.35 -1.25)
			(stroke
				(width 0.15)
				(type solid)
			)
			(layer "F.SilkS")
		)
		(fp_line
			(start -1.351 1.6)
			(end -0.5 1.6)
			(stroke
				(width 0.15)
				(type solid)
			)
			(layer "F.SilkS")
		)
		(fp_line
			(start -1.351 1.6)
			(end -1.351 1.249)
			(stroke
				(width 0.15)
				(type solid)
			)
			(layer "F.SilkS")
		)
		(fp_line
			(start -1.351 -1.601)
			(end -0.5 -1.601)
			(stroke
				(width 0.15)
				(type solid)
			)
			(layer "F.SilkS")
		)
		(fp_circle
			(center -0.7 -1.85)
			(end -0.653 -1.85)
			(stroke
				(width 0.15)
				(type solid)
			)
			(fill yes)
			(layer "F.SilkS")
		)
		(fp_rect
			(start -1.85 -2)
			(end 1.8 1.95)
			(stroke
				(width 0.05)
				(type solid)
			)
			(fill no)
			(layer "F.CrtYd")
		)
		(fp_line
			(start 1.249 1.499)
			(end -1.25 1.499)
			(stroke
				(width 0.15)
				(type solid)
			)
			(layer "F.Fab")
		)
		(fp_line
			(start 1.249 -1.5)
			(end 1.249 1.499)
			(stroke
				(width 0.15)
				(type solid)
			)
			(layer "F.Fab")
		)
		(fp_line
			(start -1 -1.5)
			(end 1.249 -1.5)
			(stroke
				(width 0.15)
				(type solid)
			)
			(layer "F.Fab")
		)
		(fp_line
			(start -1.25 1.499)
			(end -1.25 -1.25)
			(stroke
				(width 0.15)
				(type solid)
			)
			(layer "F.Fab")
		)
		(fp_line
			(start -1.25 -1.25)
			(end -1 -1.5)
			(stroke
				(width 0.15)
				(type solid)
			)
			(layer "F.Fab")
		)
		(pad "1" smd oval
			(at -0.25 -1.5 180)
			(size 0.3 0.8)
			(layers "F.Cu" "F.Mask" "F.Paste")
			(net 707 "/USB PHY/FTDI_3V3")
			(pinfunction "VCCA")
			(pintype "power_in")
		)
		(pad "2" smd oval
			(at -1.25 -1 270)
			(size 0.3 0.8)
			(layers "F.Cu" "F.Mask" "F.Paste")
			(net 1023 "/USB PHY/BDBUS0")
			(pinfunction "A1")
			(pintype "input")
		)
		(pad "3" smd oval
			(at -1.25 -0.5 270)
			(size 0.3 0.8)
			(layers "F.Cu" "F.Mask" "F.Paste")
			(net 1024 "/USB PHY/BDBUS1")
			(pinfunction "A2")
			(pintype "input")
		)
		(pad "4" smd oval
			(at -1.25 0 270)
			(size 0.3 0.8)
			(layers "F.Cu" "F.Mask" "F.Paste")
			(net 925 "/USB PHY/BDBUS3")
			(pinfunction "A3")
			(pintype "input")
		)
		(pad "5" smd oval
			(at -1.25 0.494 270)
			(size 0.3 0.8)
			(layers "F.Cu" "F.Mask" "F.Paste")
			(net 1025 "/USB PHY/BDBUS2")
			(pinfunction "A4Y")
			(pintype "output")
		)
		(pad "6" smd oval
			(at -1.25 0.994 270)
			(size 0.3 0.8)
			(layers "F.Cu" "F.Mask" "F.Paste")
			(net 1208 "unconnected-(U23-NC-Pad6)")
			(pinfunction "NC")
			(pintype "no_connect")
		)
		(pad "7" smd oval
			(at -0.25 1.499 180)
			(size 0.3 0.8)
			(layers "F.Cu" "F.Mask" "F.Paste")
			(net 1 "GND")
			(pinfunction "GND")
			(pintype "passive")
		)
		(pad "8" smd oval
			(at 0.244 1.499 180)
			(size 0.3 0.8)
			(layers "F.Cu" "F.Mask" "F.Paste")
			(net 372 "Net-(U23-OE)")
			(pinfunction "OE")
			(pintype "tri_state")
		)
		(pad "9" smd oval
			(at 1.249 0.994 270)
			(size 0.3 0.8)
			(layers "F.Cu" "F.Mask" "F.Paste")
			(net 1229 "unconnected-(U23-NC-Pad9)")
			(pinfunction "NC")
			(pintype "no_connect")
		)
		(pad "10" smd oval
			(at 1.249 0.494 270)
			(size 0.3 0.8)
			(layers "F.Cu" "F.Mask" "F.Paste")
			(net 378 "Net-(U23-B4)")
			(pinfunction "B4")
			(pintype "input")
		)
		(pad "11" smd oval
			(at 1.249 0 270)
			(size 0.3 0.8)
			(layers "F.Cu" "F.Mask" "F.Paste")
			(net 376 "Net-(U23-B3Y)")
			(pinfunction "B3Y")
			(pintype "output")
		)
		(pad "12" smd oval
			(at 1.249 -0.5 270)
			(size 0.3 0.8)
			(layers "F.Cu" "F.Mask" "F.Paste")
			(net 375 "Net-(U23-B2Y)")
			(pinfunction "B2Y")
			(pintype "output")
		)
		(pad "13" smd oval
			(at 1.249 -1 270)
			(size 0.3 0.8)
			(layers "F.Cu" "F.Mask" "F.Paste")
			(net 374 "Net-(U23-B1Y)")
			(pinfunction "B1Y")
			(pintype "output")
		)
		(pad "14" smd oval
			(at 0.244 -1.5 180)
			(size 0.3 0.8)
			(layers "F.Cu" "F.Mask" "F.Paste")
			(net 24 "+3V3")
			(pinfunction "VCCB")
			(pintype "power_in")
		)
		(pad "15" smd rect
			(at 0 0 180)
			(size 1 1.5)
			(layers "F.Cu" "F.Mask" "F.Paste")
			(net 1 "GND")
			(pinfunction "GND")
			(pintype "power_in")
		)
	)
	(footprint "antmicro-footprints:C_0402_1005Metric"
		(layer "F.Cu")
		(at 199.3625 88.3365 -90)
		(descr "Capacitor SMD 0402")
		(tags "capacitor SMD 0402")
		(property "Reference" "C284"
			(at 1.0135 -1.2075 270)
			(layer "F.SilkS")
			(effects
				(font
					(size 0.7 0.7)
					(thickness 0.15)
				)
				(justify left bottom)
			)
		)
		(property "Value" "C_100n_0402"
			(at 0 1.169 270)
			(layer "F.Fab")
			(effects
				(font
					(size 0.7 0.7)
					(thickness 0.15)
				)
				(justify left bottom)
			)
		)
		(property "Description" "SMD Multilayer Ceramic Capacitor, 0.1 µF, 50 V, 0402 [1005 Metric], ± 10%, X5R, GRM Series"
			(at 0 0 270)
			(layer "F.Fab")
			(hide yes)
			(effects
				(font
					(size 1.27 1.27)
					(thickness 0.15)
				)
			)
		)
		(property "Author" "Antmicro"
			(at 111.026 287.699 0)
			(layer "F.Fab")
			(hide yes)
			(effects
				(font
					(size 1 1)
					(thickness 0.15)
				)
			)
		)
		(property "Dielectric" "X5R"
			(at 111.026 287.699 0)
			(layer "F.Fab")
			(hide yes)
			(effects
				(font
					(size 1 1)
					(thickness 0.15)
				)
			)
		)
		(property "License" "Apache-2.0"
			(at 111.026 287.699 0)
			(layer "F.Fab")
			(hide yes)
			(effects
				(font
					(size 1 1)
					(thickness 0.15)
				)
			)
		)
		(property "MPN" "GRM155R61H104KE14D"
			(at 111.026 287.699 0)
			(layer "F.Fab")
			(hide yes)
			(effects
				(font
					(size 1 1)
					(thickness 0.15)
				)
			)
		)
		(property "Manufacturer" "Murata"
			(at 111.026 287.699 0)
			(layer "F.Fab")
			(hide yes)
			(effects
				(font
					(size 1 1)
					(thickness 0.15)
				)
			)
		)
		(property "Val" "100n"
			(at 111.026 287.699 0)
			(layer "F.Fab")
			(hide yes)
			(effects
				(font
					(size 1 1)
					(thickness 0.15)
				)
			)
		)
		(property "Voltage" "50V"
			(at 111.026 287.699 0)
			(layer "F.Fab")
			(hide yes)
			(effects
				(font
					(size 1 1)
					(thickness 0.15)
				)
			)
		)
		(sheetname "HDMI + Ethernet")
		(sheetfile "hdmi-ethernet.kicad_sch")
		(attr smd)
		(fp_rect
			(start -0.925 -0.47)
			(end 0.925 0.47)
			(stroke
				(width 0.05)
				(type default)
			)
			(fill no)
			(layer "F.CrtYd")
		)
		(fp_line
			(start -0.494 0.248)
			(end -0.494 -0.25)
			(stroke
				(width 0.15)
				(type solid)
			)
			(layer "F.Fab")
		)
		(fp_line
			(start 0.504 0.248)
			(end -0.494 0.248)
			(stroke
				(width 0.15)
				(type solid)
			)
			(layer "F.Fab")
		)
		(fp_line
			(start -0.494 -0.25)
			(end 0.504 -0.25)
			(stroke
				(width 0.15)
				(type solid)
			)
			(layer "F.Fab")
		)
		(fp_line
			(start 0.504 -0.25)
			(end 0.504 0.248)
			(stroke
				(width 0.15)
				(type solid)
			)
			(layer "F.Fab")
		)
		(pad "1" smd roundrect
			(at -0.48 0 270)
			(size 0.59 0.64)
			(layers "F.Cu" "F.Mask" "F.Paste")
			(roundrect_rratio 0.25)
			(net 1 "GND")
			(pintype "passive")
		)
		(pad "2" smd roundrect
			(at 0.48 0 270)
			(size 0.59 0.64)
			(layers "F.Cu" "F.Mask" "F.Paste")
			(roundrect_rratio 0.25)
			(net 727 "+1V2")
			(pintype "passive")
		)
	)
	(footprint "antmicro-footprints:R_0402_1005Metric"
		(layer "F.Cu")
		(at 235.915 118.5 180)
		(descr "Resistor SMD 0402")
		(tags "resistor SMD 0402")
		(property "Reference" "R79"
			(at -0.735 -0.35 180)
			(layer "F.SilkS")
			(effects
				(font
					(size 0.7 0.7)
					(thickness 0.15)
				)
				(justify left bottom)
			)
		)
		(property "Value" "R_0R_0402"
			(at 0 1.4 180)
			(layer "F.Fab")
			(effects
				(font
					(size 0.7 0.7)
					(thickness 0.15)
				)
				(justify left bottom)
			)
		)
		(property "Description" "SMD Chip Resistor, Jumper, 0 ohm, 100 mW, 0402 [1005 Metric], Thick Film, General Purpose"
			(at 0 0 180)
			(layer "F.Fab")
			(hide yes)
			(effects
				(font
					(size 1.27 1.27)
					(thickness 0.15)
				)
			)
		)
		(property "Author" "Antmicro"
			(at 471.83 237 0)
			(layer "F.Fab")
			(hide yes)
			(effects
				(font
					(size 1 1)
					(thickness 0.15)
				)
			)
		)
		(property "Current" "1A"
			(at 471.83 237 0)
			(layer "F.Fab")
			(hide yes)
			(effects
				(font
					(size 1 1)
					(thickness 0.15)
				)
			)
		)
		(property "License" "Apache-2.0"
			(at 471.83 237 0)
			(layer "F.Fab")
			(hide yes)
			(effects
				(font
					(size 1 1)
					(thickness 0.15)
				)
			)
		)
		(property "MPN" "ERJ2GE0R00X"
			(at 471.83 237 0)
			(layer "F.Fab")
			(hide yes)
			(effects
				(font
					(size 1 1)
					(thickness 0.15)
				)
			)
		)
		(property "Manufacturer" "Panasonic"
			(at 471.83 237 0)
			(layer "F.Fab")
			(hide yes)
			(effects
				(font
					(size 1 1)
					(thickness 0.15)
				)
			)
		)
		(property "Tolerance" ""
			(at 471.83 237 0)
			(layer "F.Fab")
			(hide yes)
			(effects
				(font
					(size 1 1)
					(thickness 0.15)
				)
			)
		)
		(property "Val" "0R"
			(at 471.83 237 0)
			(layer "F.Fab")
			(hide yes)
			(effects
				(font
					(size 1 1)
					(thickness 0.15)
				)
			)
		)
		(sheetname "SPI Flash + SD Card")
		(sheetfile "spi-flash.kicad_sch")
		(attr smd)
		(fp_rect
			(start -0.925 -0.47)
			(end 0.925 0.47)
			(stroke
				(width 0.05)
				(type default)
			)
			(fill no)
			(layer "F.CrtYd")
		)
		(fp_rect
			(start -0.5 -0.25)
			(end 0.5 0.25)
			(stroke
				(width 0.15)
				(type solid)
			)
			(fill no)
			(layer "F.Fab")
		)
		(pad "1" smd roundrect
			(at -0.48 0 180)
			(size 0.59 0.64)
			(layers "F.Cu" "F.Mask" "F.Paste")
			(roundrect_rratio 0.25)
			(net 398 "/FPGA Bank 14 & 15/SYSTEM_FLASH.DQ3")
			(pintype "passive")
		)
		(pad "2" smd roundrect
			(at 0.48 0 180)
			(size 0.59 0.64)
			(layers "F.Cu" "F.Mask" "F.Paste")
			(roundrect_rratio 0.25)
			(net 899 "/SPI Flash + SD Card/SYSTEM_FLASH_DQ3")
			(pintype "passive")
		)
	)
	(footprint "antmicro-footprints:R_0402_1005Metric"
		(layer "F.Cu")
		(at 252.899 96)
		(descr "Resistor SMD 0402")
		(tags "resistor SMD 0402")
		(property "Reference" "R345"
			(at -1.499 -0.5 0)
			(layer "F.SilkS")
			(effects
				(font
					(size 0.7 0.7)
					(thickness 0.15)
				)
				(justify left bottom)
			)
		)
		(property "Value" "R_10k_0402"
			(at 0 1.4 0)
			(layer "F.Fab")
			(effects
				(font
					(size 0.7 0.7)
					(thickness 0.15)
				)
				(justify left bottom)
			)
		)
		(property "Description" "SMD Chip Resistor, 10 kohm, ± 1%, 62.5 mW, 0402 [1005 Metric], Thick Film, General Purpose"
			(at 0 0 0)
			(layer "F.Fab")
			(hide yes)
			(effects
				(font
					(size 1.27 1.27)
					(thickness 0.15)
				)
			)
		)
		(property "Author" "Antmicro"
			(at 0 0 0)
			(layer "F.Fab")
			(hide yes)
			(effects
				(font
					(size 1 1)
					(thickness 0.15)
				)
			)
		)
		(property "License" "Apache-2.0"
			(at 0 0 0)
			(layer "F.Fab")
			(hide yes)
			(effects
				(font
					(size 1 1)
					(thickness 0.15)
				)
			)
		)
		(property "MPN" "CR0402-FX-1002GLF"
			(at 0 0 0)
			(layer "F.Fab")
			(hide yes)
			(effects
				(font
					(size 1 1)
					(thickness 0.15)
				)
			)
		)
		(property "Manufacturer" "Bourns"
			(at 0 0 0)
			(layer "F.Fab")
			(hide yes)
			(effects
				(font
					(size 1 1)
					(thickness 0.15)
				)
			)
		)
		(property "Tolerance" "1%"
			(at 0 0 0)
			(layer "F.Fab")
			(hide yes)
			(effects
				(font
					(size 1 1)
					(thickness 0.15)
				)
			)
		)
		(property "Val" "10k"
			(at 0 0 0)
			(layer "F.Fab")
			(hide yes)
			(effects
				(font
					(size 1 1)
					(thickness 0.15)
				)
			)
		)
		(sheetname "USB PHY")
		(sheetfile "usb-phy.kicad_sch")
		(attr smd)
		(fp_rect
			(start -0.925 -0.47)
			(end 0.925 0.47)
			(stroke
				(width 0.05)
				(type default)
			)
			(fill no)
			(layer "F.CrtYd")
		)
		(fp_rect
			(start -0.5 -0.25)
			(end 0.5 0.25)
			(stroke
				(width 0.15)
				(type solid)
			)
			(fill no)
			(layer "F.Fab")
		)
		(pad "1" smd roundrect
			(at -0.48 0)
			(size 0.59 0.64)
			(layers "F.Cu" "F.Mask" "F.Paste")
			(roundrect_rratio 0.25)
			(net 583 "/USB PHY/USB_HOST_VBUS_EN")
			(pintype "passive")
		)
		(pad "2" smd roundrect
			(at 0.48 0)
			(size 0.59 0.64)
			(layers "F.Cu" "F.Mask" "F.Paste")
			(roundrect_rratio 0.25)
			(net 1 "GND")
			(pintype "passive")
		)
	)
	(footprint "antmicro-footprints:TP_SMD_0.75mm"
		(layer "F.Cu")
		(at 164.5 170.2)
		(property "Reference" "TP6"
			(at 0.3 0.35 0)
			(layer "F.SilkS")
			(effects
				(font
					(size 0.7 0.7)
					(thickness 0.15)
				)
				(justify left bottom)
			)
		)
		(property "Value" "TP_0.75mm_SMD"
			(at 0 1.2 0)
			(layer "F.Fab")
			(effects
				(font
					(size 0.7 0.7)
					(thickness 0.15)
				)
				(justify left bottom)
			)
		)
		(property "Description" "SMT test point"
			(at 0 0 0)
			(layer "F.Fab")
			(hide yes)
			(effects
				(font
					(size 1.27 1.27)
					(thickness 0.15)
				)
			)
		)
		(property "Author" "Antmicro"
			(at 0 0 0)
			(layer "F.Fab")
			(hide yes)
			(effects
				(font
					(size 1 1)
					(thickness 0.15)
				)
			)
		)
		(property "License" "Apache-2.0"
			(at 0 0 0)
			(layer "F.Fab")
			(hide yes)
			(effects
				(font
					(size 1 1)
					(thickness 0.15)
				)
			)
		)
		(property "MPN" ""
			(at 0 0 0)
			(layer "F.Fab")
			(hide yes)
			(effects
				(font
					(size 1 1)
					(thickness 0.15)
				)
			)
		)
		(property "Manufacturer" ""
			(at 0 0 0)
			(layer "F.Fab")
			(hide yes)
			(effects
				(font
					(size 1 1)
					(thickness 0.15)
				)
			)
		)
		(sheetname "DC-DC Converters")
		(sheetfile "dc-dc.kicad_sch")
		(attr exclude_from_pos_files)
		(pad "1" smd circle
			(at 0 0)
			(size 0.75 0.75)
			(layers "F.Cu" "F.Mask")
			(net 1394 "/I2C.QDCDC1_SCL")
			(pinfunction "1")
			(pintype "passive")
		)
	)
	(footprint "antmicro-footprints:R_0402_1005Metric"
		(layer "F.Cu")
		(at 207.64 81.74)
		(descr "Resistor SMD 0402")
		(tags "resistor SMD 0402")
		(property "Reference" "R5"
			(at -1.34 1.26 0)
			(layer "F.SilkS")
			(effects
				(font
					(size 0.7 0.7)
					(thickness 0.15)
				)
				(justify left bottom)
			)
		)
		(property "Value" "R_10k_0402"
			(at 0 1.4 0)
			(layer "F.Fab")
			(effects
				(font
					(size 0.7 0.7)
					(thickness 0.15)
				)
				(justify left bottom)
			)
		)
		(property "Description" "SMD Chip Resistor, 10 kohm, ± 1%, 62.5 mW, 0402 [1005 Metric], Thick Film, General Purpose"
			(at 0 0 0)
			(layer "F.Fab")
			(hide yes)
			(effects
				(font
					(size 1.27 1.27)
					(thickness 0.15)
				)
			)
		)
		(property "Author" "Antmicro"
			(at 0 0 0)
			(layer "F.Fab")
			(hide yes)
			(effects
				(font
					(size 1 1)
					(thickness 0.15)
				)
			)
		)
		(property "License" "Apache-2.0"
			(at 0 0 0)
			(layer "F.Fab")
			(hide yes)
			(effects
				(font
					(size 1 1)
					(thickness 0.15)
				)
			)
		)
		(property "MPN" "CR0402-FX-1002GLF"
			(at 0 0 0)
			(layer "F.Fab")
			(hide yes)
			(effects
				(font
					(size 1 1)
					(thickness 0.15)
				)
			)
		)
		(property "Manufacturer" "Bourns"
			(at 0 0 0)
			(layer "F.Fab")
			(hide yes)
			(effects
				(font
					(size 1 1)
					(thickness 0.15)
				)
			)
		)
		(property "Tolerance" "1%"
			(at 0 0 0)
			(layer "F.Fab")
			(hide yes)
			(effects
				(font
					(size 1 1)
					(thickness 0.15)
				)
			)
		)
		(property "Val" "10k"
			(at 0 0 0)
			(layer "F.Fab")
			(hide yes)
			(effects
				(font
					(size 1 1)
					(thickness 0.15)
				)
			)
		)
		(sheetname "FPGA Config")
		(sheetfile "fpga-config.kicad_sch")
		(attr smd)
		(fp_rect
			(start -0.925 -0.47)
			(end 0.925 0.47)
			(stroke
				(width 0.05)
				(type default)
			)
			(fill no)
			(layer "F.CrtYd")
		)
		(fp_rect
			(start -0.5 -0.25)
			(end 0.5 0.25)
			(stroke
				(width 0.15)
				(type solid)
			)
			(fill no)
			(layer "F.Fab")
		)
		(pad "1" smd roundrect
			(at -0.48 0)
			(size 0.59 0.64)
			(layers "F.Cu" "F.Mask" "F.Paste")
			(roundrect_rratio 0.25)
			(net 246 "/FPGA Config/DONE")
			(pintype "passive")
		)
		(pad "2" smd roundrect
			(at 0.48 0)
			(size 0.59 0.64)
			(layers "F.Cu" "F.Mask" "F.Paste")
			(roundrect_rratio 0.25)
			(net 24 "+3V3")
			(pintype "passive")
		)
	)
	(footprint "antmicro-footprints:R_0402_1005Metric"
		(layer "F.Cu")
		(at 225.025 117.5)
		(descr "Resistor SMD 0402")
		(tags "resistor SMD 0402")
		(property "Reference" "R68"
			(at -2.975 0.4 0)
			(layer "F.SilkS")
			(effects
				(font
					(size 0.7 0.7)
					(thickness 0.15)
				)
				(justify left bottom)
			)
		)
		(property "Value" "R_10k_0402"
			(at 0 1.4 0)
			(layer "F.Fab")
			(effects
				(font
					(size 0.7 0.7)
					(thickness 0.15)
				)
				(justify left bottom)
			)
		)
		(property "Description" "SMD Chip Resistor, 10 kohm, ± 1%, 62.5 mW, 0402 [1005 Metric], Thick Film, General Purpose"
			(at 0 0 0)
			(layer "F.Fab")
			(hide yes)
			(effects
				(font
					(size 1.27 1.27)
					(thickness 0.15)
				)
			)
		)
		(property "Author" "Antmicro"
			(at 0 0 0)
			(layer "F.Fab")
			(hide yes)
			(effects
				(font
					(size 1 1)
					(thickness 0.15)
				)
			)
		)
		(property "License" "Apache-2.0"
			(at 0 0 0)
			(layer "F.Fab")
			(hide yes)
			(effects
				(font
					(size 1 1)
					(thickness 0.15)
				)
			)
		)
		(property "MPN" "CR0402-FX-1002GLF"
			(at 0 0 0)
			(layer "F.Fab")
			(hide yes)
			(effects
				(font
					(size 1 1)
					(thickness 0.15)
				)
			)
		)
		(property "Manufacturer" "Bourns"
			(at 0 0 0)
			(layer "F.Fab")
			(hide yes)
			(effects
				(font
					(size 1 1)
					(thickness 0.15)
				)
			)
		)
		(property "Tolerance" "1%"
			(at 0 0 0)
			(layer "F.Fab")
			(hide yes)
			(effects
				(font
					(size 1 1)
					(thickness 0.15)
				)
			)
		)
		(property "Val" "10k"
			(at 0 0 0)
			(layer "F.Fab")
			(hide yes)
			(effects
				(font
					(size 1 1)
					(thickness 0.15)
				)
			)
		)
		(sheetname "SPI Flash + SD Card")
		(sheetfile "spi-flash.kicad_sch")
		(attr smd)
		(fp_rect
			(start -0.925 -0.47)
			(end 0.925 0.47)
			(stroke
				(width 0.05)
				(type default)
			)
			(fill no)
			(layer "F.CrtYd")
		)
		(fp_rect
			(start -0.5 -0.25)
			(end 0.5 0.25)
			(stroke
				(width 0.15)
				(type solid)
			)
			(fill no)
			(layer "F.Fab")
		)
		(pad "1" smd roundrect
			(at -0.48 0)
			(size 0.59 0.64)
			(layers "F.Cu" "F.Mask" "F.Paste")
			(roundrect_rratio 0.25)
			(net 75 "/FPGA Bank 14 & 15/SYSTEM_FLASH.~{CS}")
			(pintype "passive")
		)
		(pad "2" smd roundrect
			(at 0.48 0)
			(size 0.59 0.64)
			(layers "F.Cu" "F.Mask" "F.Paste")
			(roundrect_rratio 0.25)
			(net 24 "+3V3")
			(pintype "passive")
		)
	)
	(footprint "antmicro-footprints:C_0402_1005Metric"
		(layer "F.Cu")
		(at 207.403752 96.5615 180)
		(descr "Capacitor SMD 0402")
		(tags "capacitor SMD 0402")
		(property "Reference" "C260"
			(at 1.753752 7.1115 180)
			(layer "F.SilkS")
			(effects
				(font
					(size 0.7 0.7)
					(thickness 0.15)
				)
				(justify left bottom)
			)
		)
		(property "Value" "C_100n_0402"
			(at 0 1.169 180)
			(layer "F.Fab")
			(effects
				(font
					(size 0.7 0.7)
					(thickness 0.15)
				)
				(justify left bottom)
			)
		)
		(property "Description" "SMD Multilayer Ceramic Capacitor, 0.1 µF, 50 V, 0402 [1005 Metric], ± 10%, X5R, GRM Series"
			(at 0 0 180)
			(layer "F.Fab")
			(hide yes)
			(effects
				(font
					(size 1.27 1.27)
					(thickness 0.15)
				)
			)
		)
		(property "Author" "Antmicro"
			(at 414.807504 193.123 0)
			(layer "F.Fab")
			(hide yes)
			(effects
				(font
					(size 1 1)
					(thickness 0.15)
				)
			)
		)
		(property "Dielectric" "X5R"
			(at 414.807504 193.123 0)
			(layer "F.Fab")
			(hide yes)
			(effects
				(font
					(size 1 1)
					(thickness 0.15)
				)
			)
		)
		(property "License" "Apache-2.0"
			(at 414.807504 193.123 0)
			(layer "F.Fab")
			(hide yes)
			(effects
				(font
					(size 1 1)
					(thickness 0.15)
				)
			)
		)
		(property "MPN" "GRM155R61H104KE14D"
			(at 414.807504 193.123 0)
			(layer "F.Fab")
			(hide yes)
			(effects
				(font
					(size 1 1)
					(thickness 0.15)
				)
			)
		)
		(property "Manufacturer" "Murata"
			(at 414.807504 193.123 0)
			(layer "F.Fab")
			(hide yes)
			(effects
				(font
					(size 1 1)
					(thickness 0.15)
				)
			)
		)
		(property "Val" "100n"
			(at 414.807504 193.123 0)
			(layer "F.Fab")
			(hide yes)
			(effects
				(font
					(size 1 1)
					(thickness 0.15)
				)
			)
		)
		(property "Voltage" "50V"
			(at 414.807504 193.123 0)
			(layer "F.Fab")
			(hide yes)
			(effects
				(font
					(size 1 1)
					(thickness 0.15)
				)
			)
		)
		(sheetname "HDMI + Ethernet")
		(sheetfile "hdmi-ethernet.kicad_sch")
		(attr smd)
		(fp_rect
			(start -0.925 -0.47)
			(end 0.925 0.47)
			(stroke
				(width 0.05)
				(type default)
			)
			(fill no)
			(layer "F.CrtYd")
		)
		(fp_line
			(start 0.504 0.248)
			(end -0.494 0.248)
			(stroke
				(width 0.15)
				(type solid)
			)
			(layer "F.Fab")
		)
		(fp_line
			(start 0.504 -0.25)
			(end 0.504 0.248)
			(stroke
				(width 0.15)
				(type solid)
			)
			(layer "F.Fab")
		)
		(fp_line
			(start -0.494 0.248)
			(end -0.494 -0.25)
			(stroke
				(width 0.15)
				(type solid)
			)
			(layer "F.Fab")
		)
		(fp_line
			(start -0.494 -0.25)
			(end 0.504 -0.25)
			(stroke
				(width 0.15)
				(type solid)
			)
			(layer "F.Fab")
		)
		(pad "1" smd roundrect
			(at -0.48 0 180)
			(size 0.59 0.64)
			(layers "F.Cu" "F.Mask" "F.Paste")
			(roundrect_rratio 0.25)
			(net 1 "GND")
			(pintype "passive")
		)
		(pad "2" smd roundrect
			(at 0.48 0 180)
			(size 0.59 0.64)
			(layers "F.Cu" "F.Mask" "F.Paste")
			(roundrect_rratio 0.25)
			(net 717 "/HDMI + Ethernet/GBE_AVDDH")
			(pintype "passive")
		)
	)
	(footprint "antmicro-footprints:R_0402_1005Metric"
		(layer "F.Cu")
		(at 236.35 143.45 180)
		(descr "Resistor SMD 0402")
		(tags "resistor SMD 0402")
		(property "Reference" "R185"
			(at 1.05 -4.45 180)
			(layer "F.SilkS")
			(effects
				(font
					(size 0.7 0.7)
					(thickness 0.15)
				)
				(justify left bottom)
			)
		)
		(property "Value" "R_33R_0402"
			(at 0 1.4 180)
			(layer "F.Fab")
			(effects
				(font
					(size 0.7 0.7)
					(thickness 0.15)
				)
				(justify left bottom)
			)
		)
		(property "Description" "SMD Chip Resistor, 33 ohm, ± 1%, 62.5 mW, 0402 [1005 Metric], Thick Film, General Purpose"
			(at 0 0 180)
			(layer "F.Fab")
			(hide yes)
			(effects
				(font
					(size 1.27 1.27)
					(thickness 0.15)
				)
			)
		)
		(property "Author" "Antmicro"
			(at 472.7 286.9 0)
			(layer "F.Fab")
			(hide yes)
			(effects
				(font
					(size 1 1)
					(thickness 0.15)
				)
			)
		)
		(property "License" "Apache-2.0"
			(at 472.7 286.9 0)
			(layer "F.Fab")
			(hide yes)
			(effects
				(font
					(size 1 1)
					(thickness 0.15)
				)
			)
		)
		(property "MPN" "CR0402-FX-33R0GLF"
			(at 472.7 286.9 0)
			(layer "F.Fab")
			(hide yes)
			(effects
				(font
					(size 1 1)
					(thickness 0.15)
				)
			)
		)
		(property "Manufacturer" "Bourns"
			(at 472.7 286.9 0)
			(layer "F.Fab")
			(hide yes)
			(effects
				(font
					(size 1 1)
					(thickness 0.15)
				)
			)
		)
		(property "Tolerance" "1%"
			(at 472.7 286.9 0)
			(layer "F.Fab")
			(hide yes)
			(effects
				(font
					(size 1 1)
					(thickness 0.15)
				)
			)
		)
		(property "Val" "33R"
			(at 472.7 286.9 0)
			(layer "F.Fab")
			(hide yes)
			(effects
				(font
					(size 1 1)
					(thickness 0.15)
				)
			)
		)
		(sheetname "USB PHY")
		(sheetfile "usb-phy.kicad_sch")
		(attr smd)
		(fp_rect
			(start -0.925 -0.47)
			(end 0.925 0.47)
			(stroke
				(width 0.05)
				(type default)
			)
			(fill no)
			(layer "F.CrtYd")
		)
		(fp_rect
			(start -0.5 -0.25)
			(end 0.5 0.25)
			(stroke
				(width 0.15)
				(type solid)
			)
			(fill no)
			(layer "F.Fab")
		)
		(pad "1" smd roundrect
			(at -0.48 0 180)
			(size 0.59 0.64)
			(layers "F.Cu" "F.Mask" "F.Paste")
			(roundrect_rratio 0.25)
			(net 378 "Net-(U23-B4)")
			(pintype "passive")
		)
		(pad "2" smd roundrect
			(at 0.48 0 180)
			(size 0.59 0.64)
			(layers "F.Cu" "F.Mask" "F.Paste")
			(roundrect_rratio 0.25)
			(net 1294 "/USB_SPI.MISO")
			(pintype "passive")
		)
	)
	(footprint "antmicro-footprints:C_0402_1005Metric"
		(layer "F.Cu")
		(at 230.4 141.6 180)
		(descr "Capacitor SMD 0402")
		(tags "capacitor SMD 0402")
		(property "Reference" "C365"
			(at -3.6 -0.35 0)
			(layer "F.SilkS")
			(effects
				(font
					(size 0.7 0.7)
					(thickness 0.15)
				)
				(justify right bottom)
			)
		)
		(property "Value" "C_22p_0402"
			(at 0 1.4 0)
			(layer "F.Fab")
			(effects
				(font
					(size 0.7 0.7)
					(thickness 0.15)
				)
				(justify right bottom)
			)
		)
		(property "Description" "SMD Multilayer Ceramic Capacitor, 22 pF, 50 V, 0402 [1005 Metric], ± 5%, C0G / NP0, CC Series"
			(at 0 0 180)
			(layer "F.Fab")
			(hide yes)
			(effects
				(font
					(size 1.27 1.27)
					(thickness 0.15)
				)
			)
		)
		(property "Author" "Antmicro"
			(at 460.8 283.2 0)
			(layer "F.Fab")
			(hide yes)
			(effects
				(font
					(size 1 1)
					(thickness 0.15)
				)
			)
		)
		(property "Dielectric" ""
			(at 460.8 283.2 0)
			(layer "F.Fab")
			(hide yes)
			(effects
				(font
					(size 1 1)
					(thickness 0.15)
				)
			)
		)
		(property "License" "Apache-2.0"
			(at 460.8 283.2 0)
			(layer "F.Fab")
			(hide yes)
			(effects
				(font
					(size 1 1)
					(thickness 0.15)
				)
			)
		)
		(property "MPN" "CC0402JRNPO9BN220"
			(at 460.8 283.2 0)
			(layer "F.Fab")
			(hide yes)
			(effects
				(font
					(size 1 1)
					(thickness 0.15)
				)
			)
		)
		(property "Manufacturer" "YAGEO"
			(at 460.8 283.2 0)
			(layer "F.Fab")
			(hide yes)
			(effects
				(font
					(size 1 1)
					(thickness 0.15)
				)
			)
		)
		(property "Val" "22p"
			(at 460.8 283.2 0)
			(layer "F.Fab")
			(hide yes)
			(effects
				(font
					(size 1 1)
					(thickness 0.15)
				)
			)
		)
		(property "Voltage" ""
			(at 460.8 283.2 0)
			(layer "F.Fab")
			(hide yes)
			(effects
				(font
					(size 1 1)
					(thickness 0.15)
				)
			)
		)
		(sheetname "Clocks")
		(sheetfile "clocks.kicad_sch")
		(attr smd)
		(fp_rect
			(start -0.925 -0.47)
			(end 0.925 0.47)
			(stroke
				(width 0.05)
				(type default)
			)
			(fill no)
			(layer "F.CrtYd")
		)
		(fp_line
			(start 0.504 0.248)
			(end -0.494 0.248)
			(stroke
				(width 0.15)
				(type solid)
			)
			(layer "F.Fab")
		)
		(fp_line
			(start 0.504 -0.25)
			(end 0.504 0.248)
			(stroke
				(width 0.15)
				(type solid)
			)
			(layer "F.Fab")
		)
		(fp_line
			(start -0.494 0.248)
			(end -0.494 -0.25)
			(stroke
				(width 0.15)
				(type solid)
			)
			(layer "F.Fab")
		)
		(fp_line
			(start -0.494 -0.25)
			(end 0.504 -0.25)
			(stroke
				(width 0.15)
				(type solid)
			)
			(layer "F.Fab")
		)
		(pad "1" smd roundrect
			(at -0.48 0 180)
			(size 0.59 0.64)
			(layers "F.Cu" "F.Mask" "F.Paste")
			(roundrect_rratio 0.25)
			(net 1 "GND")
			(pintype "passive")
		)
		(pad "2" smd roundrect
			(at 0.48 0 180)
			(size 0.59 0.64)
			(layers "F.Cu" "F.Mask" "F.Paste")
			(roundrect_rratio 0.25)
			(net 752 "/Clocks/PLL_XI")
			(pintype "passive")
		)
	)
	(footprint "antmicro-footprints:C_0402_1005Metric"
		(layer "F.Cu")
		(at 173.570001 127.462501 180)
		(descr "Capacitor SMD 0402")
		(tags "capacitor SMD 0402")
		(property "Reference" "C311"
			(at -3.729999 -0.389999 0)
			(layer "F.SilkS")
			(effects
				(font
					(size 0.7 0.7)
					(thickness 0.15)
				)
				(justify right bottom)
			)
		)
		(property "Value" "C_100n_0402"
			(at 0 1.4 0)
			(layer "F.Fab")
			(effects
				(font
					(size 0.7 0.7)
					(thickness 0.15)
				)
				(justify right bottom)
			)
		)
		(property "Description" "SMD Multilayer Ceramic Capacitor, 0.1 µF, 50 V, 0402 [1005 Metric], ± 10%, X5R, GRM Series"
			(at 0 0 180)
			(layer "F.Fab")
			(hide yes)
			(effects
				(font
					(size 1.27 1.27)
					(thickness 0.15)
				)
			)
		)
		(property "Author" "Antmicro"
			(at 347.140002 254.925002 0)
			(layer "F.Fab")
			(hide yes)
			(effects
				(font
					(size 1 1)
					(thickness 0.15)
				)
			)
		)
		(property "Dielectric" "X5R"
			(at 347.140002 254.925002 0)
			(layer "F.Fab")
			(hide yes)
			(effects
				(font
					(size 1 1)
					(thickness 0.15)
				)
			)
		)
		(property "License" "Apache-2.0"
			(at 347.140002 254.925002 0)
			(layer "F.Fab")
			(hide yes)
			(effects
				(font
					(size 1 1)
					(thickness 0.15)
				)
			)
		)
		(property "MPN" "GRM155R61H104KE14D"
			(at 347.140002 254.925002 0)
			(layer "F.Fab")
			(hide yes)
			(effects
				(font
					(size 1 1)
					(thickness 0.15)
				)
			)
		)
		(property "Manufacturer" "Murata"
			(at 347.140002 254.925002 0)
			(layer "F.Fab")
			(hide yes)
			(effects
				(font
					(size 1 1)
					(thickness 0.15)
				)
			)
		)
		(property "Val" "100n"
			(at 347.140002 254.925002 0)
			(layer "F.Fab")
			(hide yes)
			(effects
				(font
					(size 1 1)
					(thickness 0.15)
				)
			)
		)
		(property "Voltage" "50V"
			(at 347.140002 254.925002 0)
			(layer "F.Fab")
			(hide yes)
			(effects
				(font
					(size 1 1)
					(thickness 0.15)
				)
			)
		)
		(sheetname "FMC+ HSPC")
		(sheetfile "fmc-hspc.kicad_sch")
		(attr smd)
		(fp_rect
			(start -0.925 -0.47)
			(end 0.925 0.47)
			(stroke
				(width 0.05)
				(type default)
			)
			(fill no)
			(layer "F.CrtYd")
		)
		(fp_line
			(start 0.504 0.248)
			(end -0.494 0.248)
			(stroke
				(width 0.15)
				(type solid)
			)
			(layer "F.Fab")
		)
		(fp_line
			(start 0.504 -0.25)
			(end 0.504 0.248)
			(stroke
				(width 0.15)
				(type solid)
			)
			(layer "F.Fab")
		)
		(fp_line
			(start -0.494 0.248)
			(end -0.494 -0.25)
			(stroke
				(width 0.15)
				(type solid)
			)
			(layer "F.Fab")
		)
		(fp_line
			(start -0.494 -0.25)
			(end 0.504 -0.25)
			(stroke
				(width 0.15)
				(type solid)
			)
			(layer "F.Fab")
		)
		(pad "1" smd roundrect
			(at -0.48 0 180)
			(size 0.59 0.64)
			(layers "F.Cu" "F.Mask" "F.Paste")
			(roundrect_rratio 0.25)
			(net 115 "/FMC+ HSPC/GTX115.TX1_N")
			(pintype "passive")
		)
		(pad "2" smd roundrect
			(at 0.48 0 180)
			(size 0.59 0.64)
			(layers "F.Cu" "F.Mask" "F.Paste")
			(roundrect_rratio 0.25)
			(net 109 "/FMC+ HSPC/GTX_TX6_C_N")
			(pintype "passive")
		)
	)
	(footprint "antmicro-footprints:R_0402_1005Metric"
		(layer "F.Cu")
		(at 193.6 165.649 90)
		(descr "Resistor SMD 0402")
		(tags "resistor SMD 0402")
		(property "Reference" "R331"
			(at -4.851 2.075 90)
			(layer "F.SilkS")
			(effects
				(font
					(size 0.7 0.7)
					(thickness 0.15)
				)
				(justify left bottom)
			)
		)
		(property "Value" "R_80k6_0402"
			(at 0 1.4 90)
			(layer "F.Fab")
			(effects
				(font
					(size 0.7 0.7)
					(thickness 0.15)
				)
				(justify left bottom)
			)
		)
		(property "Description" "SMD Chip Resistor, 80.6 kohm, ± 1%, 100 mW, 0402 [1005 Metric], Thick Film, Precision"
			(at 0 0 90)
			(layer "F.Fab")
			(hide yes)
			(effects
				(font
					(size 1.27 1.27)
					(thickness 0.15)
				)
			)
		)
		(property "Author" "Antmicro"
			(at 359.249 -27.951 0)
			(layer "F.Fab")
			(hide yes)
			(effects
				(font
					(size 1 1)
					(thickness 0.15)
				)
			)
		)
		(property "License" "Apache-2.0"
			(at 359.249 -27.951 0)
			(layer "F.Fab")
			(hide yes)
			(effects
				(font
					(size 1 1)
					(thickness 0.15)
				)
			)
		)
		(property "MPN" "CR0402-FX-8062GLF"
			(at 359.249 -27.951 0)
			(layer "F.Fab")
			(hide yes)
			(effects
				(font
					(size 1 1)
					(thickness 0.15)
				)
			)
		)
		(property "Manufacturer" "Bourns"
			(at 359.249 -27.951 0)
			(layer "F.Fab")
			(hide yes)
			(effects
				(font
					(size 1 1)
					(thickness 0.15)
				)
			)
		)
		(property "Tolerance" "1%"
			(at 359.249 -27.951 0)
			(layer "F.Fab")
			(hide yes)
			(effects
				(font
					(size 1 1)
					(thickness 0.15)
				)
			)
		)
		(property "Val" "80k6"
			(at 359.249 -27.951 0)
			(layer "F.Fab")
			(hide yes)
			(effects
				(font
					(size 1 1)
					(thickness 0.15)
				)
			)
		)
		(sheetname "DC-DC Converters")
		(sheetfile "dc-dc.kicad_sch")
		(attr smd)
		(fp_rect
			(start -0.925 -0.47)
			(end 0.925 0.47)
			(stroke
				(width 0.05)
				(type default)
			)
			(fill no)
			(layer "F.CrtYd")
		)
		(fp_rect
			(start -0.5 -0.25)
			(end 0.5 0.25)
			(stroke
				(width 0.15)
				(type solid)
			)
			(fill no)
			(layer "F.Fab")
		)
		(pad "1" smd roundrect
			(at -0.48 0 90)
			(size 0.59 0.64)
			(layers "F.Cu" "F.Mask" "F.Paste")
			(roundrect_rratio 0.25)
			(net 1230 "Net-(C364-Pad1)")
			(pintype "passive")
		)
		(pad "2" smd roundrect
			(at 0.48 0 90)
			(size 0.59 0.64)
			(layers "F.Cu" "F.Mask" "F.Paste")
			(roundrect_rratio 0.25)
			(net 751 "/DC-DC Converters/1V0_REG")
			(pintype "passive")
		)
	)
	(footprint "antmicro-footprints:C_0402_1005Metric"
		(layer "F.Cu")
		(at 199.901 106.199 180)
		(descr "Capacitor SMD 0402")
		(tags "capacitor SMD 0402")
		(property "Reference" "C231"
			(at -0.899 -0.301 180)
			(layer "F.SilkS")
			(effects
				(font
					(size 0.7 0.7)
					(thickness 0.15)
				)
				(justify left bottom)
			)
		)
		(property "Value" "C_100n_0402"
			(at 0 1.169 180)
			(layer "F.Fab")
			(effects
				(font
					(size 0.7 0.7)
					(thickness 0.15)
				)
				(justify left bottom)
			)
		)
		(property "Description" "SMD Multilayer Ceramic Capacitor, 0.1 µF, 50 V, 0402 [1005 Metric], ± 10%, X5R, GRM Series"
			(at 0 0 180)
			(layer "F.Fab")
			(hide yes)
			(effects
				(font
					(size 1.27 1.27)
					(thickness 0.15)
				)
			)
		)
		(property "Author" "Antmicro"
			(at 399.802 212.398 0)
			(layer "F.Fab")
			(hide yes)
			(effects
				(font
					(size 1 1)
					(thickness 0.15)
				)
			)
		)
		(property "Dielectric" "X5R"
			(at 399.802 212.398 0)
			(layer "F.Fab")
			(hide yes)
			(effects
				(font
					(size 1 1)
					(thickness 0.15)
				)
			)
		)
		(property "License" "Apache-2.0"
			(at 399.802 212.398 0)
			(layer "F.Fab")
			(hide yes)
			(effects
				(font
					(size 1 1)
					(thickness 0.15)
				)
			)
		)
		(property "MPN" "GRM155R61H104KE14D"
			(at 399.802 212.398 0)
			(layer "F.Fab")
			(hide yes)
			(effects
				(font
					(size 1 1)
					(thickness 0.15)
				)
			)
		)
		(property "Manufacturer" "Murata"
			(at 399.802 212.398 0)
			(layer "F.Fab")
			(hide yes)
			(effects
				(font
					(size 1 1)
					(thickness 0.15)
				)
			)
		)
		(property "Val" "100n"
			(at 399.802 212.398 0)
			(layer "F.Fab")
			(hide yes)
			(effects
				(font
					(size 1 1)
					(thickness 0.15)
				)
			)
		)
		(property "Voltage" "50V"
			(at 399.802 212.398 0)
			(layer "F.Fab")
			(hide yes)
			(effects
				(font
					(size 1 1)
					(thickness 0.15)
				)
			)
		)
		(sheetname "USB PHY")
		(sheetfile "usb-phy.kicad_sch")
		(attr smd)
		(fp_rect
			(start -0.925 -0.47)
			(end 0.925 0.47)
			(stroke
				(width 0.05)
				(type default)
			)
			(fill no)
			(layer "F.CrtYd")
		)
		(fp_line
			(start 0.504 0.248)
			(end -0.494 0.248)
			(stroke
				(width 0.15)
				(type solid)
			)
			(layer "F.Fab")
		)
		(fp_line
			(start 0.504 -0.25)
			(end 0.504 0.248)
			(stroke
				(width 0.15)
				(type solid)
			)
			(layer "F.Fab")
		)
		(fp_line
			(start -0.494 0.248)
			(end -0.494 -0.25)
			(stroke
				(width 0.15)
				(type solid)
			)
			(layer "F.Fab")
		)
		(fp_line
			(start -0.494 -0.25)
			(end 0.504 -0.25)
			(stroke
				(width 0.15)
				(type solid)
			)
			(layer "F.Fab")
		)
		(pad "1" smd roundrect
			(at -0.48 0 180)
			(size 0.59 0.64)
			(layers "F.Cu" "F.Mask" "F.Paste")
			(roundrect_rratio 0.25)
			(net 1 "GND")
			(pintype "passive")
		)
		(pad "2" smd roundrect
			(at 0.48 0 180)
			(size 0.59 0.64)
			(layers "F.Cu" "F.Mask" "F.Paste")
			(roundrect_rratio 0.25)
			(net 24 "+3V3")
			(pintype "passive")
		)
	)
	(footprint "antmicro-footprints:R_0402_1005Metric"
		(layer "F.Cu")
		(at 218.4 150.8)
		(descr "Resistor SMD 0402")
		(tags "resistor SMD 0402")
		(property "Reference" "R231"
			(at -3.6 0.35 0)
			(layer "F.SilkS")
			(effects
				(font
					(size 0.7 0.7)
					(thickness 0.15)
				)
				(justify left bottom)
			)
		)
		(property "Value" "R_10R_0402"
			(at 0 1.4 0)
			(layer "F.Fab")
			(effects
				(font
					(size 0.7 0.7)
					(thickness 0.15)
				)
				(justify left bottom)
			)
		)
		(property "Description" "SMD Chip Resistor, 10 ohm, ± 1%, 62.5 mW, 0402 [1005 Metric], Thick Film, General Purpose"
			(at 0 0 0)
			(layer "F.Fab")
			(hide yes)
			(effects
				(font
					(size 1.27 1.27)
					(thickness 0.15)
				)
			)
		)
		(property "Author" "Antmicro"
			(at 0 0 0)
			(layer "F.Fab")
			(hide yes)
			(effects
				(font
					(size 1 1)
					(thickness 0.15)
				)
			)
		)
		(property "License" "Apache-2.0"
			(at 0 0 0)
			(layer "F.Fab")
			(hide yes)
			(effects
				(font
					(size 1 1)
					(thickness 0.15)
				)
			)
		)
		(property "MPN" "CR0402-FX-10R0GLF"
			(at 0 0 0)
			(layer "F.Fab")
			(hide yes)
			(effects
				(font
					(size 1 1)
					(thickness 0.15)
				)
			)
		)
		(property "Manufacturer" "Bourns"
			(at 0 0 0)
			(layer "F.Fab")
			(hide yes)
			(effects
				(font
					(size 1 1)
					(thickness 0.15)
				)
			)
		)
		(property "Tolerance" "1%"
			(at 0 0 0)
			(layer "F.Fab")
			(hide yes)
			(effects
				(font
					(size 1 1)
					(thickness 0.15)
				)
			)
		)
		(property "Val" "10R"
			(at 0 0 0)
			(layer "F.Fab")
			(hide yes)
			(effects
				(font
					(size 1 1)
					(thickness 0.15)
				)
			)
		)
		(sheetname "HDMI + Ethernet")
		(sheetfile "hdmi-ethernet.kicad_sch")
		(attr smd)
		(fp_rect
			(start -0.925 -0.47)
			(end 0.925 0.47)
			(stroke
				(width 0.05)
				(type default)
			)
			(fill no)
			(layer "F.CrtYd")
		)
		(fp_rect
			(start -0.5 -0.25)
			(end 0.5 0.25)
			(stroke
				(width 0.15)
				(type solid)
			)
			(fill no)
			(layer "F.Fab")
		)
		(pad "1" smd roundrect
			(at -0.48 0)
			(size 0.59 0.64)
			(layers "F.Cu" "F.Mask" "F.Paste")
			(roundrect_rratio 0.25)
			(net 511 "/FPGA Bank 18 & 32/ETH_RMII.TXEN")
			(pintype "passive")
		)
		(pad "2" smd roundrect
			(at 0.48 0)
			(size 0.59 0.64)
			(layers "F.Cu" "F.Mask" "F.Paste")
			(roundrect_rratio 0.25)
			(net 948 "/HDMI + Ethernet/ETH_PHY_TXEN")
			(pintype "passive")
		)
	)
	(footprint "antmicro-footprints:SW_DIP_SPSTx08_Slide_Copal_CVS-08xB_W5.9mm_P1mm"
		(layer "F.Cu")
		(at 257.2 74 90)
		(descr "SMD 8x-dip-switch SPST Copal_CVS-08xB, Slide, row spacing 5.9 mm (232 mils), body size  (see http://www.nidec-copal-electronics.com/e/catalog/switch/cvs.pdf)")
		(tags "SMD DIP Switch SPST Slide 5.9mm 232mil")
		(property "Reference" "SW2"
			(at -3.7 3.9 180)
			(layer "F.SilkS")
			(effects
				(font
					(size 0.7 0.7)
					(thickness 0.15)
				)
				(justify left bottom)
			)
		)
		(property "Value" "SW_CVS-08TB"
			(at -14.59 6.29 90)
			(layer "F.Fab")
			(effects
				(font
					(size 0.7 0.7)
					(thickness 0.15)
				)
				(justify left bottom)
			)
		)
		(property "Description" "DIP / SIP Switch, 8 Circuits, Slide, Surface Mount, SPST, 6 V, 100 mA"
			(at 0 0 90)
			(layer "F.Fab")
			(hide yes)
			(effects
				(font
					(size 1.27 1.27)
					(thickness 0.15)
				)
			)
		)
		(property "Author" "Antmicro"
			(at 331.2 -183.2 0)
			(layer "F.Fab")
			(hide yes)
			(effects
				(font
					(size 1 1)
					(thickness 0.15)
				)
			)
		)
		(property "License" "Apache-2.0"
			(at 331.2 -183.2 0)
			(layer "F.Fab")
			(hide yes)
			(effects
				(font
					(size 1 1)
					(thickness 0.15)
				)
			)
		)
		(property "MPN" "CVS-08TB"
			(at 331.2 -183.2 0)
			(layer "F.Fab")
			(hide yes)
			(effects
				(font
					(size 1 1)
					(thickness 0.15)
				)
			)
		)
		(property "Manufacturer" "Nidec Components"
			(at 331.2 -183.2 0)
			(layer "F.Fab")
			(hide yes)
			(effects
				(font
					(size 1 1)
					(thickness 0.15)
				)
			)
		)
		(sheetname "User GPIO + LED + button + DIP switch")
		(sheetfile "user-gpio.kicad_sch")
		(attr smd)
		(fp_line
			(start -1.561 -4.912)
			(end 1.56 -4.912)
			(stroke
				(width 0.15)
				(type solid)
			)
			(layer "F.SilkS")
		)
		(fp_line
			(start -1.561 4.91)
			(end 1.56 4.91)
			(stroke
				(width 0.15)
				(type solid)
			)
			(layer "F.SilkS")
		)
		(fp_circle
			(center -3.31 -4.2)
			(end -3.261 -4.2)
			(stroke
				(width 0.15)
				(type solid)
			)
			(fill yes)
			(layer "F.SilkS")
		)
		(fp_rect
			(start -3.601 -5)
			(end 3.598 4.998)
			(stroke
				(width 0.05)
				(type solid)
			)
			(fill no)
			(layer "F.CrtYd")
		)
		(fp_line
			(start 2.35 -4.5)
			(end 2.35 4.498)
			(stroke
				(width 0.15)
				(type solid)
			)
			(layer "F.Fab")
		)
		(fp_line
			(start -1.351 -4.5)
			(end 2.35 -4.5)
			(stroke
				(width 0.15)
				(type solid)
			)
			(layer "F.Fab")
		)
		(fp_line
			(start 0.998 -3.75)
			(end -1 -3.75)
			(stroke
				(width 0.15)
				(type solid)
			)
			(layer "F.Fab")
		)
		(fp_line
			(start -0.335 -3.75)
			(end -0.335 -3.25)
			(stroke
				(width 0.15)
				(type solid)
			)
			(layer "F.Fab")
		)
		(fp_line
			(start -1 -3.75)
			(end -1 -3.25)
			(stroke
				(width 0.15)
				(type solid)
			)
			(layer "F.Fab")
		)
		(fp_line
			(start -1 -3.65)
			(end -0.335 -3.65)
			(stroke
				(width 0.15)
				(type solid)
			)
			(layer "F.Fab")
		)
		(fp_line
			(start -1 -3.551)
			(end -0.335 -3.551)
			(stroke
				(width 0.15)
				(type solid)
			)
			(layer "F.Fab")
		)
		(fp_line
			(start -2.351 -3.5)
			(end -1.351 -4.5)
			(stroke
				(width 0.15)
				(type solid)
			)
			(layer "F.Fab")
		)
		(fp_line
			(start -1 -3.451)
			(end -0.335 -3.451)
			(stroke
				(width 0.15)
				(type solid)
			)
			(layer "F.Fab")
		)
		(fp_line
			(start -1 -3.351)
			(end -0.335 -3.351)
			(stroke
				(width 0.15)
				(type solid)
			)
			(layer "F.Fab")
		)
		(fp_line
			(start 0.998 -3.25)
			(end 0.998 -3.75)
			(stroke
				(width 0.15)
				(type solid)
			)
			(layer "F.Fab")
		)
		(fp_line
			(start -1 -3.25)
			(end 0.998 -3.25)
			(stroke
				(width 0.15)
				(type solid)
			)
			(layer "F.Fab")
		)
		(fp_line
			(start 0.998 -2.75)
			(end -1 -2.75)
			(stroke
				(width 0.15)
				(type solid)
			)
			(layer "F.Fab")
		)
		(fp_line
			(start -0.335 -2.75)
			(end -0.335 -2.25)
			(stroke
				(width 0.15)
				(type solid)
			)
			(layer "F.Fab")
		)
		(fp_line
			(start -1 -2.75)
			(end -1 -2.25)
			(stroke
				(width 0.15)
				(type solid)
			)
			(layer "F.Fab")
		)
		(fp_line
			(start -1 -2.65)
			(end -0.335 -2.65)
			(stroke
				(width 0.15)
				(type solid)
			)
			(layer "F.Fab")
		)
		(fp_line
			(start -1 -2.551)
			(end -0.335 -2.551)
			(stroke
				(width 0.15)
				(type solid)
			)
			(layer "F.Fab")
		)
		(fp_line
			(start -1 -2.452)
			(end -0.335 -2.452)
			(stroke
				(width 0.15)
				(type solid)
			)
			(layer "F.Fab")
		)
		(fp_line
			(start -1 -2.351)
			(end -0.335 -2.351)
			(stroke
				(width 0.15)
				(type solid)
			)
			(layer "F.Fab")
		)
		(fp_line
			(start 0.998 -2.25)
			(end 0.998 -2.75)
			(stroke
				(width 0.15)
				(type solid)
			)
			(layer "F.Fab")
		)
		(fp_line
			(start -1 -2.25)
			(end 0.998 -2.25)
			(stroke
				(width 0.15)
				(type solid)
			)
			(layer "F.Fab")
		)
		(fp_line
			(start 0.998 -1.75)
			(end -1 -1.75)
			(stroke
				(width 0.15)
				(type solid)
			)
			(layer "F.Fab")
		)
		(fp_line
			(start -0.335 -1.75)
			(end -0.335 -1.25)
			(stroke
				(width 0.15)
				(type solid)
			)
			(layer "F.Fab")
		)
		(fp_line
			(start -1 -1.75)
			(end -1 -1.25)
			(stroke
				(width 0.15)
				(type solid)
			)
			(layer "F.Fab")
		)
		(fp_line
			(start -1 -1.651)
			(end -0.335 -1.651)
			(stroke
				(width 0.15)
				(type solid)
			)
			(layer "F.Fab")
		)
		(fp_line
			(start -1 -1.551)
			(end -0.335 -1.551)
			(stroke
				(width 0.15)
				(type solid)
			)
			(layer "F.Fab")
		)
		(fp_line
			(start -1 -1.45)
			(end -0.335 -1.45)
			(stroke
				(width 0.15)
				(type solid)
			)
			(layer "F.Fab")
		)
		(fp_line
			(start -1 -1.351)
			(end -0.335 -1.351)
			(stroke
				(width 0.15)
				(type solid)
			)
			(layer "F.Fab")
		)
		(fp_line
			(start 0.998 -1.25)
			(end 0.998 -1.75)
			(stroke
				(width 0.15)
				(type solid)
			)
			(layer "F.Fab")
		)
		(fp_line
			(start -1 -1.25)
			(end 0.998 -1.25)
			(stroke
				(width 0.15)
				(type solid)
			)
			(layer "F.Fab")
		)
		(fp_line
			(start 0.998 -0.75)
			(end -1 -0.75)
			(stroke
				(width 0.15)
				(type solid)
			)
			(layer "F.Fab")
		)
		(fp_line
			(start -0.335 -0.75)
			(end -0.335 -0.25)
			(stroke
				(width 0.15)
				(type solid)
			)
			(layer "F.Fab")
		)
		(fp_line
			(start -1 -0.75)
			(end -1 -0.25)
			(stroke
				(width 0.15)
				(type solid)
			)
			(layer "F.Fab")
		)
		(fp_line
			(start -1 -0.652)
			(end -0.335 -0.652)
			(stroke
				(width 0.15)
				(type solid)
			)
			(layer "F.Fab")
		)
		(fp_line
			(start -1 -0.552)
			(end -0.335 -0.552)
			(stroke
				(width 0.15)
				(type solid)
			)
			(layer "F.Fab")
		)
		(fp_line
			(start -1 -0.452)
			(end -0.335 -0.452)
			(stroke
				(width 0.15)
				(type solid)
			)
			(layer "F.Fab")
		)
		(fp_line
			(start -1 -0.351)
			(end -0.335 -0.351)
			(stroke
				(width 0.15)
				(type solid)
			)
			(layer "F.Fab")
		)
		(fp_line
			(start 0.998 -0.25)
			(end 0.998 -0.75)
			(stroke
				(width 0.15)
				(type solid)
			)
			(layer "F.Fab")
		)
		(fp_line
			(start -1 -0.25)
			(end 0.998 -0.25)
			(stroke
				(width 0.15)
				(type solid)
			)
			(layer "F.Fab")
		)
		(fp_line
			(start 0.998 0.248)
			(end -1 0.248)
			(stroke
				(width 0.15)
				(type solid)
			)
			(layer "F.Fab")
		)
		(fp_line
			(start -0.335 0.248)
			(end -0.335 0.748)
			(stroke
				(width 0.15)
				(type solid)
			)
			(layer "F.Fab")
		)
		(fp_line
			(start -1 0.248)
			(end -1 0.748)
			(stroke
				(width 0.15)
				(type solid)
			)
			(layer "F.Fab")
		)
		(fp_line
			(start -1 0.349)
			(end -0.335 0.349)
			(stroke
				(width 0.15)
				(type solid)
			)
			(layer "F.Fab")
		)
		(fp_line
			(start -1 0.45)
			(end -0.335 0.45)
			(stroke
				(width 0.15)
				(type solid)
			)
			(layer "F.Fab")
		)
		(fp_line
			(start -1 0.55)
			(end -0.335 0.55)
			(stroke
				(width 0.15)
				(type solid)
			)
			(layer "F.Fab")
		)
		(fp_line
			(start -1 0.65)
			(end -0.335 0.65)
			(stroke
				(width 0.15)
				(type solid)
			)
			(layer "F.Fab")
		)
		(fp_line
			(start 0.998 0.748)
			(end 0.998 0.248)
			(stroke
				(width 0.15)
				(type solid)
			)
			(layer "F.Fab")
		)
		(fp_line
			(start -1 0.748)
			(end 0.998 0.748)
			(stroke
				(width 0.15)
				(type solid)
			)
			(layer "F.Fab")
		)
		(fp_line
			(start -1 0.748)
			(end -0.335 0.748)
			(stroke
				(width 0.15)
				(type solid)
			)
			(layer "F.Fab")
		)
		(fp_line
			(start 0.998 1.249)
			(end -1 1.249)
			(stroke
				(width 0.15)
				(type solid)
			)
			(layer "F.Fab")
		)
		(fp_line
			(start -0.335 1.249)
			(end -0.335 1.749)
			(stroke
				(width 0.15)
				(type solid)
			)
			(layer "F.Fab")
		)
		(fp_line
			(start -1 1.249)
			(end -1 1.749)
			(stroke
				(width 0.15)
				(type solid)
			)
			(layer "F.Fab")
		)
		(fp_line
			(start -1 1.35)
			(end -0.335 1.35)
			(stroke
				(width 0.15)
				(type solid)
			)
			(layer "F.Fab")
		)
		(fp_line
			(start -1 1.449)
			(end -0.335 1.449)
			(stroke
				(width 0.15)
				(type solid)
			)
			(layer "F.Fab")
		)
		(fp_line
			(start -1 1.55)
			(end -0.335 1.55)
			(stroke
				(width 0.15)
				(type solid)
			)
			(layer "F.Fab")
		)
		(fp_line
			(start -1 1.648)
			(end -0.335 1.648)
			(stroke
				(width 0.15)
				(type solid)
			)
			(layer "F.Fab")
		)
		(fp_line
			(start 0.998 1.749)
			(end 0.998 1.249)
			(stroke
				(width 0.15)
				(type solid)
			)
			(layer "F.Fab")
		)
		(fp_line
			(start -1 1.749)
			(end 0.998 1.749)
			(stroke
				(width 0.15)
				(type solid)
			)
			(layer "F.Fab")
		)
		(fp_line
			(start -1 1.749)
			(end -0.335 1.749)
			(stroke
				(width 0.15)
				(type solid)
			)
			(layer "F.Fab")
		)
		(fp_line
			(start 0.998 2.249)
			(end -1 2.249)
			(stroke
				(width 0.15)
				(type solid)
			)
			(layer "F.Fab")
		)
		(fp_line
			(start -0.335 2.249)
			(end -0.335 2.749)
			(stroke
				(width 0.15)
				(type solid)
			)
			(layer "F.Fab")
		)
		(fp_line
			(start -1 2.249)
			(end -1 2.749)
			(stroke
				(width 0.15)
				(type solid)
			)
			(layer "F.Fab")
		)
		(fp_line
			(start -1 2.35)
			(end -0.335 2.35)
			(stroke
				(width 0.15)
				(type solid)
			)
			(layer "F.Fab")
		)
		(fp_line
			(start -1 2.45)
			(end -0.335 2.45)
			(stroke
				(width 0.15)
				(type solid)
			)
			(layer "F.Fab")
		)
		(fp_line
			(start -1 2.548)
			(end -0.335 2.548)
			(stroke
				(width 0.15)
				(type solid)
			)
			(layer "F.Fab")
		)
		(fp_line
			(start -1 2.648)
			(end -0.335 2.648)
			(stroke
				(width 0.15)
				(type solid)
			)
			(layer "F.Fab")
		)
		(fp_line
			(start 0.998 2.749)
			(end 0.998 2.249)
			(stroke
				(width 0.15)
				(type solid)
			)
			(layer "F.Fab")
		)
		(fp_line
			(start -1 2.749)
			(end 0.998 2.749)
			(stroke
				(width 0.15)
				(type solid)
			)
			(layer "F.Fab")
		)
		(fp_line
			(start -1 2.749)
			(end -0.335 2.749)
			(stroke
				(width 0.15)
				(type solid)
			)
			(layer "F.Fab")
		)
		(fp_line
			(start 0.998 3.249)
			(end -1 3.249)
			(stroke
				(width 0.15)
				(type solid)
			)
			(layer "F.Fab")
		)
		(fp_line
			(start -0.335 3.249)
			(end -0.335 3.749)
			(stroke
				(width 0.15)
				(type solid)
			)
			(layer "F.Fab")
		)
		(fp_line
			(start -1 3.249)
			(end -1 3.749)
			(stroke
				(width 0.15)
				(type solid)
			)
			(layer "F.Fab")
		)
		(fp_line
			(start -1 3.35)
			(end -0.335 3.35)
			(stroke
				(width 0.15)
				(type solid)
			)
			(layer "F.Fab")
		)
		(fp_line
			(start -1 3.45)
			(end -0.335 3.45)
			(stroke
				(width 0.15)
				(type solid)
			)
			(layer "F.Fab")
		)
		(fp_line
			(start -1 3.548)
			(end -0.335 3.548)
			(stroke
				(width 0.15)
				(type solid)
			)
			(layer "F.Fab")
		)
		(fp_line
			(start -1 3.648)
			(end -0.335 3.648)
			(stroke
				(width 0.15)
				(type solid)
			)
			(layer "F.Fab")
		)
		(fp_line
			(start 0.998 3.749)
			(end 0.998 3.249)
			(stroke
				(width 0.15)
				(type solid)
			)
			(layer "F.Fab")
		)
		(fp_line
			(start -1 3.749)
			(end 0.998 3.749)
			(stroke
				(width 0.15)
				(type solid)
			)
			(layer "F.Fab")
		)
		(fp_line
			(start -1 3.749)
			(end -0.335 3.749)
			(stroke
				(width 0.15)
				(type solid)
			)
			(layer "F.Fab")
		)
		(fp_line
			(start 2.35 4.498)
			(end -2.351 4.498)
			(stroke
				(width 0.15)
				(type solid)
			)
			(layer "F.Fab")
		)
		(fp_line
			(start -2.351 4.498)
			(end -2.351 -3.5)
			(stroke
				(width 0.15)
				(type solid)
			)
			(layer "F.Fab")
		)
		(fp_text user "on"
			(at -1.56 0.69 180)
			(layer "F.Fab")
			(effects
				(font
					(size 0.7 0.7)
					(thickness 0.15)
				)
				(justify left bottom)
			)
		)
		(pad "1" smd rect
			(at -2.952 -3.5 90)
			(size 1.2 0.5)
			(layers "F.Cu" "F.Mask" "F.Paste")
			(net 1311 "/USER_IO.DIP_SW0")
			(pinfunction "1")
			(pintype "passive")
		)
		(pad "2" smd rect
			(at -2.952 -2.5 90)
			(size 1.2 0.5)
			(layers "F.Cu" "F.Mask" "F.Paste")
			(net 1310 "/USER_IO.DIP_SW1")
			(pinfunction "2")
			(pintype "passive")
		)
		(pad "3" smd rect
			(at -2.952 -1.5 90)
			(size 1.2 0.5)
			(layers "F.Cu" "F.Mask" "F.Paste")
			(net 1309 "/USER_IO.DIP_SW2")
			(pinfunction "3")
			(pintype "passive")
		)
		(pad "4" smd rect
			(at -2.952 -0.5 90)
			(size 1.2 0.5)
			(layers "F.Cu" "F.Mask" "F.Paste")
			(net 1308 "/USER_IO.DIP_SW3")
			(pinfunction "4")
			(pintype "passive")
		)
		(pad "5" smd rect
			(at -2.952 0.498 90)
			(size 1.2 0.5)
			(layers "F.Cu" "F.Mask" "F.Paste")
			(net 1324 "/USER_IO.DIP_SW4")
			(pinfunction "5")
			(pintype "passive")
		)
		(pad "6" smd rect
			(at -2.952 1.499 90)
			(size 1.2 0.5)
			(layers "F.Cu" "F.Mask" "F.Paste")
			(net 1322 "/USER_IO.DIP_SW5")
			(pinfunction "6")
			(pintype "passive")
		)
		(pad "7" smd rect
			(at -2.952 2.499 90)
			(size 1.2 0.5)
			(layers "F.Cu" "F.Mask" "F.Paste")
			(net 1320 "/USER_IO.DIP_SW6")
			(pinfunction "7")
			(pintype "passive")
		)
		(pad "8" smd rect
			(at -2.952 3.499 90)
			(size 1.2 0.5)
			(layers "F.Cu" "F.Mask" "F.Paste")
			(net 1318 "/USER_IO.DIP_SW7")
			(pinfunction "8")
			(pintype "passive")
		)
		(pad "9" smd rect
			(at 2.95 3.499 90)
			(size 1.2 0.5)
			(layers "F.Cu" "F.Mask" "F.Paste")
			(net 1 "GND")
			(pinfunction "9")
			(pintype "passive")
		)
		(pad "10" smd rect
			(at 2.95 2.499 90)
			(size 1.2 0.5)
			(layers "F.Cu" "F.Mask" "F.Paste")
			(net 1 "GND")
			(pinfunction "10")
			(pintype "passive")
		)
		(pad "11" smd rect
			(at 2.95 1.499 90)
			(size 1.2 0.5)
			(layers "F.Cu" "F.Mask" "F.Paste")
			(net 1 "GND")
			(pinfunction "11")
			(pintype "passive")
		)
		(pad "12" smd rect
			(at 2.95 0.498 90)
			(size 1.2 0.5)
			(layers "F.Cu" "F.Mask" "F.Paste")
			(net 1 "GND")
			(pinfunction "12")
			(pintype "passive")
		)
		(pad "13" smd rect
			(at 2.95 -0.5 90)
			(size 1.2 0.5)
			(layers "F.Cu" "F.Mask" "F.Paste")
			(net 1 "GND")
			(pinfunction "13")
			(pintype "passive")
		)
		(pad "14" smd rect
			(at 2.95 -1.5 90)
			(size 1.2 0.5)
			(layers "F.Cu" "F.Mask" "F.Paste")
			(net 1 "GND")
			(pinfunction "14")
			(pintype "passive")
		)
		(pad "15" smd rect
			(at 2.95 -2.5 90)
			(size 1.2 0.5)
			(layers "F.Cu" "F.Mask" "F.Paste")
			(net 1 "GND")
			(pinfunction "15")
			(pintype "passive")
		)
		(pad "16" smd rect
			(at 2.95 -3.5 90)
			(size 1.2 0.5)
			(layers "F.Cu" "F.Mask" "F.Paste")
			(net 1 "GND")
			(pinfunction "16")
			(pintype "passive")
		)
		(pad "17" smd rect
			(at -2.15 -4.5 90)
			(size 0.7 0.7)
			(layers "F.Cu" "F.Mask" "F.Paste")
			(net 1 "GND")
			(pinfunction "17")
			(pintype "power_in")
		)
		(pad "17" smd rect
			(at -2.15 4.498 90)
			(size 0.7 0.7)
			(layers "F.Cu" "F.Mask" "F.Paste")
			(net 1 "GND")
			(pinfunction "17")
			(pintype "power_in")
		)
		(pad "17" smd rect
			(at 2.148 -4.5 90)
			(size 0.7 0.7)
			(layers "F.Cu" "F.Mask" "F.Paste")
			(net 1 "GND")
			(pinfunction "17")
			(pintype "power_in")
		)
		(pad "17" smd rect
			(at 2.148 4.498 90)
			(size 0.7 0.7)
			(layers "F.Cu" "F.Mask" "F.Paste")
			(net 1 "GND")
			(pinfunction "17")
			(pintype "power_in")
		)
	)
	(footprint "antmicro-footprints:DFN3538"
		(layer "F.Cu")
		(at 236.9 174.5 180)
		(property "Reference" "D4"
			(at 0.7 -3.3 0)
			(unlocked yes)
			(layer "F.SilkS")
			(effects
				(font
					(size 0.7 0.7)
					(thickness 0.15)
				)
				(justify left bottom)
			)
		)
		(property "Value" "CD-MMBL110S"
			(at 0 3.5 180)
			(unlocked yes)
			(layer "F.Fab")
			(effects
				(font
					(size 0.7 0.7)
					(thickness 0.15)
				)
				(justify left bottom)
			)
		)
		(property "Description" "TVS diode"
			(at 0 0 180)
			(layer "F.Fab")
			(hide yes)
			(effects
				(font
					(size 1.27 1.27)
					(thickness 0.15)
				)
			)
		)
		(property "Author" "Antmicro"
			(at 473.8 349 0)
			(layer "F.Fab")
			(hide yes)
			(effects
				(font
					(size 1 1)
					(thickness 0.15)
				)
			)
		)
		(property "License" "Apache-2.0"
			(at 473.8 349 0)
			(layer "F.Fab")
			(hide yes)
			(effects
				(font
					(size 1 1)
					(thickness 0.15)
				)
			)
		)
		(property "MPN" "CD-MMBL110S"
			(at 473.8 349 0)
			(layer "F.Fab")
			(hide yes)
			(effects
				(font
					(size 1 1)
					(thickness 0.15)
				)
			)
		)
		(property "Manufacturer" "Bourns"
			(at 473.8 349 0)
			(layer "F.Fab")
			(hide yes)
			(effects
				(font
					(size 1 1)
					(thickness 0.15)
				)
			)
		)
		(sheetname "Power supply")
		(sheetfile "power-supply.kicad_sch")
		(attr smd)
		(fp_line
			(start 1.8 -2)
			(end 1.8 2.05)
			(stroke
				(width 0.15)
				(type solid)
			)
			(layer "F.SilkS")
		)
		(fp_line
			(start 1.6 2.05)
			(end 1.8 2.05)
			(stroke
				(width 0.15)
				(type solid)
			)
			(layer "F.SilkS")
		)
		(fp_line
			(start 1.6 -2)
			(end 1.8 -2)
			(stroke
				(width 0.15)
				(type solid)
			)
			(layer "F.SilkS")
		)
		(fp_line
			(start 0.9 -2.301)
			(end 0.598 -2.301)
			(stroke
				(width 0.15)
				(type solid)
			)
			(layer "F.SilkS")
		)
		(fp_line
			(start 0.748 -2.452)
			(end 0.748 -2.15)
			(stroke
				(width 0.15)
				(type solid)
			)
			(layer "F.SilkS")
		)
		(fp_line
			(start -0.902 -2.25)
			(end -0.6 -2.25)
			(stroke
				(width 0.15)
				(type solid)
			)
			(layer "F.SilkS")
		)
		(fp_line
			(start -0.95 2.05)
			(end 0.95 2.05)
			(stroke
				(width 0.15)
				(type solid)
			)
			(layer "F.SilkS")
		)
		(fp_line
			(start -0.95 -2)
			(end 0.95 -2)
			(stroke
				(width 0.15)
				(type solid)
			)
			(layer "F.SilkS")
		)
		(fp_line
			(start -1.8 2.05)
			(end -1.6 2.05)
			(stroke
				(width 0.15)
				(type solid)
			)
			(layer "F.SilkS")
		)
		(fp_line
			(start -1.8 -1.5)
			(end -1.8 2.05)
			(stroke
				(width 0.15)
				(type solid)
			)
			(layer "F.SilkS")
		)
		(fp_rect
			(start -2.1 -2.6)
			(end 2.1 2.6)
			(stroke
				(width 0.05)
				(type solid)
			)
			(fill no)
			(layer "F.CrtYd")
		)
		(fp_line
			(start -1.051 -2)
			(end -1.801 -1.25)
			(stroke
				(width 0.15)
				(type solid)
			)
			(layer "F.Fab")
		)
		(fp_rect
			(start 1.8 2.048)
			(end -1.8 -2)
			(stroke
				(width 0.15)
				(type solid)
			)
			(fill no)
			(layer "F.Fab")
		)
		(fp_text user "~"
			(at -0.31 2.59 180)
			(unlocked yes)
			(layer "F.SilkS")
			(effects
				(font
					(size 0.7 0.7)
					(thickness 0.15)
				)
				(justify left bottom)
			)
		)
		(pad "1" smd roundrect
			(at -1.27 -1.85 270)
			(size 1.4 0.48)
			(layers "F.Cu" "F.Mask" "F.Paste")
			(roundrect_rratio 0.25)
			(net 756 "Net-(D4-Pad1)")
			(pinfunction "1")
			(pintype "output")
		)
		(pad "2" smd roundrect
			(at 1.27 -1.85 270)
			(size 1.4 0.48)
			(layers "F.Cu" "F.Mask" "F.Paste")
			(roundrect_rratio 0.25)
			(net 757 "Net-(D4-Pad2)")
			(pinfunction "2")
			(pintype "output")
		)
		(pad "3" smd roundrect
			(at -1.27 1.85 270)
			(size 1.4 0.48)
			(layers "F.Cu" "F.Mask" "F.Paste")
			(roundrect_rratio 0.25)
			(net 759 "/HDMI + Ethernet/POE_GBE.VC2")
			(pinfunction "3")
			(pintype "input")
		)
		(pad "4" smd roundrect
			(at 1.27 1.85 270)
			(size 1.4 0.48)
			(layers "F.Cu" "F.Mask" "F.Paste")
			(roundrect_rratio 0.25)
			(net 758 "/HDMI + Ethernet/POE_GBE.VC1")
			(pinfunction "4")
			(pintype "input")
		)
	)
	(footprint "antmicro-footprints:R_0402_1005Metric"
		(layer "F.Cu")
		(at 246.6 141.6 -90)
		(descr "Resistor SMD 0402")
		(tags "resistor SMD 0402")
		(property "Reference" "R164"
			(at 1.65 -6.35 270)
			(layer "F.SilkS")
			(effects
				(font
					(size 0.7 0.7)
					(thickness 0.15)
				)
				(justify left bottom)
			)
		)
		(property "Value" "R_33R_0402"
			(at 0 1.4 270)
			(layer "F.Fab")
			(effects
				(font
					(size 0.7 0.7)
					(thickness 0.15)
				)
				(justify left bottom)
			)
		)
		(property "Description" "SMD Chip Resistor, 33 ohm, ± 1%, 62.5 mW, 0402 [1005 Metric], Thick Film, General Purpose"
			(at 0 0 270)
			(layer "F.Fab")
			(hide yes)
			(effects
				(font
					(size 1.27 1.27)
					(thickness 0.15)
				)
			)
		)
		(property "Author" "Antmicro"
			(at 105 388.2 0)
			(layer "F.Fab")
			(hide yes)
			(effects
				(font
					(size 1 1)
					(thickness 0.15)
				)
			)
		)
		(property "License" "Apache-2.0"
			(at 105 388.2 0)
			(layer "F.Fab")
			(hide yes)
			(effects
				(font
					(size 1 1)
					(thickness 0.15)
				)
			)
		)
		(property "MPN" "CR0402-FX-33R0GLF"
			(at 105 388.2 0)
			(layer "F.Fab")
			(hide yes)
			(effects
				(font
					(size 1 1)
					(thickness 0.15)
				)
			)
		)
		(property "Manufacturer" "Bourns"
			(at 105 388.2 0)
			(layer "F.Fab")
			(hide yes)
			(effects
				(font
					(size 1 1)
					(thickness 0.15)
				)
			)
		)
		(property "Tolerance" "1%"
			(at 105 388.2 0)
			(layer "F.Fab")
			(hide yes)
			(effects
				(font
					(size 1 1)
					(thickness 0.15)
				)
			)
		)
		(property "Val" "33R"
			(at 105 388.2 0)
			(layer "F.Fab")
			(hide yes)
			(effects
				(font
					(size 1 1)
					(thickness 0.15)
				)
			)
		)
		(sheetname "USB PHY")
		(sheetfile "usb-phy.kicad_sch")
		(attr smd)
		(fp_rect
			(start -0.925 -0.47)
			(end 0.925 0.47)
			(stroke
				(width 0.05)
				(type default)
			)
			(fill no)
			(layer "F.CrtYd")
		)
		(fp_rect
			(start -0.5 -0.25)
			(end 0.5 0.25)
			(stroke
				(width 0.15)
				(type solid)
			)
			(fill no)
			(layer "F.Fab")
		)
		(pad "1" smd roundrect
			(at -0.48 0 270)
			(size 0.59 0.64)
			(layers "F.Cu" "F.Mask" "F.Paste")
			(roundrect_rratio 0.25)
			(net 924 "/USB PHY/FTDI_UART1_RX")
			(pintype "passive")
		)
		(pad "2" smd roundrect
			(at 0.48 0 270)
			(size 0.59 0.64)
			(layers "F.Cu" "F.Mask" "F.Paste")
			(roundrect_rratio 0.25)
			(net 54 "/FPGA Bank 12 & 13/UART1.TX")
			(pintype "passive")
		)
	)
	(footprint "antmicro-footprints:R_0402_1005Metric"
		(layer "F.Cu")
		(at 225.1 111.2)
		(descr "Resistor SMD 0402")
		(tags "resistor SMD 0402")
		(property "Reference" "R95"
			(at -3.65 0.4 0)
			(layer "F.SilkS")
			(effects
				(font
					(size 0.7 0.7)
					(thickness 0.15)
				)
				(justify left bottom)
			)
		)
		(property "Value" "R_10k_0402"
			(at 0 1.4 0)
			(layer "F.Fab")
			(effects
				(font
					(size 0.7 0.7)
					(thickness 0.15)
				)
				(justify left bottom)
			)
		)
		(property "Description" "SMD Chip Resistor, 10 kohm, ± 1%, 62.5 mW, 0402 [1005 Metric], Thick Film, General Purpose"
			(at 0 0 0)
			(layer "F.Fab")
			(hide yes)
			(effects
				(font
					(size 1.27 1.27)
					(thickness 0.15)
				)
			)
		)
		(property "Author" "Antmicro"
			(at 0 0 0)
			(layer "F.Fab")
			(hide yes)
			(effects
				(font
					(size 1 1)
					(thickness 0.15)
				)
			)
		)
		(property "License" "Apache-2.0"
			(at 0 0 0)
			(layer "F.Fab")
			(hide yes)
			(effects
				(font
					(size 1 1)
					(thickness 0.15)
				)
			)
		)
		(property "MPN" "CR0402-FX-1002GLF"
			(at 0 0 0)
			(layer "F.Fab")
			(hide yes)
			(effects
				(font
					(size 1 1)
					(thickness 0.15)
				)
			)
		)
		(property "Manufacturer" "Bourns"
			(at 0 0 0)
			(layer "F.Fab")
			(hide yes)
			(effects
				(font
					(size 1 1)
					(thickness 0.15)
				)
			)
		)
		(property "Tolerance" "1%"
			(at 0 0 0)
			(layer "F.Fab")
			(hide yes)
			(effects
				(font
					(size 1 1)
					(thickness 0.15)
				)
			)
		)
		(property "Val" "10k"
			(at 0 0 0)
			(layer "F.Fab")
			(hide yes)
			(effects
				(font
					(size 1 1)
					(thickness 0.15)
				)
			)
		)
		(sheetname "SPI Flash + SD Card")
		(sheetfile "spi-flash.kicad_sch")
		(attr smd)
		(fp_rect
			(start -0.925 -0.47)
			(end 0.925 0.47)
			(stroke
				(width 0.05)
				(type default)
			)
			(fill no)
			(layer "F.CrtYd")
		)
		(fp_rect
			(start -0.5 -0.25)
			(end 0.5 0.25)
			(stroke
				(width 0.15)
				(type solid)
			)
			(fill no)
			(layer "F.Fab")
		)
		(pad "1" smd roundrect
			(at -0.48 0)
			(size 0.59 0.64)
			(layers "F.Cu" "F.Mask" "F.Paste")
			(roundrect_rratio 0.25)
			(net 420 "/FPGA Bank 16 & 17/USR_FLASH_1.~{CS}")
			(pintype "passive")
		)
		(pad "2" smd roundrect
			(at 0.48 0)
			(size 0.59 0.64)
			(layers "F.Cu" "F.Mask" "F.Paste")
			(roundrect_rratio 0.25)
			(net 3 "VCC_USR_B")
			(pintype "passive")
		)
	)
	(footprint "antmicro-footprints:C_0603_1608Metric"
		(layer "F.Cu")
		(at 188.1 169.249 -90)
		(descr "Capacitor SMD 0603")
		(tags "capacitor 0603")
		(property "Reference" "C207"
			(at -3.849 -0.4 90)
			(layer "F.SilkS")
			(effects
				(font
					(size 0.7 0.7)
					(thickness 0.15)
				)
				(justify right bottom)
			)
		)
		(property "Value" "C_1u_25V_0603"
			(at 0 1.6 90)
			(layer "F.Fab")
			(effects
				(font
					(size 0.7 0.7)
					(thickness 0.15)
				)
				(justify right bottom)
			)
		)
		(property "Description" "SMD Multilayer Ceramic Capacitor, 1 µF, 25 V, 0603 [1608 Metric], ± 10%, X5R, CL"
			(at 0 0 270)
			(layer "F.Fab")
			(hide yes)
			(effects
				(font
					(size 1.27 1.27)
					(thickness 0.15)
				)
			)
		)
		(property "Author" "Antmicro"
			(at 18.851 357.349 0)
			(layer "F.Fab")
			(hide yes)
			(effects
				(font
					(size 1 1)
					(thickness 0.15)
				)
			)
		)
		(property "Dielectric" ""
			(at 18.851 357.349 0)
			(layer "F.Fab")
			(hide yes)
			(effects
				(font
					(size 1 1)
					(thickness 0.15)
				)
			)
		)
		(property "License" "Apache-2.0"
			(at 18.851 357.349 0)
			(layer "F.Fab")
			(hide yes)
			(effects
				(font
					(size 1 1)
					(thickness 0.15)
				)
			)
		)
		(property "MPN" "CL10A105KA8NNNC"
			(at 18.851 357.349 0)
			(layer "F.Fab")
			(hide yes)
			(effects
				(font
					(size 1 1)
					(thickness 0.15)
				)
			)
		)
		(property "Manufacturer" "Samsung Electro-Mechanics"
			(at 18.851 357.349 0)
			(layer "F.Fab")
			(hide yes)
			(effects
				(font
					(size 1 1)
					(thickness 0.15)
				)
			)
		)
		(property "Val" "1u"
			(at 18.851 357.349 0)
			(layer "F.Fab")
			(hide yes)
			(effects
				(font
					(size 1 1)
					(thickness 0.15)
				)
			)
		)
		(property "Voltage" "25V"
			(at 18.851 357.349 0)
			(layer "F.Fab")
			(hide yes)
			(effects
				(font
					(size 1 1)
					(thickness 0.15)
				)
			)
		)
		(sheetname "Power supply")
		(sheetfile "power-supply.kicad_sch")
		(attr smd)
		(fp_line
			(start -0.15 0.4)
			(end 0.15 0.4)
			(stroke
				(width 0.15)
				(type solid)
			)
			(layer "F.SilkS")
		)
		(fp_line
			(start -0.15 -0.4)
			(end 0.15 -0.4)
			(stroke
				(width 0.15)
				(type solid)
			)
			(layer "F.SilkS")
		)
		(fp_rect
			(start -1.25 -0.65)
			(end 1.25 0.65)
			(stroke
				(width 0.05)
				(type solid)
			)
			(fill no)
			(layer "F.CrtYd")
		)
		(fp_rect
			(start -0.8 -0.4)
			(end 0.8 0.4)
			(stroke
				(width 0.15)
				(type solid)
			)
			(fill no)
			(layer "F.Fab")
		)
		(pad "1" smd roundrect
			(at -0.7 0 270)
			(size 0.8 1)
			(layers "F.Cu" "F.Mask" "F.Paste")
			(roundrect_rratio 0.2)
			(net 1 "GND")
			(pintype "passive")
		)
		(pad "2" smd roundrect
			(at 0.7 0 270)
			(size 0.8 1)
			(layers "F.Cu" "F.Mask" "F.Paste")
			(roundrect_rratio 0.2)
			(net 702 "VDC")
			(pintype "passive")
		)
	)
	(footprint "antmicro-footprints:C_0603_1608Metric"
		(layer "F.Cu")
		(at 177.5 164)
		(descr "Capacitor SMD 0603")
		(tags "capacitor 0603")
		(property "Reference" "C331"
			(at 1 0.4 0)
			(layer "F.SilkS")
			(effects
				(font
					(size 0.7 0.7)
					(thickness 0.15)
				)
				(justify left bottom)
			)
		)
		(property "Value" "C_22u_0603"
			(at 0 1.6 0)
			(layer "F.Fab")
			(effects
				(font
					(size 0.7 0.7)
					(thickness 0.15)
				)
				(justify left bottom)
			)
		)
		(property "Description" "SMD Multilayer Ceramic Capacitor, 22 µF, 6.3 V, 0603 [1608 Metric], ± 20%, X5R, GRM Series"
			(at 0 0 0)
			(layer "F.Fab")
			(hide yes)
			(effects
				(font
					(size 1.27 1.27)
					(thickness 0.15)
				)
			)
		)
		(property "Author" "Antmicro"
			(at 0 0 0)
			(layer "F.Fab")
			(hide yes)
			(effects
				(font
					(size 1 1)
					(thickness 0.15)
				)
			)
		)
		(property "Dielectric" ""
			(at 0 0 0)
			(layer "F.Fab")
			(hide yes)
			(effects
				(font
					(size 1 1)
					(thickness 0.15)
				)
			)
		)
		(property "License" "Apache-2.0"
			(at 0 0 0)
			(layer "F.Fab")
			(hide yes)
			(effects
				(font
					(size 1 1)
					(thickness 0.15)
				)
			)
		)
		(property "MPN" "GRM188R60J226MEA0D"
			(at 0 0 0)
			(layer "F.Fab")
			(hide yes)
			(effects
				(font
					(size 1 1)
					(thickness 0.15)
				)
			)
		)
		(property "Manufacturer" "Murata"
			(at 0 0 0)
			(layer "F.Fab")
			(hide yes)
			(effects
				(font
					(size 1 1)
					(thickness 0.15)
				)
			)
		)
		(property "Val" "22u"
			(at 0 0 0)
			(layer "F.Fab")
			(hide yes)
			(effects
				(font
					(size 1 1)
					(thickness 0.15)
				)
			)
		)
		(property "Voltage" ""
			(at 0 0 0)
			(layer "F.Fab")
			(hide yes)
			(effects
				(font
					(size 1 1)
					(thickness 0.15)
				)
			)
		)
		(sheetname "DC-DC Converters")
		(sheetfile "dc-dc.kicad_sch")
		(attr smd)
		(fp_line
			(start -0.15 -0.4)
			(end 0.15 -0.4)
			(stroke
				(width 0.15)
				(type solid)
			)
			(layer "F.SilkS")
		)
		(fp_line
			(start -0.15 0.4)
			(end 0.15 0.4)
			(stroke
				(width 0.15)
				(type solid)
			)
			(layer "F.SilkS")
		)
		(fp_rect
			(start -1.25 -0.65)
			(end 1.25 0.65)
			(stroke
				(width 0.05)
				(type solid)
			)
			(fill no)
			(layer "F.CrtYd")
		)
		(fp_rect
			(start -0.8 -0.4)
			(end 0.8 0.4)
			(stroke
				(width 0.15)
				(type solid)
			)
			(fill no)
			(layer "F.Fab")
		)
		(pad "1" smd roundrect
			(at -0.7 0)
			(size 0.8 1)
			(layers "F.Cu" "F.Mask" "F.Paste")
			(roundrect_rratio 0.2)
			(net 1 "GND")
			(pintype "passive")
		)
		(pad "2" smd roundrect
			(at 0.7 0)
			(size 0.8 1)
			(layers "F.Cu" "F.Mask" "F.Paste")
			(roundrect_rratio 0.2)
			(net 736 "/DC-DC Converters/3V3_local_2")
			(pintype "passive")
		)
	)
	(footprint "antmicro-footprints:C_2220_5650Metric"
		(layer "F.Cu")
		(at 234.075 185.575 90)
		(descr "Capacitor SMD 2220")
		(tags "capacitor SMD 2220")
		(property "Reference" "C199"
			(at 3.675 -1.425 180)
			(layer "F.SilkS")
			(effects
				(font
					(size 0.7 0.7)
					(thickness 0.15)
				)
				(justify left bottom)
			)
		)
		(property "Value" "C_22u_100V_2220"
			(at 0 3.9 90)
			(layer "F.Fab")
			(effects
				(font
					(size 0.7 0.7)
					(thickness 0.15)
				)
				(justify left bottom)
			)
		)
		(property "Description" "SMT Multilayer Ceramic Capacitor, 22 µF, 100 V, 2220 [5750 Metric], ± 20%, X7S, C"
			(at 0 0 90)
			(layer "F.Fab")
			(hide yes)
			(effects
				(font
					(size 1.27 1.27)
					(thickness 0.15)
				)
			)
		)
		(property "Author" "Antmicro"
			(at 419.65 -48.5 0)
			(layer "F.Fab")
			(hide yes)
			(effects
				(font
					(size 1 1)
					(thickness 0.15)
				)
			)
		)
		(property "Dielectric" "X7S"
			(at 419.65 -48.5 0)
			(layer "F.Fab")
			(hide yes)
			(effects
				(font
					(size 1 1)
					(thickness 0.15)
				)
			)
		)
		(property "License" "Apache-2.0"
			(at 419.65 -48.5 0)
			(layer "F.Fab")
			(hide yes)
			(effects
				(font
					(size 1 1)
					(thickness 0.15)
				)
			)
		)
		(property "MPN" "C5750X7S2A226M280KB"
			(at 419.65 -48.5 0)
			(layer "F.Fab")
			(hide yes)
			(effects
				(font
					(size 1 1)
					(thickness 0.15)
				)
			)
		)
		(property "Manufacturer" "TDK"
			(at 419.65 -48.5 0)
			(layer "F.Fab")
			(hide yes)
			(effects
				(font
					(size 1 1)
					(thickness 0.15)
				)
			)
		)
		(property "Val" "22u"
			(at 419.65 -48.5 0)
			(layer "F.Fab")
			(hide yes)
			(effects
				(font
					(size 1 1)
					(thickness 0.15)
				)
			)
		)
		(property "Voltage" "100V"
			(at 419.65 -48.5 0)
			(layer "F.Fab")
			(hide yes)
			(effects
				(font
					(size 1 1)
					(thickness 0.15)
				)
			)
		)
		(sheetname "Power supply")
		(sheetfile "power-supply.kicad_sch")
		(attr smd)
		(fp_line
			(start -1.415 -2.61)
			(end 1.415 -2.61)
			(stroke
				(width 0.15)
				(type solid)
			)
			(layer "F.SilkS")
		)
		(fp_line
			(start -1.415 2.61)
			(end 1.415 2.61)
			(stroke
				(width 0.15)
				(type solid)
			)
			(layer "F.SilkS")
		)
		(fp_rect
			(start -3.7 -2.95)
			(end 3.7 2.95)
			(stroke
				(width 0.05)
				(type solid)
			)
			(fill no)
			(layer "F.CrtYd")
		)
		(fp_rect
			(start -2.85 -2.5)
			(end 2.85 2.5)
			(stroke
				(width 0.15)
				(type solid)
			)
			(fill no)
			(layer "F.Fab")
		)
		(pad "1" smd roundrect
			(at -2.55 0 90)
			(size 1.8 5.4)
			(layers "F.Cu" "F.Mask" "F.Paste")
			(roundrect_rratio 0.138889)
			(net 699 "GNDD")
			(pintype "passive")
		)
		(pad "2" smd roundrect
			(at 2.55 0 90)
			(size 1.8 5.4)
			(layers "F.Cu" "F.Mask" "F.Paste")
			(roundrect_rratio 0.138889)
			(net 698 "/Power supply/VDD")
			(pintype "passive")
		)
	)
	(footprint "antmicro-footprints:C_0402_1005Metric"
		(layer "F.Cu")
		(at 168 176.1625 90)
		(descr "Capacitor SMD 0402")
		(tags "capacitor SMD 0402")
		(property "Reference" "C335"
			(at -1.4375 -0.45 90)
			(layer "F.SilkS")
			(effects
				(font
					(size 0.7 0.7)
					(thickness 0.15)
				)
				(justify left bottom)
			)
		)
		(property "Value" "C_1u_0402"
			(at 0 1.4 90)
			(layer "F.Fab")
			(effects
				(font
					(size 0.7 0.7)
					(thickness 0.15)
				)
				(justify left bottom)
			)
		)
		(property "Description" "SMD Multilayer Ceramic Capacitor, 1 µF, 10 V, 0402 [1005 Metric], ± 10%, X6S, C"
			(at 0 0 90)
			(layer "F.Fab")
			(hide yes)
			(effects
				(font
					(size 1.27 1.27)
					(thickness 0.15)
				)
			)
		)
		(property "Author" "Antmicro"
			(at 344.1625 8.1625 0)
			(layer "F.Fab")
			(hide yes)
			(effects
				(font
					(size 1 1)
					(thickness 0.15)
				)
			)
		)
		(property "DNP" "DNP"
			(at 344.1625 8.1625 0)
			(layer "F.Fab")
			(hide yes)
			(effects
				(font
					(size 1 1)
					(thickness 0.15)
				)
			)
		)
		(property "Dielectric" ""
			(at 344.1625 8.1625 0)
			(layer "F.Fab")
			(hide yes)
			(effects
				(font
					(size 1 1)
					(thickness 0.15)
				)
			)
		)
		(property "License" "Apache-2.0"
			(at 344.1625 8.1625 0)
			(layer "F.Fab")
			(hide yes)
			(effects
				(font
					(size 1 1)
					(thickness 0.15)
				)
			)
		)
		(property "MPN" "C1005X6S1A105K050BC"
			(at 344.1625 8.1625 0)
			(layer "F.Fab")
			(hide yes)
			(effects
				(font
					(size 1 1)
					(thickness 0.15)
				)
			)
		)
		(property "Manufacturer" "TDK"
			(at 344.1625 8.1625 0)
			(layer "F.Fab")
			(hide yes)
			(effects
				(font
					(size 1 1)
					(thickness 0.15)
				)
			)
		)
		(property "Val" "1u"
			(at 344.1625 8.1625 0)
			(layer "F.Fab")
			(hide yes)
			(effects
				(font
					(size 1 1)
					(thickness 0.15)
				)
			)
		)
		(property "Voltage" ""
			(at 344.1625 8.1625 0)
			(layer "F.Fab")
			(hide yes)
			(effects
				(font
					(size 1 1)
					(thickness 0.15)
				)
			)
		)
		(property "dnp" ""
			(at 344.1625 8.1625 0)
			(layer "F.Fab")
			(hide yes)
			(effects
				(font
					(size 1 1)
					(thickness 0.15)
				)
			)
		)
		(property "exclude_from_bom" ""
			(at 344.1625 8.1625 0)
			(layer "F.Fab")
			(hide yes)
			(effects
				(font
					(size 1 1)
					(thickness 0.15)
				)
			)
		)
		(sheetname "DC-DC Converters")
		(sheetfile "dc-dc.kicad_sch")
		(attr smd exclude_from_bom)
		(fp_rect
			(start -0.925 -0.47)
			(end 0.925 0.47)
			(stroke
				(width 0.05)
				(type default)
			)
			(fill no)
			(layer "F.CrtYd")
		)
		(fp_line
			(start 0.504 -0.25)
			(end 0.504 0.248)
			(stroke
				(width 0.15)
				(type solid)
			)
			(layer "F.Fab")
		)
		(fp_line
			(start -0.494 -0.25)
			(end 0.504 -0.25)
			(stroke
				(width 0.15)
				(type solid)
			)
			(layer "F.Fab")
		)
		(fp_line
			(start 0.504 0.248)
			(end -0.494 0.248)
			(stroke
				(width 0.15)
				(type solid)
			)
			(layer "F.Fab")
		)
		(fp_line
			(start -0.494 0.248)
			(end -0.494 -0.25)
			(stroke
				(width 0.15)
				(type solid)
			)
			(layer "F.Fab")
		)
		(pad "1" smd roundrect
			(at -0.48 0 90)
			(size 0.59 0.64)
			(layers "F.Cu" "F.Mask" "F.Paste")
			(roundrect_rratio 0.25)
			(net 1 "GND")
			(pintype "passive")
		)
		(pad "2" smd roundrect
			(at 0.48 0 90)
			(size 0.59 0.64)
			(layers "F.Cu" "F.Mask" "F.Paste")
			(roundrect_rratio 0.25)
			(net 25 "+1V35")
			(pintype "passive")
		)
	)
	(footprint "antmicro-footprints:R_0402_1005Metric"
		(layer "F.Cu")
		(at 155.8125 175.7 180)
		(descr "Resistor SMD 0402")
		(tags "resistor SMD 0402")
		(property "Reference" "R311"
			(at 0.6625 -4.7 270)
			(layer "F.SilkS")
			(effects
				(font
					(size 0.7 0.7)
					(thickness 0.15)
				)
				(justify left bottom)
			)
		)
		(property "Value" "R_0R_0402"
			(at 0 1.4 180)
			(layer "F.Fab")
			(effects
				(font
					(size 0.7 0.7)
					(thickness 0.15)
				)
				(justify left bottom)
			)
		)
		(property "Description" "SMD Chip Resistor, Jumper, 0 ohm, 100 mW, 0402 [1005 Metric], Thick Film, General Purpose"
			(at 0 0 180)
			(layer "F.Fab")
			(hide yes)
			(effects
				(font
					(size 1.27 1.27)
					(thickness 0.15)
				)
			)
		)
		(property "Author" "Antmicro"
			(at 311.625 351.4 0)
			(layer "F.Fab")
			(hide yes)
			(effects
				(font
					(size 1 1)
					(thickness 0.15)
				)
			)
		)
		(property "Current" "1A"
			(at 311.625 351.4 0)
			(layer "F.Fab")
			(hide yes)
			(effects
				(font
					(size 1 1)
					(thickness 0.15)
				)
			)
		)
		(property "License" "Apache-2.0"
			(at 311.625 351.4 0)
			(layer "F.Fab")
			(hide yes)
			(effects
				(font
					(size 1 1)
					(thickness 0.15)
				)
			)
		)
		(property "MPN" "ERJ2GE0R00X"
			(at 311.625 351.4 0)
			(layer "F.Fab")
			(hide yes)
			(effects
				(font
					(size 1 1)
					(thickness 0.15)
				)
			)
		)
		(property "Manufacturer" "Panasonic"
			(at 311.625 351.4 0)
			(layer "F.Fab")
			(hide yes)
			(effects
				(font
					(size 1 1)
					(thickness 0.15)
				)
			)
		)
		(property "Tolerance" ""
			(at 311.625 351.4 0)
			(layer "F.Fab")
			(hide yes)
			(effects
				(font
					(size 1 1)
					(thickness 0.15)
				)
			)
		)
		(property "Val" "0R"
			(at 311.625 351.4 0)
			(layer "F.Fab")
			(hide yes)
			(effects
				(font
					(size 1 1)
					(thickness 0.15)
				)
			)
		)
		(sheetname "DC-DC Converters")
		(sheetfile "dc-dc.kicad_sch")
		(attr smd)
		(fp_rect
			(start -0.925 -0.47)
			(end 0.925 0.47)
			(stroke
				(width 0.05)
				(type default)
			)
			(fill no)
			(layer "F.CrtYd")
		)
		(fp_rect
			(start -0.5 -0.25)
			(end 0.5 0.25)
			(stroke
				(width 0.15)
				(type solid)
			)
			(fill no)
			(layer "F.Fab")
		)
		(pad "1" smd roundrect
			(at -0.48 0 180)
			(size 0.59 0.64)
			(layers "F.Cu" "F.Mask" "F.Paste")
			(roundrect_rratio 0.25)
			(net 963 "/DC-DC Converters/FB4")
			(pintype "passive")
		)
		(pad "2" smd roundrect
			(at 0.48 0 180)
			(size 0.59 0.64)
			(layers "F.Cu" "F.Mask" "F.Paste")
			(roundrect_rratio 0.25)
			(net 738 "/DC-DC Converters/1V7_local")
			(pintype "passive")
		)
	)
	(footprint "antmicro-footprints:FB_0603_1608Metric"
		(layer "F.Cu")
		(at 220.603 154.66 180)
		(property "Reference" "FB8"
			(at 1.003 -1.44 180)
			(layer "F.SilkS")
			(effects
				(font
					(size 0.7 0.7)
					(thickness 0.15)
				)
				(justify left bottom)
			)
		)
		(property "Value" "FB_120Z_2A_Murata-BLM18PG_0603"
			(at 0 1.7 180)
			(layer "F.Fab")
			(effects
				(font
					(size 0.7 0.7)
					(thickness 0.15)
				)
				(justify left bottom)
			)
		)
		(property "Description" "Ferrite Bead, 0603 [1608 Metric], 120 ohm, 2 A, BLM18P, 0.05 ohm, ± 25%, DC power line"
			(at 0 0 180)
			(layer "F.Fab")
			(hide yes)
			(effects
				(font
					(size 1.27 1.27)
					(thickness 0.15)
				)
			)
		)
		(property "Author" "Antmicro"
			(at 441.206 309.32 0)
			(layer "F.Fab")
			(hide yes)
			(effects
				(font
					(size 1 1)
					(thickness 0.15)
				)
			)
		)
		(property "Current" ""
			(at 441.206 309.32 0)
			(layer "F.Fab")
			(hide yes)
			(effects
				(font
					(size 1 1)
					(thickness 0.15)
				)
			)
		)
		(property "License" "Apache-2.0"
			(at 441.206 309.32 0)
			(layer "F.Fab")
			(hide yes)
			(effects
				(font
					(size 1 1)
					(thickness 0.15)
				)
			)
		)
		(property "MPN" "BLM18PG121SN1D"
			(at 441.206 309.32 0)
			(layer "F.Fab")
			(hide yes)
			(effects
				(font
					(size 1 1)
					(thickness 0.15)
				)
			)
		)
		(property "Manufacturer" "Murata"
			(at 441.206 309.32 0)
			(layer "F.Fab")
			(hide yes)
			(effects
				(font
					(size 1 1)
					(thickness 0.15)
				)
			)
		)
		(property "Val" "120Z/2A"
			(at 441.206 309.32 0)
			(layer "F.Fab")
			(hide yes)
			(effects
				(font
					(size 1 1)
					(thickness 0.15)
				)
			)
		)
		(sheetname "HDMI + Ethernet")
		(sheetfile "hdmi-ethernet.kicad_sch")
		(attr smd)
		(fp_line
			(start -0.15 0.4)
			(end 0.15 0.4)
			(stroke
				(width 0.15)
				(type solid)
			)
			(layer "F.SilkS")
		)
		(fp_line
			(start -0.15 -0.4)
			(end 0.15 -0.4)
			(stroke
				(width 0.15)
				(type solid)
			)
			(layer "F.SilkS")
		)
		(fp_rect
			(start -1.25 -0.65)
			(end 1.25 0.65)
			(stroke
				(width 0.05)
				(type solid)
			)
			(fill no)
			(layer "F.CrtYd")
		)
		(fp_line
			(start 0.8 0.406)
			(end -0.803 0.406)
			(stroke
				(width 0.15)
				(type solid)
			)
			(layer "F.Fab")
		)
		(fp_line
			(start 0.8 -0.408)
			(end 0.8 0.406)
			(stroke
				(width 0.15)
				(type solid)
			)
			(layer "F.Fab")
		)
		(fp_line
			(start 0.8 -0.408)
			(end -0.803 -0.408)
			(stroke
				(width 0.15)
				(type solid)
			)
			(layer "F.Fab")
		)
		(fp_line
			(start -0.803 0.406)
			(end -0.803 -0.408)
			(stroke
				(width 0.15)
				(type solid)
			)
			(layer "F.Fab")
		)
		(pad "1" smd roundrect
			(at -0.7 0 180)
			(size 0.8 1)
			(layers "F.Cu" "F.Mask" "F.Paste")
			(roundrect_rratio 0.2)
			(net 721 "/HDMI + Ethernet/ETH_3V3")
			(pintype "passive")
		)
		(pad "2" smd roundrect
			(at 0.7 0 180)
			(size 0.8 1)
			(layers "F.Cu" "F.Mask" "F.Paste")
			(roundrect_rratio 0.2)
			(net 24 "+3V3")
			(pintype "passive")
		)
	)
	(footprint "antmicro-footprints:R_0402_1005Metric"
		(layer "F.Cu")
		(at 157.775 156.515 90)
		(descr "Resistor SMD 0402")
		(tags "resistor SMD 0402")
		(property "Reference" "R323"
			(at -3.685 0.425 90)
			(layer "F.SilkS")
			(effects
				(font
					(size 0.7 0.7)
					(thickness 0.15)
				)
				(justify left bottom)
			)
		)
		(property "Value" "R_10k_0402"
			(at 0 1.4 90)
			(layer "F.Fab")
			(effects
				(font
					(size 0.7 0.7)
					(thickness 0.15)
				)
				(justify left bottom)
			)
		)
		(property "Description" "SMD Chip Resistor, 10 kohm, ± 1%, 62.5 mW, 0402 [1005 Metric], Thick Film, General Purpose"
			(at 0 0 90)
			(layer "F.Fab")
			(hide yes)
			(effects
				(font
					(size 1.27 1.27)
					(thickness 0.15)
				)
			)
		)
		(property "Author" "Antmicro"
			(at 314.29 -1.26 0)
			(layer "F.Fab")
			(hide yes)
			(effects
				(font
					(size 1 1)
					(thickness 0.15)
				)
			)
		)
		(property "License" "Apache-2.0"
			(at 314.29 -1.26 0)
			(layer "F.Fab")
			(hide yes)
			(effects
				(font
					(size 1 1)
					(thickness 0.15)
				)
			)
		)
		(property "MPN" "CR0402-FX-1002GLF"
			(at 314.29 -1.26 0)
			(layer "F.Fab")
			(hide yes)
			(effects
				(font
					(size 1 1)
					(thickness 0.15)
				)
			)
		)
		(property "Manufacturer" "Bourns"
			(at 314.29 -1.26 0)
			(layer "F.Fab")
			(hide yes)
			(effects
				(font
					(size 1 1)
					(thickness 0.15)
				)
			)
		)
		(property "Tolerance" "1%"
			(at 314.29 -1.26 0)
			(layer "F.Fab")
			(hide yes)
			(effects
				(font
					(size 1 1)
					(thickness 0.15)
				)
			)
		)
		(property "Val" "10k"
			(at 314.29 -1.26 0)
			(layer "F.Fab")
			(hide yes)
			(effects
				(font
					(size 1 1)
					(thickness 0.15)
				)
			)
		)
		(sheetname "DC-DC Converters")
		(sheetfile "dc-dc.kicad_sch")
		(attr smd)
		(fp_rect
			(start -0.925 -0.47)
			(end 0.925 0.47)
			(stroke
				(width 0.05)
				(type default)
			)
			(fill no)
			(layer "F.CrtYd")
		)
		(fp_rect
			(start -0.5 -0.25)
			(end 0.5 0.25)
			(stroke
				(width 0.15)
				(type solid)
			)
			(fill no)
			(layer "F.Fab")
		)
		(pad "1" smd roundrect
			(at -0.48 0 90)
			(size 0.59 0.64)
			(layers "F.Cu" "F.Mask" "F.Paste")
			(roundrect_rratio 0.25)
			(net 744 "/DC-DC Converters/VDDR_VRI")
			(pintype "passive")
		)
		(pad "2" smd roundrect
			(at 0.48 0 90)
			(size 0.59 0.64)
			(layers "F.Cu" "F.Mask" "F.Paste")
			(roundrect_rratio 0.25)
			(net 25 "+1V35")
			(pintype "passive")
		)
	)
	(footprint "antmicro-footprints:R_0402_1005Metric"
		(layer "F.Cu")
		(at 156.225 157)
		(descr "Resistor SMD 0402")
		(tags "resistor SMD 0402")
		(property "Reference" "R324"
			(at -1.875 2.35 0)
			(layer "F.SilkS")
			(effects
				(font
					(size 0.7 0.7)
					(thickness 0.15)
				)
				(justify left bottom)
			)
		)
		(property "Value" "R_10k_0402"
			(at 0 1.4 0)
			(layer "F.Fab")
			(effects
				(font
					(size 0.7 0.7)
					(thickness 0.15)
				)
				(justify left bottom)
			)
		)
		(property "Description" "SMD Chip Resistor, 10 kohm, ± 1%, 62.5 mW, 0402 [1005 Metric], Thick Film, General Purpose"
			(at 0 0 0)
			(layer "F.Fab")
			(hide yes)
			(effects
				(font
					(size 1.27 1.27)
					(thickness 0.15)
				)
			)
		)
		(property "Author" "Antmicro"
			(at 0 0 0)
			(layer "F.Fab")
			(hide yes)
			(effects
				(font
					(size 1 1)
					(thickness 0.15)
				)
			)
		)
		(property "License" "Apache-2.0"
			(at 0 0 0)
			(layer "F.Fab")
			(hide yes)
			(effects
				(font
					(size 1 1)
					(thickness 0.15)
				)
			)
		)
		(property "MPN" "CR0402-FX-1002GLF"
			(at 0 0 0)
			(layer "F.Fab")
			(hide yes)
			(effects
				(font
					(size 1 1)
					(thickness 0.15)
				)
			)
		)
		(property "Manufacturer" "Bourns"
			(at 0 0 0)
			(layer "F.Fab")
			(hide yes)
			(effects
				(font
					(size 1 1)
					(thickness 0.15)
				)
			)
		)
		(property "Tolerance" "1%"
			(at 0 0 0)
			(layer "F.Fab")
			(hide yes)
			(effects
				(font
					(size 1 1)
					(thickness 0.15)
				)
			)
		)
		(property "Val" "10k"
			(at 0 0 0)
			(layer "F.Fab")
			(hide yes)
			(effects
				(font
					(size 1 1)
					(thickness 0.15)
				)
			)
		)
		(sheetname "DC-DC Converters")
		(sheetfile "dc-dc.kicad_sch")
		(attr smd)
		(fp_rect
			(start -0.925 -0.47)
			(end 0.925 0.47)
			(stroke
				(width 0.05)
				(type default)
			)
			(fill no)
			(layer "F.CrtYd")
		)
		(fp_rect
			(start -0.5 -0.25)
			(end 0.5 0.25)
			(stroke
				(width 0.15)
				(type solid)
			)
			(fill no)
			(layer "F.Fab")
		)
		(pad "1" smd roundrect
			(at -0.48 0)
			(size 0.59 0.64)
			(layers "F.Cu" "F.Mask" "F.Paste")
			(roundrect_rratio 0.25)
			(net 1 "GND")
			(pintype "passive")
		)
		(pad "2" smd roundrect
			(at 0.48 0)
			(size 0.59 0.64)
			(layers "F.Cu" "F.Mask" "F.Paste")
			(roundrect_rratio 0.25)
			(net 744 "/DC-DC Converters/VDDR_VRI")
			(pintype "passive")
		)
	)
	(footprint "antmicro-footprints:R_0402_1005Metric"
		(layer "F.Cu")
		(at 236.2 130.55 180)
		(descr "Resistor SMD 0402")
		(tags "resistor SMD 0402")
		(property "Reference" "R178"
			(at 1.825 3.525 180)
			(layer "F.SilkS")
			(effects
				(font
					(size 0.7 0.7)
					(thickness 0.15)
				)
				(justify left bottom)
			)
		)
		(property "Value" "R_33R_0402"
			(at 0 1.4 180)
			(layer "F.Fab")
			(effects
				(font
					(size 0.7 0.7)
					(thickness 0.15)
				)
				(justify left bottom)
			)
		)
		(property "Description" "SMD Chip Resistor, 33 ohm, ± 1%, 62.5 mW, 0402 [1005 Metric], Thick Film, General Purpose"
			(at 0 0 180)
			(layer "F.Fab")
			(hide yes)
			(effects
				(font
					(size 1.27 1.27)
					(thickness 0.15)
				)
			)
		)
		(property "Author" "Antmicro"
			(at 472.4 261.1 0)
			(layer "F.Fab")
			(hide yes)
			(effects
				(font
					(size 1 1)
					(thickness 0.15)
				)
			)
		)
		(property "License" "Apache-2.0"
			(at 472.4 261.1 0)
			(layer "F.Fab")
			(hide yes)
			(effects
				(font
					(size 1 1)
					(thickness 0.15)
				)
			)
		)
		(property "MPN" "CR0402-FX-33R0GLF"
			(at 472.4 261.1 0)
			(layer "F.Fab")
			(hide yes)
			(effects
				(font
					(size 1 1)
					(thickness 0.15)
				)
			)
		)
		(property "Manufacturer" "Bourns"
			(at 472.4 261.1 0)
			(layer "F.Fab")
			(hide yes)
			(effects
				(font
					(size 1 1)
					(thickness 0.15)
				)
			)
		)
		(property "Tolerance" "1%"
			(at 472.4 261.1 0)
			(layer "F.Fab")
			(hide yes)
			(effects
				(font
					(size 1 1)
					(thickness 0.15)
				)
			)
		)
		(property "Val" "33R"
			(at 472.4 261.1 0)
			(layer "F.Fab")
			(hide yes)
			(effects
				(font
					(size 1 1)
					(thickness 0.15)
				)
			)
		)
		(sheetname "USB PHY")
		(sheetfile "usb-phy.kicad_sch")
		(attr smd)
		(fp_rect
			(start -0.925 -0.47)
			(end 0.925 0.47)
			(stroke
				(width 0.05)
				(type default)
			)
			(fill no)
			(layer "F.CrtYd")
		)
		(fp_rect
			(start -0.5 -0.25)
			(end 0.5 0.25)
			(stroke
				(width 0.15)
				(type solid)
			)
			(fill no)
			(layer "F.Fab")
		)
		(pad "1" smd roundrect
			(at -0.48 0 180)
			(size 0.59 0.64)
			(layers "F.Cu" "F.Mask" "F.Paste")
			(roundrect_rratio 0.25)
			(net 370 "Net-(U22-B3Y)")
			(pintype "passive")
		)
		(pad "2" smd roundrect
			(at 0.48 0 180)
			(size 0.59 0.64)
			(layers "F.Cu" "F.Mask" "F.Paste")
			(roundrect_rratio 0.25)
			(net 220 "/FPGA Config/JTAG.TDI")
			(pintype "passive")
		)
	)
	(footprint "antmicro-footprints:DHVQFN-14-1EP_2.5x3mm"
		(layer "F.Cu")
		(at 239.6 137.7 180)
		(property "Reference" "U24"
			(at -2.625 -1.85 270)
			(layer "F.SilkS")
			(effects
				(font
					(size 0.7 0.7)
					(thickness 0.15)
				)
				(justify left bottom)
			)
		)
		(property "Value" "TXU0304BQAR"
			(at 0 2.898 180)
			(layer "F.Fab")
			(effects
				(font
					(size 0.7 0.7)
					(thickness 0.15)
				)
				(justify left bottom)
			)
		)
		(property "Description" "Logic translator/level shifter"
			(at 0 0 180)
			(layer "F.Fab")
			(hide yes)
			(effects
				(font
					(size 1.27 1.27)
					(thickness 0.15)
				)
			)
		)
		(property "Author" "Antmicro"
			(at 479.2 275.4 0)
			(layer "F.Fab")
			(hide yes)
			(effects
				(font
					(size 1 1)
					(thickness 0.15)
				)
			)
		)
		(property "License" "Apache-2.0"
			(at 479.2 275.4 0)
			(layer "F.Fab")
			(hide yes)
			(effects
				(font
					(size 1 1)
					(thickness 0.15)
				)
			)
		)
		(property "MPN" "TXU0304BQAR"
			(at 479.2 275.4 0)
			(layer "F.Fab")
			(hide yes)
			(effects
				(font
					(size 1 1)
					(thickness 0.15)
				)
			)
		)
		(property "Manufacturer" "Texas Instruments"
			(at 479.2 275.4 0)
			(layer "F.Fab")
			(hide yes)
			(effects
				(font
					(size 1 1)
					(thickness 0.15)
				)
			)
		)
		(sheetname "USB PHY")
		(sheetfile "usb-phy.kicad_sch")
		(attr smd)
		(fp_line
			(start 1.35 1.6)
			(end 1.35 1.249)
			(stroke
				(width 0.15)
				(type solid)
			)
			(layer "F.SilkS")
		)
		(fp_line
			(start 1.35 -1.601)
			(end 1.35 -1.25)
			(stroke
				(width 0.15)
				(type solid)
			)
			(layer "F.SilkS")
		)
		(fp_line
			(start 1.35 -1.601)
			(end 0.494 -1.601)
			(stroke
				(width 0.15)
				(type solid)
			)
			(layer "F.SilkS")
		)
		(fp_line
			(start 0.494 1.6)
			(end 1.35 1.6)
			(stroke
				(width 0.15)
				(type solid)
			)
			(layer "F.SilkS")
		)
		(fp_line
			(start -1.35 -1.601)
			(end -1.35 -1.25)
			(stroke
				(width 0.15)
				(type solid)
			)
			(layer "F.SilkS")
		)
		(fp_line
			(start -1.351 1.6)
			(end -0.5 1.6)
			(stroke
				(width 0.15)
				(type solid)
			)
			(layer "F.SilkS")
		)
		(fp_line
			(start -1.351 1.6)
			(end -1.351 1.249)
			(stroke
				(width 0.15)
				(type solid)
			)
			(layer "F.SilkS")
		)
		(fp_line
			(start -1.351 -1.601)
			(end -0.5 -1.601)
			(stroke
				(width 0.15)
				(type solid)
			)
			(layer "F.SilkS")
		)
		(fp_circle
			(center -0.7 -1.85)
			(end -0.653 -1.85)
			(stroke
				(width 0.15)
				(type solid)
			)
			(fill yes)
			(layer "F.SilkS")
		)
		(fp_rect
			(start -1.85 -2)
			(end 1.8 1.95)
			(stroke
				(width 0.05)
				(type solid)
			)
			(fill no)
			(layer "F.CrtYd")
		)
		(fp_line
			(start 1.249 1.499)
			(end -1.25 1.499)
			(stroke
				(width 0.15)
				(type solid)
			)
			(layer "F.Fab")
		)
		(fp_line
			(start 1.249 -1.5)
			(end 1.249 1.499)
			(stroke
				(width 0.15)
				(type solid)
			)
			(layer "F.Fab")
		)
		(fp_line
			(start -1 -1.5)
			(end 1.249 -1.5)
			(stroke
				(width 0.15)
				(type solid)
			)
			(layer "F.Fab")
		)
		(fp_line
			(start -1.25 1.499)
			(end -1.25 -1.25)
			(stroke
				(width 0.15)
				(type solid)
			)
			(layer "F.Fab")
		)
		(fp_line
			(start -1.25 -1.25)
			(end -1 -1.5)
			(stroke
				(width 0.15)
				(type solid)
			)
			(layer "F.Fab")
		)
		(pad "1" smd oval
			(at -0.25 -1.5 180)
			(size 0.3 0.8)
			(layers "F.Cu" "F.Mask" "F.Paste")
			(net 707 "/USB PHY/FTDI_3V3")
			(pinfunction "VCCA")
			(pintype "power_in")
		)
		(pad "2" smd oval
			(at -1.25 -1 270)
			(size 0.3 0.8)
			(layers "F.Cu" "F.Mask" "F.Paste")
			(net 1023 "/USB PHY/BDBUS0")
			(pinfunction "A1")
			(pintype "input")
		)
		(pad "3" smd oval
			(at -1.25 -0.5 270)
			(size 0.3 0.8)
			(layers "F.Cu" "F.Mask" "F.Paste")
			(net 1 "GND")
			(pinfunction "A2")
			(pintype "input")
		)
		(pad "4" smd oval
			(at -1.25 0 270)
			(size 0.3 0.8)
			(layers "F.Cu" "F.Mask" "F.Paste")
			(net 1024 "/USB PHY/BDBUS1")
			(pinfunction "A3")
			(pintype "input")
		)
		(pad "5" smd oval
			(at -1.25 0.494 270)
			(size 0.3 0.8)
			(layers "F.Cu" "F.Mask" "F.Paste")
			(net 1025 "/USB PHY/BDBUS2")
			(pinfunction "A4Y")
			(pintype "output")
		)
		(pad "6" smd oval
			(at -1.25 0.994 270)
			(size 0.3 0.8)
			(layers "F.Cu" "F.Mask" "F.Paste")
			(net 1306 "unconnected-(U24-NC-Pad6)")
			(pinfunction "NC")
			(pintype "no_connect")
		)
		(pad "7" smd oval
			(at -0.25 1.499 180)
			(size 0.3 0.8)
			(layers "F.Cu" "F.Mask" "F.Paste")
			(net 1 "GND")
			(pinfunction "GND")
			(pintype "passive")
		)
		(pad "8" smd oval
			(at 0.244 1.499 180)
			(size 0.3 0.8)
			(layers "F.Cu" "F.Mask" "F.Paste")
			(net 379 "Net-(U24-OE)")
			(pinfunction "OE")
			(pintype "tri_state")
		)
		(pad "9" smd oval
			(at 1.249 0.994 270)
			(size 0.3 0.8)
			(layers "F.Cu" "F.Mask" "F.Paste")
			(net 1357 "unconnected-(U24-NC-Pad9)")
			(pinfunction "NC")
			(pintype "no_connect")
		)
		(pad "10" smd oval
			(at 1.249 0.494 270)
			(size 0.3 0.8)
			(layers "F.Cu" "F.Mask" "F.Paste")
			(net 942 "/USB PHY/FTDI_SDA_IN")
			(pinfunction "B4")
			(pintype "input")
		)
		(pad "11" smd oval
			(at 1.249 0 270)
			(size 0.3 0.8)
			(layers "F.Cu" "F.Mask" "F.Paste")
			(net 1047 "/USB PHY/FTDI_SDA_OUT")
			(pinfunction "B3Y")
			(pintype "output")
		)
		(pad "12" smd oval
			(at 1.249 -0.5 270)
			(size 0.3 0.8)
			(layers "F.Cu" "F.Mask" "F.Paste")
			(net 1368 "unconnected-(U24-B2Y-Pad12)")
			(pinfunction "B2Y")
			(pintype "output+no_connect")
		)
		(pad "13" smd oval
			(at 1.249 -1 270)
			(size 0.3 0.8)
			(layers "F.Cu" "F.Mask" "F.Paste")
			(net 941 "/USB PHY/FTDI_SCL")
			(pinfunction "B1Y")
			(pintype "output")
		)
		(pad "14" smd oval
			(at 0.244 -1.5 180)
			(size 0.3 0.8)
			(layers "F.Cu" "F.Mask" "F.Paste")
			(net 24 "+3V3")
			(pinfunction "VCCB")
			(pintype "power_in")
		)
		(pad "15" smd rect
			(at 0 0 180)
			(size 1 1.5)
			(layers "F.Cu" "F.Mask" "F.Paste")
			(net 1 "GND")
			(pinfunction "GND")
			(pintype "power_in")
		)
	)
	(footprint "antmicro-footprints:C_0603_1608Metric"
		(layer "F.Cu")
		(at 170.85 172.8125 -90)
		(descr "Capacitor SMD 0603")
		(tags "capacitor 0603")
		(property "Reference" "C333"
			(at -6.5625 3.2 90)
			(layer "F.SilkS")
			(effects
				(font
					(size 0.7 0.7)
					(thickness 0.15)
				)
				(justify right bottom)
			)
		)
		(property "Value" "C_22u_0603"
			(at 0 1.6 90)
			(layer "F.Fab")
			(effects
				(font
					(size 0.7 0.7)
					(thickness 0.15)
				)
				(justify right bottom)
			)
		)
		(property "Description" "SMD Multilayer Ceramic Capacitor, 22 µF, 6.3 V, 0603 [1608 Metric], ± 20%, X5R, GRM Series"
			(at 0 0 270)
			(layer "F.Fab")
			(hide yes)
			(effects
				(font
					(size 1.27 1.27)
					(thickness 0.15)
				)
			)
		)
		(property "Author" "Antmicro"
			(at -1.9625 343.6625 0)
			(layer "F.Fab")
			(hide yes)
			(effects
				(font
					(size 1 1)
					(thickness 0.15)
				)
			)
		)
		(property "Dielectric" ""
			(at -1.9625 343.6625 0)
			(layer "F.Fab")
			(hide yes)
			(effects
				(font
					(size 1 1)
					(thickness 0.15)
				)
			)
		)
		(property "License" "Apache-2.0"
			(at -1.9625 343.6625 0)
			(layer "F.Fab")
			(hide yes)
			(effects
				(font
					(size 1 1)
					(thickness 0.15)
				)
			)
		)
		(property "MPN" "GRM188R60J226MEA0D"
			(at -1.9625 343.6625 0)
			(layer "F.Fab")
			(hide yes)
			(effects
				(font
					(size 1 1)
					(thickness 0.15)
				)
			)
		)
		(property "Manufacturer" "Murata"
			(at -1.9625 343.6625 0)
			(layer "F.Fab")
			(hide yes)
			(effects
				(font
					(size 1 1)
					(thickness 0.15)
				)
			)
		)
		(property "Val" "22u"
			(at -1.9625 343.6625 0)
			(layer "F.Fab")
			(hide yes)
			(effects
				(font
					(size 1 1)
					(thickness 0.15)
				)
			)
		)
		(property "Voltage" ""
			(at -1.9625 343.6625 0)
			(layer "F.Fab")
			(hide yes)
			(effects
				(font
					(size 1 1)
					(thickness 0.15)
				)
			)
		)
		(sheetname "DC-DC Converters")
		(sheetfile "dc-dc.kicad_sch")
		(attr smd)
		(fp_line
			(start -0.15 0.4)
			(end 0.15 0.4)
			(stroke
				(width 0.15)
				(type solid)
			)
			(layer "F.SilkS")
		)
		(fp_line
			(start -0.15 -0.4)
			(end 0.15 -0.4)
			(stroke
				(width 0.15)
				(type solid)
			)
			(layer "F.SilkS")
		)
		(fp_rect
			(start -1.25 -0.65)
			(end 1.25 0.65)
			(stroke
				(width 0.05)
				(type solid)
			)
			(fill no)
			(layer "F.CrtYd")
		)
		(fp_rect
			(start -0.8 -0.4)
			(end 0.8 0.4)
			(stroke
				(width 0.15)
				(type solid)
			)
			(fill no)
			(layer "F.Fab")
		)
		(pad "1" smd roundrect
			(at -0.7 0 270)
			(size 0.8 1)
			(layers "F.Cu" "F.Mask" "F.Paste")
			(roundrect_rratio 0.2)
			(net 1 "GND")
			(pintype "passive")
		)
		(pad "2" smd roundrect
			(at 0.7 0 270)
			(size 0.8 1)
			(layers "F.Cu" "F.Mask" "F.Paste")
			(roundrect_rratio 0.2)
			(net 740 "/DC-DC Converters/1V35_local")
			(pintype "passive")
		)
	)
	(footprint "antmicro-footprints:C_0402_1005Metric"
		(layer "F.Cu")
		(at 207.403752 95.634 180)
		(descr "Capacitor SMD 0402")
		(tags "capacitor SMD 0402")
		(property "Reference" "C289"
			(at 1.753752 7.134 180)
			(layer "F.SilkS")
			(effects
				(font
					(size 0.7 0.7)
					(thickness 0.15)
				)
				(justify left bottom)
			)
		)
		(property "Value" "C_100n_0402"
			(at 0 1.169 180)
			(layer "F.Fab")
			(effects
				(font
					(size 0.7 0.7)
					(thickness 0.15)
				)
				(justify left bottom)
			)
		)
		(property "Description" "SMD Multilayer Ceramic Capacitor, 0.1 µF, 50 V, 0402 [1005 Metric], ± 10%, X5R, GRM Series"
			(at 0 0 180)
			(layer "F.Fab")
			(hide yes)
			(effects
				(font
					(size 1.27 1.27)
					(thickness 0.15)
				)
			)
		)
		(property "Author" "Antmicro"
			(at 414.807504 191.268 0)
			(layer "F.Fab")
			(hide yes)
			(effects
				(font
					(size 1 1)
					(thickness 0.15)
				)
			)
		)
		(property "Dielectric" "X5R"
			(at 414.807504 191.268 0)
			(layer "F.Fab")
			(hide yes)
			(effects
				(font
					(size 1 1)
					(thickness 0.15)
				)
			)
		)
		(property "License" "Apache-2.0"
			(at 414.807504 191.268 0)
			(layer "F.Fab")
			(hide yes)
			(effects
				(font
					(size 1 1)
					(thickness 0.15)
				)
			)
		)
		(property "MPN" "GRM155R61H104KE14D"
			(at 414.807504 191.268 0)
			(layer "F.Fab")
			(hide yes)
			(effects
				(font
					(size 1 1)
					(thickness 0.15)
				)
			)
		)
		(property "Manufacturer" "Murata"
			(at 414.807504 191.268 0)
			(layer "F.Fab")
			(hide yes)
			(effects
				(font
					(size 1 1)
					(thickness 0.15)
				)
			)
		)
		(property "Val" "100n"
			(at 414.807504 191.268 0)
			(layer "F.Fab")
			(hide yes)
			(effects
				(font
					(size 1 1)
					(thickness 0.15)
				)
			)
		)
		(property "Voltage" "50V"
			(at 414.807504 191.268 0)
			(layer "F.Fab")
			(hide yes)
			(effects
				(font
					(size 1 1)
					(thickness 0.15)
				)
			)
		)
		(sheetname "HDMI + Ethernet")
		(sheetfile "hdmi-ethernet.kicad_sch")
		(attr smd)
		(fp_rect
			(start -0.925 -0.47)
			(end 0.925 0.47)
			(stroke
				(width 0.05)
				(type default)
			)
			(fill no)
			(layer "F.CrtYd")
		)
		(fp_line
			(start 0.504 0.248)
			(end -0.494 0.248)
			(stroke
				(width 0.15)
				(type solid)
			)
			(layer "F.Fab")
		)
		(fp_line
			(start 0.504 -0.25)
			(end 0.504 0.248)
			(stroke
				(width 0.15)
				(type solid)
			)
			(layer "F.Fab")
		)
		(fp_line
			(start -0.494 0.248)
			(end -0.494 -0.25)
			(stroke
				(width 0.15)
				(type solid)
			)
			(layer "F.Fab")
		)
		(fp_line
			(start -0.494 -0.25)
			(end 0.504 -0.25)
			(stroke
				(width 0.15)
				(type solid)
			)
			(layer "F.Fab")
		)
		(pad "1" smd roundrect
			(at -0.48 0 180)
			(size 0.59 0.64)
			(layers "F.Cu" "F.Mask" "F.Paste")
			(roundrect_rratio 0.25)
			(net 1 "GND")
			(pintype "passive")
		)
		(pad "2" smd roundrect
			(at 0.48 0 180)
			(size 0.59 0.64)
			(layers "F.Cu" "F.Mask" "F.Paste")
			(roundrect_rratio 0.25)
			(net 728 "/HDMI + Ethernet/GBE_AVDDL{slash}PLL")
			(pintype "passive")
		)
	)
	(footprint "antmicro-footprints:R_0603_1608Metric"
		(layer "F.Cu")
		(at 166.3 172.8 90)
		(descr "Resistor SMD 0603")
		(tags "resistor SMD 0603")
		(property "Reference" "R287"
			(at -1.49 1.41 90)
			(layer "F.SilkS")
			(effects
				(font
					(size 0.7 0.7)
					(thickness 0.15)
				)
				(justify left bottom)
			)
		)
		(property "Value" "R_0R_22.4A_0603"
			(at 0 1.6 90)
			(layer "F.Fab")
			(effects
				(font
					(size 0.7 0.7)
					(thickness 0.15)
				)
				(justify left bottom)
			)
		)
		(property "Description" "SMD Chip Resistor"
			(at 0 0 90)
			(layer "F.Fab")
			(hide yes)
			(effects
				(font
					(size 1.27 1.27)
					(thickness 0.15)
				)
			)
		)
		(property "Author" "Antmicro"
			(at 339.1 6.5 0)
			(layer "F.Fab")
			(hide yes)
			(effects
				(font
					(size 1 1)
					(thickness 0.15)
				)
			)
		)
		(property "License" "Apache-2.0"
			(at 339.1 6.5 0)
			(layer "F.Fab")
			(hide yes)
			(effects
				(font
					(size 1 1)
					(thickness 0.15)
				)
			)
		)
		(property "MPN" "PMR03EZPJ000"
			(at 339.1 6.5 0)
			(layer "F.Fab")
			(hide yes)
			(effects
				(font
					(size 1 1)
					(thickness 0.15)
				)
			)
		)
		(property "Manufacturer" "ROHM Semiconductor"
			(at 339.1 6.5 0)
			(layer "F.Fab")
			(hide yes)
			(effects
				(font
					(size 1 1)
					(thickness 0.15)
				)
			)
		)
		(property "Max. Curr." "22.4A"
			(at 339.1 6.5 0)
			(layer "F.Fab")
			(hide yes)
			(effects
				(font
					(size 1 1)
					(thickness 0.15)
				)
			)
		)
		(property "Tolerance" "template_tolerance"
			(at 339.1 6.5 0)
			(layer "F.Fab")
			(hide yes)
			(effects
				(font
					(size 1 1)
					(thickness 0.15)
				)
			)
		)
		(property "Val" "0R"
			(at 339.1 6.5 0)
			(layer "F.Fab")
			(hide yes)
			(effects
				(font
					(size 1 1)
					(thickness 0.15)
				)
			)
		)
		(sheetname "DC-DC Converters")
		(sheetfile "dc-dc.kicad_sch")
		(attr smd)
		(fp_line
			(start -0.15 -0.4)
			(end 0.15 -0.4)
			(stroke
				(width 0.15)
				(type solid)
			)
			(layer "F.SilkS")
		)
		(fp_line
			(start -0.15 0.4)
			(end 0.15 0.4)
			(stroke
				(width 0.15)
				(type solid)
			)
			(layer "F.SilkS")
		)
		(fp_rect
			(start -1.25 -0.65)
			(end 1.25 0.65)
			(stroke
				(width 0.05)
				(type solid)
			)
			(fill no)
			(layer "F.CrtYd")
		)
		(fp_rect
			(start -0.8 -0.4)
			(end 0.8 0.4)
			(stroke
				(width 0.15)
				(type solid)
			)
			(fill no)
			(layer "F.Fab")
		)
		(pad "1" smd roundrect
			(at -0.7 0 90)
			(size 0.8 1)
			(layers "F.Cu" "F.Mask" "F.Paste")
			(roundrect_rratio 0.2)
			(net 737 "/DC-DC Converters/1V2_local")
			(pintype "passive")
		)
		(pad "2" smd roundrect
			(at 0.7 0 90)
			(size 0.8 1)
			(layers "F.Cu" "F.Mask" "F.Paste")
			(roundrect_rratio 0.2)
			(net 727 "+1V2")
			(pintype "passive")
		)
	)
	(footprint "antmicro-footprints:0895-2C1R-GVH"
		(locked yes)
		(layer "F.Cu")
		(at 261.5 161.5 90)
		(property "Reference" "J15"
			(at 6.85 -27.9 90)
			(layer "F.SilkS")
			(effects
				(font
					(size 0.7 0.7)
					(thickness 0.15)
				)
				(justify left bottom)
			)
		)
		(property "Value" "0895-2C1R-GVH"
			(at 0 -2.5 90)
			(layer "F.Fab")
			(effects
				(font
					(size 0.7 0.7)
					(thickness 0.15)
				)
				(justify left bottom)
			)
		)
		(property "Description" "Modular connector with magnetics"
			(at 0 0 90)
			(layer "F.Fab")
			(hide yes)
			(effects
				(font
					(size 1.27 1.27)
					(thickness 0.15)
				)
			)
		)
		(property "Author" "Antmicro"
			(at 423 -100 0)
			(layer "F.Fab")
			(hide yes)
			(effects
				(font
					(size 1 1)
					(thickness 0.15)
				)
			)
		)
		(property "License" "Apache-2.0"
			(at 423 -100 0)
			(layer "F.Fab")
			(hide yes)
			(effects
				(font
					(size 1 1)
					(thickness 0.15)
				)
			)
		)
		(property "MPN" "0895-2C1R-GVH"
			(at 423 -100 0)
			(layer "F.Fab")
			(hide yes)
			(effects
				(font
					(size 1 1)
					(thickness 0.15)
				)
			)
		)
		(property "Manufacturer" "Bel Fuse"
			(at 423 -100 0)
			(layer "F.Fab")
			(hide yes)
			(effects
				(font
					(size 1 1)
					(thickness 0.15)
				)
			)
		)
		(sheetname "HDMI + Ethernet")
		(sheetfile "hdmi-ethernet.kicad_sch")
		(attr through_hole)
		(fp_line
			(start 8.585 -27.61)
			(end -8.587 -27.61)
			(stroke
				(width 0.15)
				(type solid)
			)
			(layer "F.SilkS")
		)
		(fp_line
			(start 8.585 -24.258)
			(end 8.585 -12.93)
			(stroke
				(width 0.15)
				(type solid)
			)
			(layer "F.SilkS")
		)
		(fp_line
			(start -8.587 -24.258)
			(end -8.587 -17.02)
			(stroke
				(width 0.15)
				(type solid)
			)
			(layer "F.SilkS")
		)
		(fp_line
			(start -8.587 -13.971)
			(end -8.587 3.072)
			(stroke
				(width 0.15)
				(type solid)
			)
			(layer "F.SilkS")
		)
		(fp_line
			(start 8.585 -9.907)
			(end 8.585 3.047)
			(stroke
				(width 0.15)
				(type solid)
			)
			(layer "F.SilkS")
		)
		(fp_line
			(start 7.11 4.825)
			(end 7.11 7.365)
			(stroke
				(width 0.15)
				(type solid)
			)
			(layer "F.SilkS")
		)
		(fp_line
			(start -7.112 4.825)
			(end 7.11 4.825)
			(stroke
				(width 0.15)
				(type solid)
			)
			(layer "F.SilkS")
		)
		(fp_line
			(start -7.112 4.825)
			(end -7.112 7.365)
			(stroke
				(width 0.15)
				(type solid)
			)
			(layer "F.SilkS")
		)
		(fp_line
			(start 8.585 6.07)
			(end 8.585 7.365)
			(stroke
				(width 0.15)
				(type solid)
			)
			(layer "F.SilkS")
		)
		(fp_line
			(start -8.587 6.094)
			(end -8.587 7.365)
			(stroke
				(width 0.15)
				(type solid)
			)
			(layer "F.SilkS")
		)
		(fp_line
			(start 8.585 7.365)
			(end 7.11 7.365)
			(stroke
				(width 0.15)
				(type solid)
			)
			(layer "F.SilkS")
		)
		(fp_line
			(start -8.587 7.365)
			(end -7.112 7.365)
			(stroke
				(width 0.15)
				(type solid)
			)
			(layer "F.SilkS")
		)
		(fp_circle
			(center -10.51 -4.734)
			(end -10.41 -4.734)
			(stroke
				(width 0.15)
				(type solid)
			)
			(fill no)
			(layer "F.SilkS")
		)
		(fp_rect
			(start -10.856 -28.622)
			(end 10.854 12.316)
			(stroke
				(width 0.05)
				(type solid)
			)
			(fill no)
			(layer "F.CrtYd")
		)
		(fp_line
			(start 8.585 -27.61)
			(end -8.587 -27.61)
			(stroke
				(width 0.15)
				(type solid)
			)
			(layer "F.Fab")
		)
		(fp_line
			(start 8.585 -27.61)
			(end 8.585 10.743)
			(stroke
				(width 0.15)
				(type solid)
			)
			(layer "F.Fab")
		)
		(fp_line
			(start -8.587 -27.61)
			(end -8.587 10.743)
			(stroke
				(width 0.15)
				(type solid)
			)
			(layer "F.Fab")
		)
		(fp_line
			(start -8.587 10.743)
			(end 8.585 10.743)
			(stroke
				(width 0.15)
				(type solid)
			)
			(layer "F.Fab")
		)
		(fp_arc
			(start 8.499 0.497)
			(mid 9.441 5.613)
			(end 8.585 10.743)
			(stroke
				(width 0.15)
				(type solid)
			)
			(layer "F.Fab")
		)
		(fp_arc
			(start -8.587 10.743)
			(mid -9.443 5.613)
			(end -8.5 0.497)
			(stroke
				(width 0.15)
				(type solid)
			)
			(layer "F.Fab")
		)
		(fp_circle
			(center -10.51 -4.734)
			(end -10.41 -4.734)
			(stroke
				(width 0.15)
				(type solid)
			)
			(fill no)
			(layer "F.Fab")
		)
		(pad "" np_thru_hole circle
			(at -5.715 0 90)
			(size 3.2512 3.2512)
			(drill 3.2512)
			(layers "*.Cu" "*.Mask")
		)
		(pad "" np_thru_hole circle
			(at 5.714 0 90)
			(size 3.2512 3.2512)
			(drill 3.2512)
			(layers "*.Cu" "*.Mask")
		)
		(pad "1_1" thru_hole circle
			(at -3.302 -4.699 90)
			(size 1.524 1.524)
			(drill 1.016)
			(layers "*.Cu" "*.Mask")
			(remove_unused_layers no)
			(net 725 "/HDMI + Ethernet/ETH1_N")
			(pinfunction "TRD1-_1")
			(pintype "passive")
		)
		(pad "1_2" thru_hole circle
			(at 3.301 -4.699 90)
			(size 1.524 1.524)
			(drill 1.016)
			(layers "*.Cu" "*.Mask")
			(remove_unused_layers no)
			(net 853 "/HDMI + Ethernet/GBE4_N")
			(pinfunction "TRD1-_2")
			(pintype "passive")
		)
		(pad "2_1" thru_hole circle
			(at -2.032 -5.97 90)
			(size 1.524 1.524)
			(drill 1.016)
			(layers "*.Cu" "*.Mask")
			(remove_unused_layers no)
			(net 724 "/HDMI + Ethernet/ETH1_P")
			(pinfunction "TRD1+_1")
			(pintype "passive")
		)
		(pad "2_2" thru_hole circle
			(at 2.031 -5.97 90)
			(size 1.524 1.524)
			(drill 1.016)
			(layers "*.Cu" "*.Mask")
			(remove_unused_layers no)
			(net 854 "/HDMI + Ethernet/GBE4_P")
			(pinfunction "TRD1+_2")
			(pintype "passive")
		)
		(pad "3_1" thru_hole circle
			(at -3.302 -7.239 90)
			(size 1.524 1.524)
			(drill 1.016)
			(layers "*.Cu" "*.Mask")
			(remove_unused_layers no)
			(net 729 "/HDMI + Ethernet/ETH2_N")
			(pinfunction "TRD2-_1")
			(pintype "passive")
		)
		(pad "3_2" thru_hole circle
			(at 3.301 -7.239 90)
			(size 1.524 1.524)
			(drill 1.016)
			(layers "*.Cu" "*.Mask")
			(remove_unused_layers no)
			(net 855 "/HDMI + Ethernet/GBE3_N")
			(pinfunction "TRD2-_2")
			(pintype "passive")
		)
		(pad "4_1" thru_hole circle
			(at -2.032 -8.51 90)
			(size 1.524 1.524)
			(drill 1.016)
			(layers "*.Cu" "*.Mask")
			(remove_unused_layers no)
			(net 726 "/HDMI + Ethernet/ETH2_P")
			(pinfunction "TRD2+_1")
			(pintype "passive")
		)
		(pad "4_2" thru_hole circle
			(at 2.031 -8.51 90)
			(size 1.524 1.524)
			(drill 1.016)
			(layers "*.Cu" "*.Mask")
			(remove_unused_layers no)
			(net 856 "/HDMI + Ethernet/GBE3_P")
			(pinfunction "TRD2+_2")
			(pintype "passive")
		)
		(pad "5_1" thru_hole circle
			(at -3.302 -9.779 90)
			(size 1.524 1.524)
			(drill 1.016)
			(layers "*.Cu" "*.Mask")
			(remove_unused_layers no)
			(net 36 "unconnected-(J15A-TRD3-_1-Pad5_1)")
			(pinfunction "TRD3-_1")
			(pintype "passive+no_connect")
		)
		(pad "5_2" thru_hole circle
			(at 3.301 -9.779 90)
			(size 1.524 1.524)
			(drill 1.016)
			(layers "*.Cu" "*.Mask")
			(remove_unused_layers no)
			(net 857 "/HDMI + Ethernet/GBE2_N")
			(pinfunction "TRD3-_2")
			(pintype "passive")
		)
		(pad "6_1" thru_hole circle
			(at -2.032 -11.049 90)
			(size 1.524 1.524)
			(drill 1.016)
			(layers "*.Cu" "*.Mask")
			(remove_unused_layers no)
			(net 39 "unconnected-(J15A-TRD3+_1-Pad6_1)")
			(pinfunction "TRD3+_1")
			(pintype "passive+no_connect")
		)
		(pad "6_2" thru_hole circle
			(at 2.031 -11.049 90)
			(size 1.524 1.524)
			(drill 1.016)
			(layers "*.Cu" "*.Mask")
			(remove_unused_layers no)
			(net 858 "/HDMI + Ethernet/GBE2_P")
			(pinfunction "TRD3+_2")
			(pintype "passive")
		)
		(pad "7_1" thru_hole circle
			(at -3.302 -12.321 90)
			(size 1.524 1.524)
			(drill 1.016)
			(layers "*.Cu" "*.Mask")
			(remove_unused_layers no)
			(net 40 "unconnected-(J15A-TRD4-_1-Pad7_1)")
			(pinfunction "TRD4-_1")
			(pintype "passive+no_connect")
		)
		(pad "7_2" thru_hole circle
			(at 3.301 -12.321 90)
			(size 1.524 1.524)
			(drill 1.016)
			(layers "*.Cu" "*.Mask")
			(remove_unused_layers no)
			(net 859 "/HDMI + Ethernet/GBE1_N")
			(pinfunction "TRD4-_2")
			(pintype "passive")
		)
		(pad "8_1" thru_hole circle
			(at -2.032 -13.59 90)
			(size 1.524 1.524)
			(drill 1.016)
			(layers "*.Cu" "*.Mask")
			(remove_unused_layers no)
			(net 41 "unconnected-(J15A-TRD4+_1-Pad8_1)")
			(pinfunction "TRD4+_1")
			(pintype "passive+no_connect")
		)
		(pad "8_2" thru_hole circle
			(at 2.031 -13.59 90)
			(size 1.524 1.524)
			(drill 1.016)
			(layers "*.Cu" "*.Mask")
			(remove_unused_layers no)
			(net 860 "/HDMI + Ethernet/GBE1_P")
			(pinfunction "TRD4+_2")
			(pintype "passive")
		)
		(pad "9_1" thru_hole circle
			(at -3.302 -14.859 90)
			(size 1.524 1.524)
			(drill 1.016)
			(layers "*.Cu" "*.Mask")
			(remove_unused_layers no)
			(net 12 "Net-(J15A-TRDCT1{slash}2{slash}3{slash}4_1)")
			(pinfunction "TRDCT1/2/3/4_1")
			(pintype "passive")
		)
		(pad "9_2" thru_hole circle
			(at 3.301 -14.859 90)
			(size 1.524 1.524)
			(drill 1.016)
			(layers "*.Cu" "*.Mask")
			(remove_unused_layers no)
			(net 730 "/HDMI + Ethernet/GBE_CONN_COMM")
			(pinfunction "TRDCT1/2/3/4_2")
			(pintype "passive")
		)
		(pad "10_1" thru_hole circle
			(at -2.032 -16.13 90)
			(size 1.524 1.524)
			(drill 1.016)
			(layers "*.Cu" "*.Mask")
			(remove_unused_layers no)
			(net 1 "GND")
			(pinfunction "GND_1")
			(pintype "power_in")
		)
		(pad "10_2" thru_hole circle
			(at 2.031 -16.13 90)
			(size 1.524 1.524)
			(drill 1.016)
			(layers "*.Cu" "*.Mask")
			(remove_unused_layers no)
			(net 1 "GND")
			(pinfunction "GND_2")
			(pintype "passive")
		)
		(pad "11_1" thru_hole circle
			(at -3.302 -19.939 90)
			(size 1.524 1.524)
			(drill 1.016)
			(layers "*.Cu" "*.Mask")
			(remove_unused_layers no)
			(net 765 "/HDMI + Ethernet/POE_ETH.VC2")
			(pinfunction "VC36_1")
			(pintype "passive")
		)
		(pad "11_2" thru_hole circle
			(at 3.301 -19.939 90)
			(size 1.524 1.524)
			(drill 1.016)
			(layers "*.Cu" "*.Mask")
			(remove_unused_layers no)
			(net 759 "/HDMI + Ethernet/POE_GBE.VC2")
			(pinfunction "VC36_2")
			(pintype "passive")
		)
		(pad "12_1" thru_hole circle
			(at -2.032 -21.209 90)
			(size 1.524 1.524)
			(drill 1.016)
			(layers "*.Cu" "*.Mask")
			(remove_unused_layers no)
			(net 766 "/HDMI + Ethernet/POE_ETH.VC3")
			(pinfunction "VC45_1")
			(pintype "passive")
		)
		(pad "12_2" thru_hole circle
			(at 2.031 -21.209 90)
			(size 1.524 1.524)
			(drill 1.016)
			(layers "*.Cu" "*.Mask")
			(remove_unused_layers no)
			(net 760 "/HDMI + Ethernet/POE_GBE.VC3")
			(pinfunction "VC45_2")
			(pintype "passive")
		)
		(pad "13_1" thru_hole circle
			(at -3.302 -22.479 90)
			(size 1.524 1.524)
			(drill 1.016)
			(layers "*.Cu" "*.Mask")
			(remove_unused_layers no)
			(net 767 "/HDMI + Ethernet/POE_ETH.VC4")
			(pinfunction "VC78_1")
			(pintype "passive")
		)
		(pad "13_2" thru_hole circle
			(at 3.301 -22.479 90)
			(size 1.524 1.524)
			(drill 1.016)
			(layers "*.Cu" "*.Mask")
			(remove_unused_layers no)
			(net 761 "/HDMI + Ethernet/POE_GBE.VC4")
			(pinfunction "VC78_2")
			(pintype "passive")
		)
		(pad "14_1" thru_hole circle
			(at -2.032 -23.749 90)
			(size 1.524 1.524)
			(drill 1.016)
			(layers "*.Cu" "*.Mask")
			(remove_unused_layers no)
			(net 764 "/HDMI + Ethernet/POE_ETH.VC1")
			(pinfunction "VC12_1")
			(pintype "passive")
		)
		(pad "14_2" thru_hole circle
			(at 2.031 -23.749 90)
			(size 1.524 1.524)
			(drill 1.016)
			(layers "*.Cu" "*.Mask")
			(remove_unused_layers no)
			(net 758 "/HDMI + Ethernet/POE_GBE.VC1")
			(pinfunction "VC12_2")
			(pintype "passive")
		)
		(pad "15_1" thru_hole circle
			(at -6.986 2.894 90)
			(size 1.62 1.62)
			(drill 1.143)
			(layers "*.Cu" "*.Mask")
			(remove_unused_layers no)
			(net 845 "/HDMI + Ethernet/ETH_LED_LINK+")
			(pintype "passive")
		)
		(pad "15_2" thru_hole circle
			(at -6.986 -11.786 90)
			(size 1.7145 1.7145)
			(drill 1.143)
			(layers "*.Cu" "*.Mask")
			(remove_unused_layers no)
			(net 849 "/HDMI + Ethernet/GBE_LED_LINK+")
			(pintype "passive")
		)
		(pad "16_1" thru_hole circle
			(at -4.446 2.894 90)
			(size 1.62 1.62)
			(drill 1.143)
			(layers "*.Cu" "*.Mask")
			(remove_unused_layers no)
			(net 847 "/HDMI + Ethernet/ETH_LED_LINK-")
			(pintype "passive")
		)
		(pad "16_2" thru_hole circle
			(at -6.986 -5.436 90)
			(size 1.7145 1.7145)
			(drill 1.143)
			(layers "*.Cu" "*.Mask")
			(remove_unused_layers no)
			(net 851 "/HDMI + Ethernet/GBE_LED_LINK-")
			(pintype "passive")
		)
		(pad "17_1" thru_hole circle
			(at 4.445 2.894 90)
			(size 1.62 1.62)
			(drill 1.143)
			(layers "*.Cu" "*.Mask")
			(remove_unused_layers no)
			(net 846 "/HDMI + Ethernet/ETH_LED_SPD-")
			(pintype "passive")
		)
		(pad "17_2" thru_hole circle
			(at 6.985 -7.976 90)
			(size 1.7145 1.7145)
			(drill 1.143)
			(layers "*.Cu" "*.Mask")
			(remove_unused_layers no)
			(net 850 "/HDMI + Ethernet/GBE_LED_SPD-")
			(pintype "passive")
		)
		(pad "18_1" thru_hole circle
			(at 6.985 2.894 90)
			(size 1.62 1.62)
			(drill 1.143)
			(layers "*.Cu" "*.Mask")
			(remove_unused_layers no)
			(net 848 "/HDMI + Ethernet/ETH_LED_SPD+")
			(pintype "passive")
		)
		(pad "18_2" thru_hole circle
			(at 6.985 -5.436 90)
			(size 1.7145 1.7145)
			(drill 1.143)
			(layers "*.Cu" "*.Mask")
			(remove_unused_layers no)
			(net 852 "/HDMI + Ethernet/GBE_LED_SPD+")
			(pintype "passive")
		)
		(pad "SH" thru_hole circle
			(at -8.51 -25.781 90)
			(size 2.3622 2.3622)
			(drill 1.5748)
			(layers "*.Cu" "*.Mask")
			(remove_unused_layers no)
			(net 723 "/HDMI + Ethernet/ETH_CONN_SH")
			(pinfunction "SHIELD")
			(pintype "passive")
		)
		(pad "SH" thru_hole circle
			(at -8.51 -15.494 90)
			(size 2.3622 2.3622)
			(drill 1.5748)
			(layers "*.Cu" "*.Mask")
			(remove_unused_layers no)
			(net 723 "/HDMI + Ethernet/ETH_CONN_SH")
			(pinfunction "SHIELD")
			(pintype "passive")
		)
		(pad "SH" thru_hole circle
			(at -8.51 4.57 90)
			(size 2.3622 2.3622)
			(drill 1.5748)
			(layers "*.Cu" "*.Mask")
			(remove_unused_layers no)
			(net 723 "/HDMI + Ethernet/ETH_CONN_SH")
			(pinfunction "SHIELD")
			(pintype "passive")
		)
		(pad "SH" thru_hole circle
			(at 8.509 -25.781 90)
			(size 2.3622 2.3622)
			(drill 1.5748)
			(layers "*.Cu" "*.Mask")
			(remove_unused_layers no)
			(net 723 "/HDMI + Ethernet/ETH_CONN_SH")
			(pinfunction "SHIELD")
			(pintype "passive")
		)
		(pad "SH" thru_hole circle
			(at 8.509 -11.43 90)
			(size 2.3622 2.3622)
			(drill 1.5748)
			(layers "*.Cu" "*.Mask")
			(remove_unused_layers no)
			(net 723 "/HDMI + Ethernet/ETH_CONN_SH")
			(pinfunction "SHIELD")
			(pintype "passive")
		)
		(pad "SH" thru_hole circle
			(at 8.509 4.57 90)
			(size 2.3622 2.3622)
			(drill 1.5748)
			(layers "*.Cu" "*.Mask")
			(remove_unused_layers no)
			(net 723 "/HDMI + Ethernet/ETH_CONN_SH")
			(pinfunction "SHIELD")
			(pintype "passive")
		)
		(zone
			(net 0)
			(net_name "")
			(layer "F.Cu")
			(hatch full 0.508)
			(connect_pads
				(clearance 0)
			)
			(min_thickness 0.01)
			(filled_areas_thickness no)
			(keepout
				(tracks not_allowed)
				(vias allowed)
				(pads allowed)
				(copperpour not_allowed)
				(footprints allowed)
			)
			(placement
				(enabled no)
				(sheetname "")
			)
			(fill
				(thermal_gap 0.508)
				(thermal_bridge_width 0.508)
			)
			(polygon
				(pts
					(xy 258.832 161.5) (xy 272.294 161.5) (xy 272.294 152.103) (xy 233.899 152.103) (xy 233.899 155.914)
					(xy 258.832 155.914)
				)
			)
		)
		(zone
			(net 0)
			(net_name "")
			(layer "F.Cu")
			(hatch full 0.508)
			(connect_pads
				(clearance 0)
			)
			(min_thickness 0.01)
			(filled_areas_thickness no)
			(keepout
				(tracks not_allowed)
				(vias allowed)
				(pads allowed)
				(copperpour not_allowed)
				(footprints allowed)
			)
			(placement
				(enabled no)
				(sheetname "")
			)
			(fill
				(thermal_gap 0.508)
				(thermal_bridge_width 0.508)
			)
			(polygon
				(pts
					(xy 258.832 161.5) (xy 272.294 161.5) (xy 272.294 170.898) (xy 233.899 170.898) (xy 233.899 167.088)
					(xy 258.832 167.088)
				)
			)
		)
	)
	(footprint "antmicro-footprints:SOT-23-6"
		(layer "F.Cu")
		(at 191 168.749 90)
		(property "Reference" "U10"
			(at 1.699 -2.05 180)
			(layer "F.SilkS")
			(effects
				(font
					(size 0.7 0.7)
					(thickness 0.15)
				)
				(justify left bottom)
			)
		)
		(property "Value" "LTC4412IS6"
			(at -1.75 2.75 90)
			(layer "F.Fab")
			(effects
				(font
					(size 0.7 0.7)
					(thickness 0.15)
				)
				(justify left bottom)
			)
		)
		(property "Description" "Ideal diode controller"
			(at 0 0 90)
			(layer "F.Fab")
			(hide yes)
			(effects
				(font
					(size 1.27 1.27)
					(thickness 0.15)
				)
			)
		)
		(property "Author" "Antmicro"
			(at 359.749 -22.251 0)
			(layer "F.Fab")
			(hide yes)
			(effects
				(font
					(size 1 1)
					(thickness 0.15)
				)
			)
		)
		(property "License" "Apache-2.0"
			(at 359.749 -22.251 0)
			(layer "F.Fab")
			(hide yes)
			(effects
				(font
					(size 1 1)
					(thickness 0.15)
				)
			)
		)
		(property "MPN" "LTC4412IS6#TRMPBF"
			(at 359.749 -22.251 0)
			(layer "F.Fab")
			(hide yes)
			(effects
				(font
					(size 1 1)
					(thickness 0.15)
				)
			)
		)
		(property "Manufacturer" "Analog Devices"
			(at 359.749 -22.251 0)
			(layer "F.Fab")
			(hide yes)
			(effects
				(font
					(size 1 1)
					(thickness 0.15)
				)
			)
		)
		(sheetname "Power supply")
		(sheetfile "power-supply.kicad_sch")
		(attr smd)
		(fp_line
			(start 1.45 -0.7)
			(end 1.45 -0.4)
			(stroke
				(width 0.12)
				(type solid)
			)
			(layer "F.SilkS")
		)
		(fp_line
			(start 1.3 -0.7)
			(end 1.45 -0.7)
			(stroke
				(width 0.12)
				(type solid)
			)
			(layer "F.SilkS")
		)
		(fp_line
			(start -1.3 -0.7)
			(end -1.45 -0.7)
			(stroke
				(width 0.12)
				(type solid)
			)
			(layer "F.SilkS")
		)
		(fp_line
			(start -1.45 -0.7)
			(end -1.45 -0.4)
			(stroke
				(width 0.12)
				(type solid)
			)
			(layer "F.SilkS")
		)
		(fp_line
			(start 1.45 0.7)
			(end 1.45 0.4)
			(stroke
				(width 0.12)
				(type solid)
			)
			(layer "F.SilkS")
		)
		(fp_line
			(start 1.3 0.7)
			(end 1.45 0.7)
			(stroke
				(width 0.12)
				(type solid)
			)
			(layer "F.SilkS")
		)
		(fp_line
			(start -1.45 0.7)
			(end -1.45 0.4)
			(stroke
				(width 0.12)
				(type solid)
			)
			(layer "F.SilkS")
		)
		(fp_rect
			(start -1.55 -1.85)
			(end 1.55 1.75)
			(stroke
				(width 0.05)
				(type solid)
			)
			(fill no)
			(layer "F.CrtYd")
		)
		(fp_line
			(start 1.5 -0.7)
			(end 1.5 0.7)
			(stroke
				(width 0.1)
				(type solid)
			)
			(layer "F.Fab")
		)
		(fp_line
			(start -1.5 -0.7)
			(end 1.5 -0.7)
			(stroke
				(width 0.1)
				(type solid)
			)
			(layer "F.Fab")
		)
		(fp_line
			(start 1.5 0.7)
			(end -1.5 0.7)
			(stroke
				(width 0.1)
				(type solid)
			)
			(layer "F.Fab")
		)
		(fp_line
			(start -1.5 0.7)
			(end -1.5 -0.7)
			(stroke
				(width 0.1)
				(type solid)
			)
			(layer "F.Fab")
		)
		(fp_text user "."
			(at -1.4 1.2 270)
			(layer "F.SilkS")
			(effects
				(font
					(size 1 1)
					(thickness 0.15)
				)
			)
		)
		(pad "1" smd roundrect
			(at -0.954 1.1 90)
			(size 0.55 1)
			(layers "F.Cu" "F.Mask" "F.Paste")
			(roundrect_rratio 0.15)
			(net 700 "/Power supply/USB_PD_VBUS")
			(pinfunction "IN")
			(pintype "power_in")
		)
		(pad "2" smd roundrect
			(at -0.003 1.1 90)
			(size 0.55 1)
			(layers "F.Cu" "F.Mask" "F.Paste")
			(roundrect_rratio 0.15)
			(net 1 "GND")
			(pinfunction "GND")
			(pintype "power_in")
		)
		(pad "3" smd roundrect
			(at 0.947 1.1 90)
			(size 0.55 1)
			(layers "F.Cu" "F.Mask" "F.Paste")
			(roundrect_rratio 0.15)
			(net 1 "GND")
			(pinfunction "CTL")
			(pintype "input")
		)
		(pad "4" smd roundrect
			(at 0.947 -1.214 90)
			(size 0.55 1)
			(layers "F.Cu" "F.Mask" "F.Paste")
			(roundrect_rratio 0.15)
			(net 1157 "unconnected-(U10-STAT-Pad4)")
			(pinfunction "STAT")
			(pintype "output+no_connect")
		)
		(pad "5" smd roundrect
			(at -0.003 -1.214 90)
			(size 0.55 1)
			(layers "F.Cu" "F.Mask" "F.Paste")
			(roundrect_rratio 0.15)
			(net 341 "Net-(Q6-G)")
			(pinfunction "GATE")
			(pintype "output")
		)
		(pad "6" smd roundrect
			(at -0.954 -1.214 90)
			(size 0.55 1)
			(layers "F.Cu" "F.Mask" "F.Paste")
			(roundrect_rratio 0.15)
			(net 702 "VDC")
			(pinfunction "SENSE")
			(pintype "input")
		)
	)
	(footprint "antmicro-footprints:PinHeader_2x17_P1.27mm_SMD_Shrouded"
		(layer "F.Cu")
		(at 231.001 88.2225)
		(property "Reference" "J11"
			(at 12.199 -2.9725 0)
			(layer "F.SilkS")
			(effects
				(font
					(size 0.7 0.7)
					(thickness 0.15)
				)
				(justify left bottom)
			)
		)
		(property "Value" "PinHeader_2x17_P1.27mm_SMD_Shrouded"
			(at -3.63 0.37 0)
			(layer "F.Fab")
			(effects
				(font
					(size 0.7 0.7)
					(thickness 0.15)
				)
				(justify left bottom)
			)
		)
		(property "Description" "Pin Header, Wire-to-Board, 1.27 mm, 2 Rows, 34 Contacts, Surface Mount Straight, WR-BHD Series"
			(at 0 0 0)
			(layer "F.Fab")
			(hide yes)
			(effects
				(font
					(size 1.27 1.27)
					(thickness 0.15)
				)
			)
		)
		(property "Author" "Antmicro"
			(at 0 0 0)
			(layer "F.Fab")
			(hide yes)
			(effects
				(font
					(size 1 1)
					(thickness 0.15)
				)
			)
		)
		(property "License" "Apache-2.0"
			(at 0 0 0)
			(layer "F.Fab")
			(hide yes)
			(effects
				(font
					(size 1 1)
					(thickness 0.15)
				)
			)
		)
		(property "MPN" "62703420621"
			(at 0 0 0)
			(layer "F.Fab")
			(hide yes)
			(effects
				(font
					(size 1 1)
					(thickness 0.15)
				)
			)
		)
		(property "Manufacturer" "Würth Elektronik"
			(at 0 0 0)
			(layer "F.Fab")
			(hide yes)
			(effects
				(font
					(size 1 1)
					(thickness 0.15)
				)
			)
		)
		(sheetname "User GPIO + LED + button + DIP switch")
		(sheetfile "user-gpio.kicad_sch")
		(attr smd)
		(fp_line
			(start -14 -2.6)
			(end -14 2.6)
			(stroke
				(width 0.15)
				(type solid)
			)
			(layer "F.SilkS")
		)
		(fp_line
			(start -14 -2.6)
			(end -10.8 -2.6)
			(stroke
				(width 0.15)
				(type solid)
			)
			(layer "F.SilkS")
		)
		(fp_line
			(start -14 2.6)
			(end -10.8 2.6)
			(stroke
				(width 0.15)
				(type solid)
			)
			(layer "F.SilkS")
		)
		(fp_line
			(start 10.8 -2.6)
			(end 14 -2.6)
			(stroke
				(width 0.15)
				(type solid)
			)
			(layer "F.SilkS")
		)
		(fp_line
			(start 10.8 2.6)
			(end 14 2.6)
			(stroke
				(width 0.15)
				(type solid)
			)
			(layer "F.SilkS")
		)
		(fp_line
			(start 14 -2.6)
			(end 14 2.6)
			(stroke
				(width 0.15)
				(type solid)
			)
			(layer "F.SilkS")
		)
		(fp_circle
			(center -10.86 3.07)
			(end -10.809 3.07)
			(stroke
				(width 0.15)
				(type solid)
			)
			(fill yes)
			(layer "F.SilkS")
		)
		(fp_rect
			(start -14.3 -3.5)
			(end 14.3 3.5)
			(stroke
				(width 0.05)
				(type solid)
			)
			(fill no)
			(layer "F.CrtYd")
		)
		(fp_line
			(start -13.96 2.57)
			(end -13.76 2.77)
			(stroke
				(width 0.15)
				(type solid)
			)
			(layer "F.Fab")
		)
		(fp_rect
			(start -13.971 -2.778)
			(end 13.97 2.777)
			(stroke
				(width 0.15)
				(type solid)
			)
			(fill no)
			(layer "F.Fab")
		)
		(pad "1" smd rect
			(at -10.16 1.999)
			(size 0.74 2.8)
			(layers "F.Cu" "F.Mask" "F.Paste")
			(net 1266 "/USER_IO.B1")
			(pintype "passive")
		)
		(pad "2" smd rect
			(at -10.16 -2)
			(size 0.74 2.8)
			(layers "F.Cu" "F.Mask" "F.Paste")
			(net 1 "GND")
			(pintype "passive")
		)
		(pad "3" smd rect
			(at -8.891 1.999)
			(size 0.74 2.8)
			(layers "F.Cu" "F.Mask" "F.Paste")
			(net 1267 "/USER_IO.B3")
			(pintype "passive")
		)
		(pad "4" smd rect
			(at -8.891 -2)
			(size 0.74 2.8)
			(layers "F.Cu" "F.Mask" "F.Paste")
			(net 1 "GND")
			(pintype "passive")
		)
		(pad "5" smd rect
			(at -7.62 1.999)
			(size 0.74 2.8)
			(layers "F.Cu" "F.Mask" "F.Paste")
			(net 1268 "/USER_IO.B5")
			(pintype "passive")
		)
		(pad "6" smd rect
			(at -7.62 -2)
			(size 0.74 2.8)
			(layers "F.Cu" "F.Mask" "F.Paste")
			(net 1269 "/USER_IO.B6")
			(pintype "passive")
		)
		(pad "7" smd rect
			(at -6.351 1.999)
			(size 0.74 2.8)
			(layers "F.Cu" "F.Mask" "F.Paste")
			(net 1270 "/USER_IO.B7")
			(pintype "passive")
		)
		(pad "8" smd rect
			(at -6.351 -2)
			(size 0.74 2.8)
			(layers "F.Cu" "F.Mask" "F.Paste")
			(net 1271 "/USER_IO.B8")
			(pintype "passive")
		)
		(pad "9" smd rect
			(at -5.08 1.999)
			(size 0.74 2.8)
			(layers "F.Cu" "F.Mask" "F.Paste")
			(net 1272 "/USER_IO.B9")
			(pintype "passive")
		)
		(pad "10" smd rect
			(at -5.08 -2)
			(size 0.74 2.8)
			(layers "F.Cu" "F.Mask" "F.Paste")
			(net 1273 "/USER_IO.B10")
			(pintype "passive")
		)
		(pad "11" smd rect
			(at -3.81 1.999)
			(size 0.74 2.8)
			(layers "F.Cu" "F.Mask" "F.Paste")
			(net 1274 "/USER_IO.B11")
			(pintype "passive")
		)
		(pad "12" smd rect
			(at -3.81 -2)
			(size 0.74 2.8)
			(layers "F.Cu" "F.Mask" "F.Paste")
			(net 1275 "/USER_IO.B12")
			(pintype "passive")
		)
		(pad "13" smd rect
			(at -2.54 1.999)
			(size 0.74 2.8)
			(layers "F.Cu" "F.Mask" "F.Paste")
			(net 3 "VCC_USR_B")
			(pintype "passive")
		)
		(pad "14" smd rect
			(at -2.54 -2)
			(size 0.74 2.8)
			(layers "F.Cu" "F.Mask" "F.Paste")
			(net 1276 "/USER_IO.B14")
			(pintype "passive")
		)
		(pad "15" smd rect
			(at -1.27 1.999)
			(size 0.74 2.8)
			(layers "F.Cu" "F.Mask" "F.Paste")
			(net 1277 "/USER_IO.B15")
			(pintype "passive")
		)
		(pad "16" smd rect
			(at -1.27 -2)
			(size 0.74 2.8)
			(layers "F.Cu" "F.Mask" "F.Paste")
			(net 1278 "/USER_IO.B16")
			(pintype "passive")
		)
		(pad "17" smd rect
			(at 0 1.999)
			(size 0.74 2.8)
			(layers "F.Cu" "F.Mask" "F.Paste")
			(net 1279 "/USER_IO.B17")
			(pintype "passive")
		)
		(pad "18" smd rect
			(at 0 -2)
			(size 0.74 2.8)
			(layers "F.Cu" "F.Mask" "F.Paste")
			(net 1280 "/USER_IO.B18")
			(pintype "passive")
		)
		(pad "19" smd rect
			(at 1.269 1.999)
			(size 0.74 2.8)
			(layers "F.Cu" "F.Mask" "F.Paste")
			(net 1281 "/USER_IO.B19")
			(pintype "passive")
		)
		(pad "20" smd rect
			(at 1.269 -2)
			(size 0.74 2.8)
			(layers "F.Cu" "F.Mask" "F.Paste")
			(net 1 "GND")
			(pintype "passive")
		)
		(pad "21" smd rect
			(at 2.539 1.999)
			(size 0.74 2.8)
			(layers "F.Cu" "F.Mask" "F.Paste")
			(net 1282 "/USER_IO.B21")
			(pintype "passive")
		)
		(pad "22" smd rect
			(at 2.539 -2)
			(size 0.74 2.8)
			(layers "F.Cu" "F.Mask" "F.Paste")
			(net 24 "+3V3")
			(pintype "passive")
		)
		(pad "23" smd rect
			(at 3.809 1.999)
			(size 0.74 2.8)
			(layers "F.Cu" "F.Mask" "F.Paste")
			(net 1283 "/USER_IO.B23")
			(pintype "passive")
		)
		(pad "24" smd rect
			(at 3.809 -2)
			(size 0.74 2.8)
			(layers "F.Cu" "F.Mask" "F.Paste")
			(net 1284 "/USER_IO.B24")
			(pintype "passive")
		)
		(pad "25" smd rect
			(at 5.078 1.999)
			(size 0.74 2.8)
			(layers "F.Cu" "F.Mask" "F.Paste")
			(net 1285 "/USER_IO.B25")
			(pintype "passive")
		)
		(pad "26" smd rect
			(at 5.078 -2)
			(size 0.74 2.8)
			(layers "F.Cu" "F.Mask" "F.Paste")
			(net 1286 "/USER_IO.B26")
			(pintype "passive")
		)
		(pad "27" smd rect
			(at 6.349 1.999)
			(size 0.74 2.8)
			(layers "F.Cu" "F.Mask" "F.Paste")
			(net 1287 "/USER_IO.B27")
			(pintype "passive")
		)
		(pad "28" smd rect
			(at 6.349 -2)
			(size 0.74 2.8)
			(layers "F.Cu" "F.Mask" "F.Paste")
			(net 1288 "/USER_IO.B28")
			(pintype "passive")
		)
		(pad "29" smd rect
			(at 7.618 1.999)
			(size 0.74 2.8)
			(layers "F.Cu" "F.Mask" "F.Paste")
			(net 1289 "/USER_IO.B29")
			(pintype "passive")
		)
		(pad "30" smd rect
			(at 7.618 -2)
			(size 0.74 2.8)
			(layers "F.Cu" "F.Mask" "F.Paste")
			(net 1290 "/USER_IO.B30")
			(pintype "passive")
		)
		(pad "31" smd rect
			(at 8.89 1.999)
			(size 0.74 2.8)
			(layers "F.Cu" "F.Mask" "F.Paste")
			(net 1291 "/USER_IO.B31")
			(pintype "passive")
		)
		(pad "32" smd rect
			(at 8.89 -2)
			(size 0.74 2.8)
			(layers "F.Cu" "F.Mask" "F.Paste")
			(net 1292 "/USER_IO.B32")
			(pintype "passive")
		)
		(pad "33" smd rect
			(at 10.159 1.999)
			(size 0.74 2.8)
			(layers "F.Cu" "F.Mask" "F.Paste")
			(net 1293 "/USER_IO.B33")
			(pintype "passive")
		)
		(pad "34" smd rect
			(at 10.159 -2)
			(size 0.74 2.8)
			(layers "F.Cu" "F.Mask" "F.Paste")
			(net 1 "GND")
			(pintype "passive")
		)
	)
	(footprint "antmicro-footprints:C_0402_1005Metric"
		(layer "F.Cu")
		(at 173.570001 113.143751 180)
		(descr "Capacitor SMD 0402")
		(tags "capacitor SMD 0402")
		(property "Reference" "C302"
			(at -3.729999 -0.356249 0)
			(layer "F.SilkS")
			(effects
				(font
					(size 0.7 0.7)
					(thickness 0.15)
				)
				(justify right bottom)
			)
		)
		(property "Value" "C_100n_0402"
			(at 0 1.4 0)
			(layer "F.Fab")
			(effects
				(font
					(size 0.7 0.7)
					(thickness 0.15)
				)
				(justify right bottom)
			)
		)
		(property "Description" "SMD Multilayer Ceramic Capacitor, 0.1 µF, 50 V, 0402 [1005 Metric], ± 10%, X5R, GRM Series"
			(at 0 0 180)
			(layer "F.Fab")
			(hide yes)
			(effects
				(font
					(size 1.27 1.27)
					(thickness 0.15)
				)
			)
		)
		(property "Author" "Antmicro"
			(at 347.140002 226.287502 0)
			(layer "F.Fab")
			(hide yes)
			(effects
				(font
					(size 1 1)
					(thickness 0.15)
				)
			)
		)
		(property "Dielectric" "X5R"
			(at 347.140002 226.287502 0)
			(layer "F.Fab")
			(hide yes)
			(effects
				(font
					(size 1 1)
					(thickness 0.15)
				)
			)
		)
		(property "License" "Apache-2.0"
			(at 347.140002 226.287502 0)
			(layer "F.Fab")
			(hide yes)
			(effects
				(font
					(size 1 1)
					(thickness 0.15)
				)
			)
		)
		(property "MPN" "GRM155R61H104KE14D"
			(at 347.140002 226.287502 0)
			(layer "F.Fab")
			(hide yes)
			(effects
				(font
					(size 1 1)
					(thickness 0.15)
				)
			)
		)
		(property "Manufacturer" "Murata"
			(at 347.140002 226.287502 0)
			(layer "F.Fab")
			(hide yes)
			(effects
				(font
					(size 1 1)
					(thickness 0.15)
				)
			)
		)
		(property "Val" "100n"
			(at 347.140002 226.287502 0)
			(layer "F.Fab")
			(hide yes)
			(effects
				(font
					(size 1 1)
					(thickness 0.15)
				)
			)
		)
		(property "Voltage" "50V"
			(at 347.140002 226.287502 0)
			(layer "F.Fab")
			(hide yes)
			(effects
				(font
					(size 1 1)
					(thickness 0.15)
				)
			)
		)
		(sheetname "FMC+ HSPC")
		(sheetfile "fmc-hspc.kicad_sch")
		(attr smd)
		(fp_rect
			(start -0.925 -0.47)
			(end 0.925 0.47)
			(stroke
				(width 0.05)
				(type default)
			)
			(fill no)
			(layer "F.CrtYd")
		)
		(fp_line
			(start 0.504 0.248)
			(end -0.494 0.248)
			(stroke
				(width 0.15)
				(type solid)
			)
			(layer "F.Fab")
		)
		(fp_line
			(start 0.504 -0.25)
			(end 0.504 0.248)
			(stroke
				(width 0.15)
				(type solid)
			)
			(layer "F.Fab")
		)
		(fp_line
			(start -0.494 0.248)
			(end -0.494 -0.25)
			(stroke
				(width 0.15)
				(type solid)
			)
			(layer "F.Fab")
		)
		(fp_line
			(start -0.494 -0.25)
			(end 0.504 -0.25)
			(stroke
				(width 0.15)
				(type solid)
			)
			(layer "F.Fab")
		)
		(pad "1" smd roundrect
			(at -0.48 0 180)
			(size 0.59 0.64)
			(layers "F.Cu" "F.Mask" "F.Paste")
			(roundrect_rratio 0.25)
			(net 73 "/FMC+ HSPC/GTX116.TX1_P")
			(pintype "passive")
		)
		(pad "2" smd roundrect
			(at 0.48 0 180)
			(size 0.59 0.64)
			(layers "F.Cu" "F.Mask" "F.Paste")
			(roundrect_rratio 0.25)
			(net 71 "/FMC+ HSPC/GTX_TX2_C_P")
			(pintype "passive")
		)
	)
	(footprint "antmicro-footprints:C_1206_3216Metric"
		(layer "F.Cu")
		(at 195.8 184.449 90)
		(descr "Capacitor SMD 1206")
		(tags "capacitor SMD 1206")
		(property "Reference" "C200"
			(at -1.501 -1.15 90)
			(layer "F.SilkS")
			(effects
				(font
					(size 0.7 0.7)
					(thickness 0.15)
				)
				(justify left bottom)
			)
		)
		(property "Value" "C_47u_16V_1206"
			(at 0 2.1 90)
			(layer "F.Fab")
			(effects
				(font
					(size 0.7 0.7)
					(thickness 0.15)
				)
				(justify left bottom)
			)
		)
		(property "Description" "SMD Multilayer Ceramic Capacitor, 47 µF, 16 V, 1206 [3216 Metric], ± 20%, X5R, C"
			(at 0 0 90)
			(layer "F.Fab")
			(hide yes)
			(effects
				(font
					(size 1.27 1.27)
					(thickness 0.15)
				)
			)
		)
		(property "Author" "Antmicro"
			(at 380.249 -11.351 0)
			(layer "F.Fab")
			(hide yes)
			(effects
				(font
					(size 1 1)
					(thickness 0.15)
				)
			)
		)
		(property "Dielectric" "X5R"
			(at 380.249 -11.351 0)
			(layer "F.Fab")
			(hide yes)
			(effects
				(font
					(size 1 1)
					(thickness 0.15)
				)
			)
		)
		(property "License" "Apache-2.0"
			(at 380.249 -11.351 0)
			(layer "F.Fab")
			(hide yes)
			(effects
				(font
					(size 1 1)
					(thickness 0.15)
				)
			)
		)
		(property "MPN" "C3216X5R1C476M160AB"
			(at 380.249 -11.351 0)
			(layer "F.Fab")
			(hide yes)
			(effects
				(font
					(size 1 1)
					(thickness 0.15)
				)
			)
		)
		(property "Manufacturer" "TDK"
			(at 380.249 -11.351 0)
			(layer "F.Fab")
			(hide yes)
			(effects
				(font
					(size 1 1)
					(thickness 0.15)
				)
			)
		)
		(property "Val" "47u"
			(at 380.249 -11.351 0)
			(layer "F.Fab")
			(hide yes)
			(effects
				(font
					(size 1 1)
					(thickness 0.15)
				)
			)
		)
		(property "Voltage" "16V"
			(at 380.249 -11.351 0)
			(layer "F.Fab")
			(hide yes)
			(effects
				(font
					(size 1 1)
					(thickness 0.15)
				)
			)
		)
		(sheetname "Power supply")
		(sheetfile "power-supply.kicad_sch")
		(attr smd)
		(fp_line
			(start 0.8 -0.899)
			(end -0.8 -0.899)
			(stroke
				(width 0.15)
				(type solid)
			)
			(layer "F.SilkS")
		)
		(fp_line
			(start 0.8 0.901)
			(end -0.8 0.901)
			(stroke
				(width 0.15)
				(type solid)
			)
			(layer "F.SilkS")
		)
		(fp_rect
			(start -2.325 -1.15)
			(end 2.325 1.15)
			(stroke
				(width 0.05)
				(type default)
			)
			(fill no)
			(layer "F.CrtYd")
		)
		(fp_rect
			(start -1.6 -0.799)
			(end 1.6 0.801)
			(stroke
				(width 0.15)
				(type solid)
			)
			(fill no)
			(layer "F.Fab")
		)
		(pad "1" smd roundrect
			(at -1.5 0.001 90)
			(size 1.15 1.8)
			(layers "F.Cu" "F.Mask" "F.Paste")
			(roundrect_rratio 0.25)
			(net 1 "GND")
			(pintype "passive")
		)
		(pad "2" smd roundrect
			(at 1.5 0.001 90)
			(size 1.15 1.8)
			(layers "F.Cu" "F.Mask" "F.Paste")
			(roundrect_rratio 0.25)
			(net 956 "/DC-DC Converters/POE_DC")
			(pintype "passive")
		)
	)
	(footprint "antmicro-footprints:R_0402_1005Metric"
		(layer "F.Cu")
		(at 181.05 168.7125 90)
		(descr "Resistor SMD 0402")
		(tags "resistor SMD 0402")
		(property "Reference" "R302"
			(at -0.9375 1.25 90)
			(layer "F.SilkS")
			(effects
				(font
					(size 0.7 0.7)
					(thickness 0.15)
				)
				(justify left bottom)
			)
		)
		(property "Value" "R_0R_0402"
			(at 0 1.4 90)
			(layer "F.Fab")
			(effects
				(font
					(size 0.7 0.7)
					(thickness 0.15)
				)
				(justify left bottom)
			)
		)
		(property "Description" "SMD Chip Resistor, Jumper, 0 ohm, 100 mW, 0402 [1005 Metric], Thick Film, General Purpose"
			(at 0 0 90)
			(layer "F.Fab")
			(hide yes)
			(effects
				(font
					(size 1.27 1.27)
					(thickness 0.15)
				)
			)
		)
		(property "Author" "Antmicro"
			(at 349.7625 -12.3375 0)
			(layer "F.Fab")
			(hide yes)
			(effects
				(font
					(size 1 1)
					(thickness 0.15)
				)
			)
		)
		(property "Current" "1A"
			(at 349.7625 -12.3375 0)
			(layer "F.Fab")
			(hide yes)
			(effects
				(font
					(size 1 1)
					(thickness 0.15)
				)
			)
		)
		(property "License" "Apache-2.0"
			(at 349.7625 -12.3375 0)
			(layer "F.Fab")
			(hide yes)
			(effects
				(font
					(size 1 1)
					(thickness 0.15)
				)
			)
		)
		(property "MPN" "ERJ2GE0R00X"
			(at 349.7625 -12.3375 0)
			(layer "F.Fab")
			(hide yes)
			(effects
				(font
					(size 1 1)
					(thickness 0.15)
				)
			)
		)
		(property "Manufacturer" "Panasonic"
			(at 349.7625 -12.3375 0)
			(layer "F.Fab")
			(hide yes)
			(effects
				(font
					(size 1 1)
					(thickness 0.15)
				)
			)
		)
		(property "Tolerance" ""
			(at 349.7625 -12.3375 0)
			(layer "F.Fab")
			(hide yes)
			(effects
				(font
					(size 1 1)
					(thickness 0.15)
				)
			)
		)
		(property "Val" "0R"
			(at 349.7625 -12.3375 0)
			(layer "F.Fab")
			(hide yes)
			(effects
				(font
					(size 1 1)
					(thickness 0.15)
				)
			)
		)
		(sheetname "DC-DC Converters")
		(sheetfile "dc-dc.kicad_sch")
		(attr smd)
		(fp_rect
			(start -0.925 -0.47)
			(end 0.925 0.47)
			(stroke
				(width 0.05)
				(type default)
			)
			(fill no)
			(layer "F.CrtYd")
		)
		(fp_rect
			(start -0.5 -0.25)
			(end 0.5 0.25)
			(stroke
				(width 0.15)
				(type solid)
			)
			(fill no)
			(layer "F.Fab")
		)
		(pad "1" smd roundrect
			(at -0.48 0 90)
			(size 0.59 0.64)
			(layers "F.Cu" "F.Mask" "F.Paste")
			(roundrect_rratio 0.25)
			(net 957 "/DC-DC Converters/FB6")
			(pintype "passive")
		)
		(pad "2" smd roundrect
			(at 0.48 0 90)
			(size 0.59 0.64)
			(layers "F.Cu" "F.Mask" "F.Paste")
			(roundrect_rratio 0.25)
			(net 736 "/DC-DC Converters/3V3_local_2")
			(pintype "passive")
		)
	)
	(footprint "antmicro-footprints:C_0402_1005Metric"
		(layer "F.Cu")
		(at 160.8 155.7 -90)
		(descr "Capacitor SMD 0402")
		(tags "capacitor SMD 0402")
		(property "Reference" "C340"
			(at 0.75 -0.4 90)
			(layer "F.SilkS")
			(effects
				(font
					(size 0.7 0.7)
					(thickness 0.15)
				)
				(justify right bottom)
			)
		)
		(property "Value" "C_10u_0402"
			(at 0 1.4 90)
			(layer "F.Fab")
			(effects
				(font
					(size 0.7 0.7)
					(thickness 0.15)
				)
				(justify right bottom)
			)
		)
		(property "Description" "SMD Multilayer Ceramic Capacitor, 10 µF, 6.3 V, 0402 [1005 Metric], ± 20%, X5R, CC Series"
			(at 0 0 270)
			(layer "F.Fab")
			(hide yes)
			(effects
				(font
					(size 1.27 1.27)
					(thickness 0.15)
				)
			)
		)
		(property "Author" "Antmicro"
			(at 5.1 316.5 0)
			(layer "F.Fab")
			(hide yes)
			(effects
				(font
					(size 1 1)
					(thickness 0.15)
				)
			)
		)
		(property "Dielectric" ""
			(at 5.1 316.5 0)
			(layer "F.Fab")
			(hide yes)
			(effects
				(font
					(size 1 1)
					(thickness 0.15)
				)
			)
		)
		(property "License" "Apache-2.0"
			(at 5.1 316.5 0)
			(layer "F.Fab")
			(hide yes)
			(effects
				(font
					(size 1 1)
					(thickness 0.15)
				)
			)
		)
		(property "MPN" "CC0402MRX5R5BB106"
			(at 5.1 316.5 0)
			(layer "F.Fab")
			(hide yes)
			(effects
				(font
					(size 1 1)
					(thickness 0.15)
				)
			)
		)
		(property "Manufacturer" "YAGEO"
			(at 5.1 316.5 0)
			(layer "F.Fab")
			(hide yes)
			(effects
				(font
					(size 1 1)
					(thickness 0.15)
				)
			)
		)
		(property "Val" "10u"
			(at 5.1 316.5 0)
			(layer "F.Fab")
			(hide yes)
			(effects
				(font
					(size 1 1)
					(thickness 0.15)
				)
			)
		)
		(property "Voltage" ""
			(at 5.1 316.5 0)
			(layer "F.Fab")
			(hide yes)
			(effects
				(font
					(size 1 1)
					(thickness 0.15)
				)
			)
		)
		(sheetname "DC-DC Converters")
		(sheetfile "dc-dc.kicad_sch")
		(attr smd)
		(fp_rect
			(start -0.925 -0.47)
			(end 0.925 0.47)
			(stroke
				(width 0.05)
				(type default)
			)
			(fill no)
			(layer "F.CrtYd")
		)
		(fp_line
			(start -0.494 0.248)
			(end -0.494 -0.25)
			(stroke
				(width 0.15)
				(type solid)
			)
			(layer "F.Fab")
		)
		(fp_line
			(start 0.504 0.248)
			(end -0.494 0.248)
			(stroke
				(width 0.15)
				(type solid)
			)
			(layer "F.Fab")
		)
		(fp_line
			(start -0.494 -0.25)
			(end 0.504 -0.25)
			(stroke
				(width 0.15)
				(type solid)
			)
			(layer "F.Fab")
		)
		(fp_line
			(start 0.504 -0.25)
			(end 0.504 0.248)
			(stroke
				(width 0.15)
				(type solid)
			)
			(layer "F.Fab")
		)
		(pad "1" smd roundrect
			(at -0.48 0 270)
			(size 0.59 0.64)
			(layers "F.Cu" "F.Mask" "F.Paste")
			(roundrect_rratio 0.25)
			(net 1 "GND")
			(pintype "passive")
		)
		(pad "2" smd roundrect
			(at 0.48 0 270)
			(size 0.59 0.64)
			(layers "F.Cu" "F.Mask" "F.Paste")
			(roundrect_rratio 0.25)
			(net 25 "+1V35")
			(pintype "passive")
		)
	)
	(footprint "antmicro-footprints:R_0402_1005Metric"
		(layer "F.Cu")
		(at 242.15 105.1)
		(descr "Resistor SMD 0402")
		(tags "resistor SMD 0402")
		(property "Reference" "R257"
			(at -3.65 0.35 0)
			(layer "F.SilkS")
			(effects
				(font
					(size 0.7 0.7)
					(thickness 0.15)
				)
				(justify left bottom)
			)
		)
		(property "Value" "R_0R_0402"
			(at 0 1.4 0)
			(layer "F.Fab")
			(effects
				(font
					(size 0.7 0.7)
					(thickness 0.15)
				)
				(justify left bottom)
			)
		)
		(property "Description" "SMD Chip Resistor, Jumper, 0 ohm, 100 mW, 0402 [1005 Metric], Thick Film, General Purpose"
			(at 0 0 0)
			(layer "F.Fab")
			(hide yes)
			(effects
				(font
					(size 1.27 1.27)
					(thickness 0.15)
				)
			)
		)
		(property "Author" "Antmicro"
			(at 0 0 0)
			(layer "F.Fab")
			(hide yes)
			(effects
				(font
					(size 1 1)
					(thickness 0.15)
				)
			)
		)
		(property "Current" "1A"
			(at 0 0 0)
			(layer "F.Fab")
			(hide yes)
			(effects
				(font
					(size 1 1)
					(thickness 0.15)
				)
			)
		)
		(property "License" "Apache-2.0"
			(at 0 0 0)
			(layer "F.Fab")
			(hide yes)
			(effects
				(font
					(size 1 1)
					(thickness 0.15)
				)
			)
		)
		(property "MPN" "ERJ2GE0R00X"
			(at 0 0 0)
			(layer "F.Fab")
			(hide yes)
			(effects
				(font
					(size 1 1)
					(thickness 0.15)
				)
			)
		)
		(property "Manufacturer" "Panasonic"
			(at 0 0 0)
			(layer "F.Fab")
			(hide yes)
			(effects
				(font
					(size 1 1)
					(thickness 0.15)
				)
			)
		)
		(property "Tolerance" ""
			(at 0 0 0)
			(layer "F.Fab")
			(hide yes)
			(effects
				(font
					(size 1 1)
					(thickness 0.15)
				)
			)
		)
		(property "Val" "0R"
			(at 0 0 0)
			(layer "F.Fab")
			(hide yes)
			(effects
				(font
					(size 1 1)
					(thickness 0.15)
				)
			)
		)
		(sheetname "HDMI + Ethernet")
		(sheetfile "hdmi-ethernet.kicad_sch")
		(attr smd)
		(fp_rect
			(start -0.925 -0.47)
			(end 0.925 0.47)
			(stroke
				(width 0.05)
				(type default)
			)
			(fill no)
			(layer "F.CrtYd")
		)
		(fp_rect
			(start -0.5 -0.25)
			(end 0.5 0.25)
			(stroke
				(width 0.15)
				(type solid)
			)
			(fill no)
			(layer "F.Fab")
		)
		(pad "1" smd roundrect
			(at -0.48 0)
			(size 0.59 0.64)
			(layers "F.Cu" "F.Mask" "F.Paste")
			(roundrect_rratio 0.25)
			(net 527 "/FPGA Bank 16 & 17/HDMI.D1_N")
			(pintype "passive")
		)
		(pad "2" smd roundrect
			(at 0.48 0)
			(size 0.59 0.64)
			(layers "F.Cu" "F.Mask" "F.Paste")
			(roundrect_rratio 0.25)
			(net 864 "/HDMI + Ethernet/HDMI_CONN_D1_N")
			(pintype "passive")
		)
	)
	(footprint "antmicro-footprints:FB_0603_1608Metric"
		(layer "F.Cu")
		(at 207.038 98.85 180)
		(property "Reference" "FB7"
			(at -4.962 -7.75 180)
			(layer "F.SilkS")
			(effects
				(font
					(size 0.7 0.7)
					(thickness 0.15)
				)
				(justify left bottom)
			)
		)
		(property "Value" "FB_120Z_2A_Murata-BLM18PG_0603"
			(at 0 1.7 180)
			(layer "F.Fab")
			(effects
				(font
					(size 0.7 0.7)
					(thickness 0.15)
				)
				(justify left bottom)
			)
		)
		(property "Description" "Ferrite Bead, 0603 [1608 Metric], 120 ohm, 2 A, BLM18P, 0.05 ohm, ± 25%, DC power line"
			(at 0 0 180)
			(layer "F.Fab")
			(hide yes)
			(effects
				(font
					(size 1.27 1.27)
					(thickness 0.15)
				)
			)
		)
		(property "Author" "Antmicro"
			(at 414.076 197.7 0)
			(layer "F.Fab")
			(hide yes)
			(effects
				(font
					(size 1 1)
					(thickness 0.15)
				)
			)
		)
		(property "Current" ""
			(at 414.076 197.7 0)
			(layer "F.Fab")
			(hide yes)
			(effects
				(font
					(size 1 1)
					(thickness 0.15)
				)
			)
		)
		(property "License" "Apache-2.0"
			(at 414.076 197.7 0)
			(layer "F.Fab")
			(hide yes)
			(effects
				(font
					(size 1 1)
					(thickness 0.15)
				)
			)
		)
		(property "MPN" "BLM18PG121SN1D"
			(at 414.076 197.7 0)
			(layer "F.Fab")
			(hide yes)
			(effects
				(font
					(size 1 1)
					(thickness 0.15)
				)
			)
		)
		(property "Manufacturer" "Murata"
			(at 414.076 197.7 0)
			(layer "F.Fab")
			(hide yes)
			(effects
				(font
					(size 1 1)
					(thickness 0.15)
				)
			)
		)
		(property "Val" "120Z/2A"
			(at 414.076 197.7 0)
			(layer "F.Fab")
			(hide yes)
			(effects
				(font
					(size 1 1)
					(thickness 0.15)
				)
			)
		)
		(sheetname "HDMI + Ethernet")
		(sheetfile "hdmi-ethernet.kicad_sch")
		(attr smd)
		(fp_line
			(start -0.15 0.4)
			(end 0.15 0.4)
			(stroke
				(width 0.15)
				(type solid)
			)
			(layer "F.SilkS")
		)
		(fp_line
			(start -0.15 -0.4)
			(end 0.15 -0.4)
			(stroke
				(width 0.15)
				(type solid)
			)
			(layer "F.SilkS")
		)
		(fp_rect
			(start -1.25 -0.65)
			(end 1.25 0.65)
			(stroke
				(width 0.05)
				(type solid)
			)
			(fill no)
			(layer "F.CrtYd")
		)
		(fp_line
			(start 0.8 0.406)
			(end -0.803 0.406)
			(stroke
				(width 0.15)
				(type solid)
			)
			(layer "F.Fab")
		)
		(fp_line
			(start 0.8 -0.408)
			(end 0.8 0.406)
			(stroke
				(width 0.15)
				(type solid)
			)
			(layer "F.Fab")
		)
		(fp_line
			(start 0.8 -0.408)
			(end -0.803 -0.408)
			(stroke
				(width 0.15)
				(type solid)
			)
			(layer "F.Fab")
		)
		(fp_line
			(start -0.803 0.406)
			(end -0.803 -0.408)
			(stroke
				(width 0.15)
				(type solid)
			)
			(layer "F.Fab")
		)
		(pad "1" smd roundrect
			(at -0.7 0 180)
			(size 0.8 1)
			(layers "F.Cu" "F.Mask" "F.Paste")
			(roundrect_rratio 0.2)
			(net 24 "+3V3")
			(pintype "passive")
		)
		(pad "2" smd roundrect
			(at 0.7 0 180)
			(size 0.8 1)
			(layers "F.Cu" "F.Mask" "F.Paste")
			(roundrect_rratio 0.2)
			(net 717 "/HDMI + Ethernet/GBE_AVDDH")
			(pintype "passive")
		)
	)
	(footprint "antmicro-footprints:C_0402_1005Metric"
		(layer "F.Cu")
		(at 195.803752 95.6615)
		(descr "Capacitor SMD 0402")
		(tags "capacitor SMD 0402")
		(property "Reference" "C264"
			(at -1.578752 -0.4615 0)
			(layer "F.SilkS")
			(effects
				(font
					(size 0.7 0.7)
					(thickness 0.15)
				)
				(justify left bottom)
			)
		)
		(property "Value" "C_100n_0402"
			(at 0 1.169 0)
			(layer "F.Fab")
			(effects
				(font
					(size 0.7 0.7)
					(thickness 0.15)
				)
				(justify left bottom)
			)
		)
		(property "Description" "SMD Multilayer Ceramic Capacitor, 0.1 µF, 50 V, 0402 [1005 Metric], ± 10%, X5R, GRM Series"
			(at 0 0 0)
			(layer "F.Fab")
			(hide yes)
			(effects
				(font
					(size 1.27 1.27)
					(thickness 0.15)
				)
			)
		)
		(property "Author" "Antmicro"
			(at 0 0 0)
			(layer "F.Fab")
			(hide yes)
			(effects
				(font
					(size 1 1)
					(thickness 0.15)
				)
			)
		)
		(property "Dielectric" "X5R"
			(at 0 0 0)
			(layer "F.Fab")
			(hide yes)
			(effects
				(font
					(size 1 1)
					(thickness 0.15)
				)
			)
		)
		(property "License" "Apache-2.0"
			(at 0 0 0)
			(layer "F.Fab")
			(hide yes)
			(effects
				(font
					(size 1 1)
					(thickness 0.15)
				)
			)
		)
		(property "MPN" "GRM155R61H104KE14D"
			(at 0 0 0)
			(layer "F.Fab")
			(hide yes)
			(effects
				(font
					(size 1 1)
					(thickness 0.15)
				)
			)
		)
		(property "Manufacturer" "Murata"
			(at 0 0 0)
			(layer "F.Fab")
			(hide yes)
			(effects
				(font
					(size 1 1)
					(thickness 0.15)
				)
			)
		)
		(property "Val" "100n"
			(at 0 0 0)
			(layer "F.Fab")
			(hide yes)
			(effects
				(font
					(size 1 1)
					(thickness 0.15)
				)
			)
		)
		(property "Voltage" "50V"
			(at 0 0 0)
			(layer "F.Fab")
			(hide yes)
			(effects
				(font
					(size 1 1)
					(thickness 0.15)
				)
			)
		)
		(sheetname "HDMI + Ethernet")
		(sheetfile "hdmi-ethernet.kicad_sch")
		(attr smd)
		(fp_rect
			(start -0.925 -0.47)
			(end 0.925 0.47)
			(stroke
				(width 0.05)
				(type default)
			)
			(fill no)
			(layer "F.CrtYd")
		)
		(fp_line
			(start -0.494 -0.25)
			(end 0.504 -0.25)
			(stroke
				(width 0.15)
				(type solid)
			)
			(layer "F.Fab")
		)
		(fp_line
			(start -0.494 0.248)
			(end -0.494 -0.25)
			(stroke
				(width 0.15)
				(type solid)
			)
			(layer "F.Fab")
		)
		(fp_line
			(start 0.504 -0.25)
			(end 0.504 0.248)
			(stroke
				(width 0.15)
				(type solid)
			)
			(layer "F.Fab")
		)
		(fp_line
			(start 0.504 0.248)
			(end -0.494 0.248)
			(stroke
				(width 0.15)
				(type solid)
			)
			(layer "F.Fab")
		)
		(pad "1" smd roundrect
			(at -0.48 0)
			(size 0.59 0.64)
			(layers "F.Cu" "F.Mask" "F.Paste")
			(roundrect_rratio 0.25)
			(net 1 "GND")
			(pintype "passive")
		)
		(pad "2" smd roundrect
			(at 0.48 0)
			(size 0.59 0.64)
			(layers "F.Cu" "F.Mask" "F.Paste")
			(roundrect_rratio 0.25)
			(net 24 "+3V3")
			(pintype "passive")
		)
	)
	(footprint "antmicro-footprints:VQFN-20_5x5x1mm_P0.65mm"
		(layer "F.Cu")
		(at 252.6 174.9)
		(property "Reference" "U7"
			(at -0.75 -2.9 0)
			(layer "F.SilkS")
			(effects
				(font
					(size 0.7 0.7)
					(thickness 0.15)
				)
				(justify left bottom)
			)
		)
		(property "Value" "TPS2372-3RGWR"
			(at 0 3.883 0)
			(layer "F.Fab")
			(effects
				(font
					(size 0.7 0.7)
					(thickness 0.15)
				)
				(justify left bottom)
			)
		)
		(property "Description" "PoE interface"
			(at 0 0 0)
			(layer "F.Fab")
			(hide yes)
			(effects
				(font
					(size 1.27 1.27)
					(thickness 0.15)
				)
			)
		)
		(property "Author" "Antmicro"
			(at 0 0 0)
			(layer "F.Fab")
			(hide yes)
			(effects
				(font
					(size 1 1)
					(thickness 0.15)
				)
			)
		)
		(property "License" "Apache-2.0"
			(at 0 0 0)
			(layer "F.Fab")
			(hide yes)
			(effects
				(font
					(size 1 1)
					(thickness 0.15)
				)
			)
		)
		(property "MPN" "TPS2372-3RGWR"
			(at 0 0 0)
			(layer "F.Fab")
			(hide yes)
			(effects
				(font
					(size 1 1)
					(thickness 0.15)
				)
			)
		)
		(property "Manufacturer" "Texas Instruments"
			(at 0 0 0)
			(layer "F.Fab")
			(hide yes)
			(effects
				(font
					(size 1 1)
					(thickness 0.15)
				)
			)
		)
		(sheetname "Power supply")
		(sheetfile "power-supply.kicad_sch")
		(attr smd)
		(fp_line
			(start -2.5 2.499)
			(end -2.5 1.789)
			(stroke
				(width 0.15)
				(type solid)
			)
			(layer "F.SilkS")
		)
		(fp_line
			(start -2.5 2.499)
			(end -1.79 2.499)
			(stroke
				(width 0.15)
				(type solid)
			)
			(layer "F.SilkS")
		)
		(fp_line
			(start -1.625 -2.5)
			(end -2.5 -2.5)
			(stroke
				(width 0.15)
				(type solid)
			)
			(layer "F.SilkS")
		)
		(fp_line
			(start 2.499 -2.5)
			(end 1.789 -2.5)
			(stroke
				(width 0.15)
				(type solid)
			)
			(layer "F.SilkS")
		)
		(fp_line
			(start 2.499 -2.5)
			(end 2.499 -1.79)
			(stroke
				(width 0.15)
				(type solid)
			)
			(layer "F.SilkS")
		)
		(fp_line
			(start 2.499 2.499)
			(end 1.789 2.499)
			(stroke
				(width 0.15)
				(type solid)
			)
			(layer "F.SilkS")
		)
		(fp_line
			(start 2.499 2.499)
			(end 2.499 1.789)
			(stroke
				(width 0.15)
				(type solid)
			)
			(layer "F.SilkS")
		)
		(fp_circle
			(center -2.775 -1.875)
			(end -2.725 -1.825)
			(stroke
				(width 0.15)
				(type solid)
			)
			(fill yes)
			(layer "F.SilkS")
		)
		(fp_poly
			(pts
				(xy -1.081 -1.081) (xy -0.11 -1.081) (xy -0.11 -0.09) (xy -1.081 -0.09)
			)
			(stroke
				(width 0.01)
				(type solid)
			)
			(fill yes)
			(layer "F.Paste")
		)
		(fp_poly
			(pts
				(xy -1.081 0.088) (xy -0.11 0.088) (xy -0.11 1.08) (xy -1.081 1.08)
			)
			(stroke
				(width 0.01)
				(type solid)
			)
			(fill yes)
			(layer "F.Paste")
		)
		(fp_poly
			(pts
				(xy 0.108 -1.081) (xy 1.08 -1.081) (xy 1.08 -0.09) (xy 0.108 -0.09)
			)
			(stroke
				(width 0.01)
				(type solid)
			)
			(fill yes)
			(layer "F.Paste")
		)
		(fp_poly
			(pts
				(xy 0.108 0.088) (xy 1.08 0.088) (xy 1.08 1.08) (xy 0.108 1.08)
			)
			(stroke
				(width 0.01)
				(type solid)
			)
			(fill yes)
			(layer "F.Paste")
		)
		(fp_rect
			(start -2.95 -2.95)
			(end 2.95 2.95)
			(stroke
				(width 0.05)
				(type solid)
			)
			(fill no)
			(layer "F.CrtYd")
		)
		(fp_line
			(start -2.5 -1.65)
			(end -1.65 -2.5)
			(stroke
				(width 0.15)
				(type solid)
			)
			(layer "F.Fab")
		)
		(fp_line
			(start -2.5 2.499)
			(end -2.5 -1.65)
			(stroke
				(width 0.15)
				(type solid)
			)
			(layer "F.Fab")
		)
		(fp_line
			(start 2.499 -2.5)
			(end -1.65 -2.5)
			(stroke
				(width 0.15)
				(type solid)
			)
			(layer "F.Fab")
		)
		(fp_line
			(start 2.499 2.499)
			(end -2.5 2.499)
			(stroke
				(width 0.15)
				(type solid)
			)
			(layer "F.Fab")
		)
		(fp_line
			(start 2.499 2.499)
			(end 2.499 -2.5)
			(stroke
				(width 0.15)
				(type solid)
			)
			(layer "F.Fab")
		)
		(pad "1" smd roundrect
			(at -2.327 -1.301)
			(size 0.75 0.31)
			(layers "F.Cu" "F.Mask" "F.Paste")
			(roundrect_rratio 0.25)
			(net 698 "/Power supply/VDD")
			(pinfunction "VDD")
			(pintype "power_in")
		)
		(pad "2" smd roundrect
			(at -2.327 -0.652)
			(size 0.75 0.31)
			(layers "F.Cu" "F.Mask" "F.Paste")
			(roundrect_rratio 0.25)
			(net 887 "/Power supply/DEN")
			(pinfunction "DEN")
			(pintype "input")
		)
		(pad "3" smd roundrect
			(at -2.327 0)
			(size 0.75 0.31)
			(layers "F.Cu" "F.Mask" "F.Paste")
			(roundrect_rratio 0.25)
			(net 885 "/Power supply/CLSA")
			(pinfunction "CLSA")
			(pintype "input")
		)
		(pad "4" smd roundrect
			(at -2.327 0.65)
			(size 0.75 0.31)
			(layers "F.Cu" "F.Mask" "F.Paste")
			(roundrect_rratio 0.25)
			(net 697 "/Power supply/VSS")
			(pinfunction "VSSA")
			(pintype "power_in")
		)
		(pad "5" smd roundrect
			(at -2.327 1.3)
			(size 0.75 0.31)
			(layers "F.Cu" "F.Mask" "F.Paste")
			(roundrect_rratio 0.25)
			(net 697 "/Power supply/VSS")
			(pinfunction "VSSB")
			(pintype "power_in")
		)
		(pad "6" smd roundrect
			(at -1.301 2.325)
			(size 0.31 0.75)
			(layers "F.Cu" "F.Mask" "F.Paste")
			(roundrect_rratio 0.25)
			(net 886 "/Power supply/CLSB")
			(pinfunction "CLSB")
			(pintype "input")
		)
		(pad "7" smd roundrect
			(at -0.652 2.325)
			(size 0.31 0.75)
			(layers "F.Cu" "F.Mask" "F.Paste")
			(roundrect_rratio 0.25)
			(net 882 "/Power supply/REF")
			(pinfunction "REF")
			(pintype "input")
		)
		(pad "8" smd roundrect
			(at 0 2.325)
			(size 0.31 0.75)
			(layers "F.Cu" "F.Mask" "F.Paste")
			(roundrect_rratio 0.25)
			(net 881 "/Power supply/AMPS_CTL")
			(pinfunction "AMPS_CTL")
			(pintype "input")
		)
		(pad "9" smd roundrect
			(at 0.65 2.325)
			(size 0.31 0.75)
			(layers "F.Cu" "F.Mask" "F.Paste")
			(roundrect_rratio 0.25)
			(net 883 "/Power supply/MPS_DUTY")
			(pinfunction "MPS_DUTY")
			(pintype "input")
		)
		(pad "10" smd roundrect
			(at 1.3 2.325)
			(size 0.31 0.75)
			(layers "F.Cu" "F.Mask" "F.Paste")
			(roundrect_rratio 0.25)
			(net 1148 "unconnected-(U7-~{AUTCLS}-Pad10)")
			(pinfunction "~{AUTCLS}")
			(pintype "input+no_connect")
		)
		(pad "11" smd roundrect
			(at 2.325 1.3)
			(size 0.75 0.31)
			(layers "F.Cu" "F.Mask" "F.Paste")
			(roundrect_rratio 0.25)
			(net 699 "GNDD")
			(pinfunction "RTNA")
			(pintype "output")
		)
		(pad "12" smd roundrect
			(at 2.325 0.65)
			(size 0.75 0.31)
			(layers "F.Cu" "F.Mask" "F.Paste")
			(roundrect_rratio 0.25)
			(net 699 "GNDD")
			(pinfunction "RTNB")
			(pintype "output")
		)
		(pad "13" smd roundrect
			(at 2.325 0)
			(size 0.75 0.31)
			(layers "F.Cu" "F.Mask" "F.Paste")
			(roundrect_rratio 0.25)
			(net 889 "/Power supply/PG")
			(pinfunction "PG")
			(pintype "output")
		)
		(pad "14" smd roundrect
			(at 2.325 -0.652)
			(size 0.75 0.31)
			(layers "F.Cu" "F.Mask" "F.Paste")
			(roundrect_rratio 0.25)
			(net 1149 "unconnected-(U7-NC-Pad14)")
			(pinfunction "NC")
			(pintype "no_connect")
		)
		(pad "15" smd roundrect
			(at 2.325 -1.301)
			(size 0.75 0.31)
			(layers "F.Cu" "F.Mask" "F.Paste")
			(roundrect_rratio 0.25)
			(net 1150 "unconnected-(U7-NC-Pad15)")
			(pinfunction "NC")
			(pintype "no_connect")
		)
		(pad "16" smd roundrect
			(at 1.3 -2.327)
			(size 0.31 0.75)
			(layers "F.Cu" "F.Mask" "F.Paste")
			(roundrect_rratio 0.25)
			(net 1151 "unconnected-(U7-IRSHDL_EN-Pad16)")
			(pinfunction "IRSHDL_EN")
			(pintype "output+no_connect")
		)
		(pad "17" smd roundrect
			(at 0.65 -2.327)
			(size 0.31 0.75)
			(layers "F.Cu" "F.Mask" "F.Paste")
			(roundrect_rratio 0.25)
			(net 1152 "unconnected-(U7-TPL-Pad17)")
			(pinfunction "TPL")
			(pintype "output+no_connect")
		)
		(pad "18" smd roundrect
			(at 0 -2.327)
			(size 0.31 0.75)
			(layers "F.Cu" "F.Mask" "F.Paste")
			(roundrect_rratio 0.25)
			(net 1153 "unconnected-(U7-TPH-Pad18)")
			(pinfunction "TPH")
			(pintype "output+no_connect")
		)
		(pad "19" smd roundrect
			(at -0.652 -2.327)
			(size 0.31 0.75)
			(layers "F.Cu" "F.Mask" "F.Paste")
			(roundrect_rratio 0.25)
			(net 1154 "unconnected-(U7-~{BT}-Pad19)")
			(pinfunction "~{BT}")
			(pintype "output+no_connect")
		)
		(pad "20" smd roundrect
			(at -1.301 -2.327)
			(size 0.31 0.75)
			(layers "F.Cu" "F.Mask" "F.Paste")
			(roundrect_rratio 0.25)
			(net 1155 "unconnected-(U7-NC-Pad20)")
			(pinfunction "NC")
			(pintype "no_connect")
		)
		(pad "21" smd rect
			(at 0 0)
			(size 2.2 2.2)
			(layers "F.Cu" "F.Mask")
			(net 697 "/Power supply/VSS")
			(pinfunction "PAD_VSSC")
			(pintype "power_in")
		)
	)
	(footprint "antmicro-footprints:Oscillator_SMD_Abracon_AX3_3.2x2.5x1mm"
		(layer "F.Cu")
		(at 189.915001 150.886 90)
		(property "Reference" "Y6"
			(at 0.686 -2.05 90)
			(layer "F.SilkS")
			(effects
				(font
					(size 0.7 0.7)
					(thickness 0.15)
				)
				(justify right bottom)
			)
		)
		(property "Value" "Oscillator_200MHz_AX3DC"
			(at 0 2.8 90)
			(layer "F.Fab")
			(effects
				(font
					(size 0.7 0.7)
					(thickness 0.15)
				)
				(justify left bottom)
			)
		)
		(property "Description" "150 MHz XO (Standard) LVDS Oscillator 1.8V Enable/Disable 6-SMD, No Lead"
			(at 0 0 90)
			(layer "F.Fab")
			(hide yes)
			(effects
				(font
					(size 1.27 1.27)
					(thickness 0.15)
				)
			)
		)
		(property "Author" "Antmicro"
			(at 340.801001 -39.029001 0)
			(layer "F.Fab")
			(hide yes)
			(effects
				(font
					(size 1 1)
					(thickness 0.15)
				)
			)
		)
		(property "License" "Apache-2.0"
			(at 340.801001 -39.029001 0)
			(layer "F.Fab")
			(hide yes)
			(effects
				(font
					(size 1 1)
					(thickness 0.15)
				)
			)
		)
		(property "MPN" "AX3DCF1-200.0000"
			(at 340.801001 -39.029001 0)
			(layer "F.Fab")
			(hide yes)
			(effects
				(font
					(size 1 1)
					(thickness 0.15)
				)
			)
		)
		(property "Manufacturer" "Abracon"
			(at 340.801001 -39.029001 0)
			(layer "F.Fab")
			(hide yes)
			(effects
				(font
					(size 1 1)
					(thickness 0.15)
				)
			)
		)
		(property "Val" "200 MHz"
			(at 340.801001 -39.029001 0)
			(layer "F.Fab")
			(hide yes)
			(effects
				(font
					(size 1 1)
					(thickness 0.15)
				)
			)
		)
		(sheetname "Clocks")
		(sheetfile "clocks.kicad_sch")
		(attr smd)
		(fp_line
			(start 1.5 -1.8)
			(end -1.5 -1.8)
			(stroke
				(width 0.12)
				(type solid)
			)
			(layer "F.SilkS")
		)
		(fp_line
			(start -1.5 -1.8)
			(end -1.5 -1.5)
			(stroke
				(width 0.12)
				(type solid)
			)
			(layer "F.SilkS")
		)
		(fp_line
			(start 1.5 -1.5)
			(end 1.5 -1.8)
			(stroke
				(width 0.12)
				(type solid)
			)
			(layer "F.SilkS")
		)
		(fp_line
			(start -1.5 1.5)
			(end -1.5 1.8)
			(stroke
				(width 0.12)
				(type solid)
			)
			(layer "F.SilkS")
		)
		(fp_line
			(start 1.5 1.8)
			(end 1.5 1.5)
			(stroke
				(width 0.12)
				(type solid)
			)
			(layer "F.SilkS")
		)
		(fp_line
			(start -1.5 1.8)
			(end 1.5 1.8)
			(stroke
				(width 0.12)
				(type solid)
			)
			(layer "F.SilkS")
		)
		(fp_circle
			(center -1.7 -1.9)
			(end -1.7 -1.85)
			(stroke
				(width 0.15)
				(type solid)
			)
			(fill yes)
			(layer "F.SilkS")
		)
		(fp_rect
			(start 1.6 -1.9)
			(end -1.6 1.9)
			(stroke
				(width 0.05)
				(type solid)
			)
			(fill no)
			(layer "F.CrtYd")
		)
		(fp_line
			(start -0.6 -1.6)
			(end -1.3 -0.9)
			(stroke
				(width 0.15)
				(type solid)
			)
			(layer "F.Fab")
		)
		(fp_rect
			(start 1.3 -1.601)
			(end -1.3 1.599)
			(stroke
				(width 0.15)
				(type solid)
			)
			(fill no)
			(layer "F.Fab")
		)
		(pad "1" smd rect
			(at -0.8 -1.199)
			(size 0.9 1.1)
			(layers "F.Cu" "F.Mask" "F.Paste")
			(net 640 "/Clocks/LVDS_XO_200M_ENA")
			(pinfunction "EN")
			(pintype "input")
		)
		(pad "2" smd rect
			(at -0.8 0)
			(size 0.9 1.1)
			(layers "F.Cu" "F.Mask" "F.Paste")
			(net 1412 "unconnected-(Y6-NC-Pad2)")
			(pinfunction "NC")
			(pintype "no_connect")
		)
		(pad "3" smd rect
			(at -0.8 1.199)
			(size 0.9 1.1)
			(layers "F.Cu" "F.Mask" "F.Paste")
			(net 1 "GND")
			(pinfunction "GND")
			(pintype "power_in")
		)
		(pad "4" smd rect
			(at 0.801 1.199)
			(size 0.9 1.1)
			(layers "F.Cu" "F.Mask" "F.Paste")
			(net 624 "/Clocks/SYS.CLK_P")
			(pinfunction "OUT+")
			(pintype "output")
		)
		(pad "5" smd rect
			(at 0.801 0)
			(size 0.9 1.1)
			(layers "F.Cu" "F.Mask" "F.Paste")
			(net 623 "/Clocks/SYS.CLK_N")
			(pinfunction "OUT-")
			(pintype "output")
		)
		(pad "6" smd rect
			(at 0.801 -1.199)
			(size 0.9 1.1)
			(layers "F.Cu" "F.Mask" "F.Paste")
			(net 26 "+1V8")
			(pinfunction "VCC")
			(pintype "power_in")
		)
	)
	(footprint "antmicro-footprints:C_0402_1005Metric"
		(layer "F.Cu")
		(at 231.8 124.5 180)
		(descr "Capacitor SMD 0402")
		(tags "capacitor SMD 0402")
		(property "Reference" "C217"
			(at 0.9 -0.35 0)
			(layer "F.SilkS")
			(effects
				(font
					(size 0.7 0.7)
					(thickness 0.15)
				)
				(justify right bottom)
			)
		)
		(property "Value" "C_1u_0402"
			(at 0 1.4 0)
			(layer "F.Fab")
			(effects
				(font
					(size 0.7 0.7)
					(thickness 0.15)
				)
				(justify right bottom)
			)
		)
		(property "Description" "SMD Multilayer Ceramic Capacitor, 1 µF, 10 V, 0402 [1005 Metric], ± 10%, X6S, C"
			(at 0 0 180)
			(layer "F.Fab")
			(hide yes)
			(effects
				(font
					(size 1.27 1.27)
					(thickness 0.15)
				)
			)
		)
		(property "Author" "Antmicro"
			(at 463.6 249 0)
			(layer "F.Fab")
			(hide yes)
			(effects
				(font
					(size 1 1)
					(thickness 0.15)
				)
			)
		)
		(property "Dielectric" ""
			(at 463.6 249 0)
			(layer "F.Fab")
			(hide yes)
			(effects
				(font
					(size 1 1)
					(thickness 0.15)
				)
			)
		)
		(property "License" "Apache-2.0"
			(at 463.6 249 0)
			(layer "F.Fab")
			(hide yes)
			(effects
				(font
					(size 1 1)
					(thickness 0.15)
				)
			)
		)
		(property "MPN" "C1005X6S1A105K050BC"
			(at 463.6 249 0)
			(layer "F.Fab")
			(hide yes)
			(effects
				(font
					(size 1 1)
					(thickness 0.15)
				)
			)
		)
		(property "Manufacturer" "TDK"
			(at 463.6 249 0)
			(layer "F.Fab")
			(hide yes)
			(effects
				(font
					(size 1 1)
					(thickness 0.15)
				)
			)
		)
		(property "Val" "1u"
			(at 463.6 249 0)
			(layer "F.Fab")
			(hide yes)
			(effects
				(font
					(size 1 1)
					(thickness 0.15)
				)
			)
		)
		(property "Voltage" ""
			(at 463.6 249 0)
			(layer "F.Fab")
			(hide yes)
			(effects
				(font
					(size 1 1)
					(thickness 0.15)
				)
			)
		)
		(sheetname "User GPIO + LED + button + DIP switch")
		(sheetfile "user-gpio.kicad_sch")
		(attr smd)
		(fp_rect
			(start -0.925 -0.47)
			(end 0.925 0.47)
			(stroke
				(width 0.05)
				(type default)
			)
			(fill no)
			(layer "F.CrtYd")
		)
		(fp_line
			(start 0.504 0.248)
			(end -0.494 0.248)
			(stroke
				(width 0.15)
				(type solid)
			)
			(layer "F.Fab")
		)
		(fp_line
			(start 0.504 -0.25)
			(end 0.504 0.248)
			(stroke
				(width 0.15)
				(type solid)
			)
			(layer "F.Fab")
		)
		(fp_line
			(start -0.494 0.248)
			(end -0.494 -0.25)
			(stroke
				(width 0.15)
				(type solid)
			)
			(layer "F.Fab")
		)
		(fp_line
			(start -0.494 -0.25)
			(end 0.504 -0.25)
			(stroke
				(width 0.15)
				(type solid)
			)
			(layer "F.Fab")
		)
		(pad "1" smd roundrect
			(at -0.48 0 180)
			(size 0.59 0.64)
			(layers "F.Cu" "F.Mask" "F.Paste")
			(roundrect_rratio 0.25)
			(net 1 "GND")
			(pintype "passive")
		)
		(pad "2" smd roundrect
			(at 0.48 0 180)
			(size 0.59 0.64)
			(layers "F.Cu" "F.Mask" "F.Paste")
			(roundrect_rratio 0.25)
			(net 703 "+5V")
			(pintype "passive")
		)
	)
	(footprint "antmicro-footprints:R_0402_1005Metric"
		(layer "F.Cu")
		(at 237.65 141.7 -90)
		(descr "Resistor SMD 0402")
		(tags "resistor SMD 0402")
		(property "Reference" "R181"
			(at 3.85 -6.85 270)
			(layer "F.SilkS")
			(effects
				(font
					(size 0.7 0.7)
					(thickness 0.15)
				)
				(justify left bottom)
			)
		)
		(property "Value" "R_0R_0402"
			(at 0 1.4 270)
			(layer "F.Fab")
			(effects
				(font
					(size 0.7 0.7)
					(thickness 0.15)
				)
				(justify left bottom)
			)
		)
		(property "Description" "SMD Chip Resistor, Jumper, 0 ohm, 100 mW, 0402 [1005 Metric], Thick Film, General Purpose"
			(at 0 0 270)
			(layer "F.Fab")
			(hide yes)
			(effects
				(font
					(size 1.27 1.27)
					(thickness 0.15)
				)
			)
		)
		(property "Author" "Antmicro"
			(at 95.95 379.35 0)
			(layer "F.Fab")
			(hide yes)
			(effects
				(font
					(size 1 1)
					(thickness 0.15)
				)
			)
		)
		(property "Current" "1A"
			(at 95.95 379.35 0)
			(layer "F.Fab")
			(hide yes)
			(effects
				(font
					(size 1 1)
					(thickness 0.15)
				)
			)
		)
		(property "DNP" "DNP"
			(at 95.95 379.35 0)
			(layer "F.Fab")
			(hide yes)
			(effects
				(font
					(size 1 1)
					(thickness 0.15)
				)
			)
		)
		(property "License" "Apache-2.0"
			(at 95.95 379.35 0)
			(layer "F.Fab")
			(hide yes)
			(effects
				(font
					(size 1 1)
					(thickness 0.15)
				)
			)
		)
		(property "MPN" "ERJ2GE0R00X"
			(at 95.95 379.35 0)
			(layer "F.Fab")
			(hide yes)
			(effects
				(font
					(size 1 1)
					(thickness 0.15)
				)
			)
		)
		(property "Manufacturer" "Panasonic"
			(at 95.95 379.35 0)
			(layer "F.Fab")
			(hide yes)
			(effects
				(font
					(size 1 1)
					(thickness 0.15)
				)
			)
		)
		(property "Tolerance" ""
			(at 95.95 379.35 0)
			(layer "F.Fab")
			(hide yes)
			(effects
				(font
					(size 1 1)
					(thickness 0.15)
				)
			)
		)
		(property "Val" "0R"
			(at 95.95 379.35 0)
			(layer "F.Fab")
			(hide yes)
			(effects
				(font
					(size 1 1)
					(thickness 0.15)
				)
			)
		)
		(property "dnp" ""
			(at 95.95 379.35 0)
			(layer "F.Fab")
			(hide yes)
			(effects
				(font
					(size 1 1)
					(thickness 0.15)
				)
			)
		)
		(property "exclude_from_bom" ""
			(at 95.95 379.35 0)
			(layer "F.Fab")
			(hide yes)
			(effects
				(font
					(size 1 1)
					(thickness 0.15)
				)
			)
		)
		(sheetname "USB PHY")
		(sheetfile "usb-phy.kicad_sch")
		(attr smd exclude_from_bom)
		(fp_rect
			(start -0.925 -0.47)
			(end 0.925 0.47)
			(stroke
				(width 0.05)
				(type default)
			)
			(fill no)
			(layer "F.CrtYd")
		)
		(fp_rect
			(start -0.5 -0.25)
			(end 0.5 0.25)
			(stroke
				(width 0.15)
				(type solid)
			)
			(fill no)
			(layer "F.Fab")
		)
		(pad "1" smd roundrect
			(at -0.48 0 270)
			(size 0.59 0.64)
			(layers "F.Cu" "F.Mask" "F.Paste")
			(roundrect_rratio 0.25)
			(net 934 "/USB PHY/SPI_EN")
			(pintype "passive")
		)
		(pad "2" smd roundrect
			(at 0.48 0 270)
			(size 0.59 0.64)
			(layers "F.Cu" "F.Mask" "F.Paste")
			(roundrect_rratio 0.25)
			(net 372 "Net-(U23-OE)")
			(pintype "passive")
		)
	)
	(footprint "antmicro-footprints:R_Array_4x0201_Panasonic_EXB18V"
		(layer "F.Cu")
		(at 251.4 122)
		(property "Reference" "R27"
			(at 1.25 -0.8 0)
			(layer "F.SilkS")
			(effects
				(font
					(size 0.7 0.7)
					(thickness 0.15)
				)
				(justify right bottom)
			)
		)
		(property "Value" "R_4x33R_0201_array"
			(at -1.1 1.8 0)
			(layer "F.Fab")
			(effects
				(font
					(size 0.7 0.7)
					(thickness 0.15)
				)
				(justify left bottom)
			)
		)
		(property "Description" "Fixed Network Resistor, 33 ohm, Isolated, 4 Resistors, 0502 [1406 Metric], Flat, ± 5%"
			(at 0 0 0)
			(layer "F.Fab")
			(hide yes)
			(effects
				(font
					(size 1.27 1.27)
					(thickness 0.15)
				)
			)
		)
		(property "Author" "Antmicro"
			(at 0 0 0)
			(layer "F.Fab")
			(hide yes)
			(effects
				(font
					(size 1 1)
					(thickness 0.15)
				)
			)
		)
		(property "License" "Apache-2.0"
			(at 0 0 0)
			(layer "F.Fab")
			(hide yes)
			(effects
				(font
					(size 1 1)
					(thickness 0.15)
				)
			)
		)
		(property "MPN" "EXB-18V330JX"
			(at 0 0 0)
			(layer "F.Fab")
			(hide yes)
			(effects
				(font
					(size 1 1)
					(thickness 0.15)
				)
			)
		)
		(property "Manufacturer" "Panasonic"
			(at 0 0 0)
			(layer "F.Fab")
			(hide yes)
			(effects
				(font
					(size 1 1)
					(thickness 0.15)
				)
			)
		)
		(property "Val" "R_4x33R_0201"
			(at 0 0 0)
			(layer "F.Fab")
			(hide yes)
			(effects
				(font
					(size 1 1)
					(thickness 0.15)
				)
			)
		)
		(sheetname "Supervisior MCU")
		(sheetfile "supervisor-mcu.kicad_sch")
		(attr smd)
		(fp_line
			(start -0.8 -0.45)
			(end -0.8 0.45)
			(stroke
				(width 0.12)
				(type solid)
			)
			(layer "F.SilkS")
		)
		(fp_line
			(start 0.8 -0.45)
			(end 0.8 0.45)
			(stroke
				(width 0.12)
				(type solid)
			)
			(layer "F.SilkS")
		)
		(fp_rect
			(start -0.898 -0.66)
			(end 0.898 0.65)
			(stroke
				(width 0.05)
				(type solid)
			)
			(fill no)
			(layer "F.CrtYd")
		)
		(pad "1" smd roundrect
			(at -0.6 0.298)
			(size 0.2 0.4)
			(layers "F.Cu" "F.Mask" "F.Paste")
			(roundrect_rratio 0.25)
			(net 1082 "/Supervisior MCU/TXD0")
			(pinfunction "R1.1")
			(pintype "passive")
		)
		(pad "2" smd roundrect
			(at -0.202 0.298)
			(size 0.2 0.4)
			(layers "F.Cu" "F.Mask" "F.Paste")
			(roundrect_rratio 0.25)
			(net 1081 "/Supervisior MCU/TXD1")
			(pinfunction "R2.1")
			(pintype "passive")
		)
		(pad "3" smd roundrect
			(at 0.2 0.298)
			(size 0.2 0.4)
			(layers "F.Cu" "F.Mask" "F.Paste")
			(roundrect_rratio 0.25)
			(net 1084 "/Supervisior MCU/RXD0")
			(pinfunction "R3.1")
			(pintype "passive")
		)
		(pad "4" smd roundrect
			(at 0.598 0.298)
			(size 0.2 0.4)
			(layers "F.Cu" "F.Mask" "F.Paste")
			(roundrect_rratio 0.25)
			(net 1087 "/Supervisior MCU/PGOOD_1V8")
			(pinfunction "R4.1")
			(pintype "passive")
		)
		(pad "5" smd roundrect
			(at 0.598 -0.3)
			(size 0.2 0.4)
			(layers "F.Cu" "F.Mask" "F.Paste")
			(roundrect_rratio 0.25)
			(net 1413 "/SUP_MCU.PG_1V2")
			(pinfunction "R4.2")
			(pintype "passive")
		)
		(pad "6" smd roundrect
			(at 0.2 -0.3)
			(size 0.2 0.4)
			(layers "F.Cu" "F.Mask" "F.Paste")
			(roundrect_rratio 0.25)
			(net 1331 "/SUP_MCU.RX0")
			(pinfunction "R3.2")
			(pintype "passive")
		)
		(pad "7" smd roundrect
			(at -0.202 -0.3)
			(size 0.2 0.4)
			(layers "F.Cu" "F.Mask" "F.Paste")
			(roundrect_rratio 0.25)
			(net 1328 "/SUP_MCU.TX1")
			(pinfunction "R2.2")
			(pintype "passive")
		)
		(pad "8" smd roundrect
			(at -0.6 -0.3)
			(size 0.2 0.4)
			(layers "F.Cu" "F.Mask" "F.Paste")
			(roundrect_rratio 0.25)
			(net 1329 "/SUP_MCU.TX0")
			(pinfunction "R1.2")
			(pintype "passive")
		)
	)
	(footprint "antmicro-footprints:C_0402_1005Metric"
		(layer "F.Cu")
		(at 226.7 147.5 90)
		(descr "Capacitor SMD 0402")
		(tags "capacitor SMD 0402")
		(property "Reference" "C271"
			(at 0.75 0.3 90)
			(layer "F.SilkS")
			(effects
				(font
					(size 0.7 0.7)
					(thickness 0.15)
				)
				(justify left bottom)
			)
		)
		(property "Value" "C_10u_0402"
			(at 0 1.4 90)
			(layer "F.Fab")
			(effects
				(font
					(size 0.7 0.7)
					(thickness 0.15)
				)
				(justify left bottom)
			)
		)
		(property "Description" "SMD Multilayer Ceramic Capacitor, 10 µF, 6.3 V, 0402 [1005 Metric], ± 20%, X5R, CC Series"
			(at 0 0 90)
			(layer "F.Fab")
			(hide yes)
			(effects
				(font
					(size 1.27 1.27)
					(thickness 0.15)
				)
			)
		)
		(property "Author" "Antmicro"
			(at 374.2 -79.2 0)
			(layer "F.Fab")
			(hide yes)
			(effects
				(font
					(size 1 1)
					(thickness 0.15)
				)
			)
		)
		(property "Dielectric" ""
			(at 374.2 -79.2 0)
			(layer "F.Fab")
			(hide yes)
			(effects
				(font
					(size 1 1)
					(thickness 0.15)
				)
			)
		)
		(property "License" "Apache-2.0"
			(at 374.2 -79.2 0)
			(layer "F.Fab")
			(hide yes)
			(effects
				(font
					(size 1 1)
					(thickness 0.15)
				)
			)
		)
		(property "MPN" "CC0402MRX5R5BB106"
			(at 374.2 -79.2 0)
			(layer "F.Fab")
			(hide yes)
			(effects
				(font
					(size 1 1)
					(thickness 0.15)
				)
			)
		)
		(property "Manufacturer" "YAGEO"
			(at 374.2 -79.2 0)
			(layer "F.Fab")
			(hide yes)
			(effects
				(font
					(size 1 1)
					(thickness 0.15)
				)
			)
		)
		(property "Val" "10u"
			(at 374.2 -79.2 0)
			(layer "F.Fab")
			(hide yes)
			(effects
				(font
					(size 1 1)
					(thickness 0.15)
				)
			)
		)
		(property "Voltage" ""
			(at 374.2 -79.2 0)
			(layer "F.Fab")
			(hide yes)
			(effects
				(font
					(size 1 1)
					(thickness 0.15)
				)
			)
		)
		(sheetname "HDMI + Ethernet")
		(sheetfile "hdmi-ethernet.kicad_sch")
		(attr smd)
		(fp_rect
			(start -0.925 -0.47)
			(end 0.925 0.47)
			(stroke
				(width 0.05)
				(type default)
			)
			(fill no)
			(layer "F.CrtYd")
		)
		(fp_line
			(start 0.504 -0.25)
			(end 0.504 0.248)
			(stroke
				(width 0.15)
				(type solid)
			)
			(layer "F.Fab")
		)
		(fp_line
			(start -0.494 -0.25)
			(end 0.504 -0.25)
			(stroke
				(width 0.15)
				(type solid)
			)
			(layer "F.Fab")
		)
		(fp_line
			(start 0.504 0.248)
			(end -0.494 0.248)
			(stroke
				(width 0.15)
				(type solid)
			)
			(layer "F.Fab")
		)
		(fp_line
			(start -0.494 0.248)
			(end -0.494 -0.25)
			(stroke
				(width 0.15)
				(type solid)
			)
			(layer "F.Fab")
		)
		(pad "1" smd roundrect
			(at -0.48 0 90)
			(size 0.59 0.64)
			(layers "F.Cu" "F.Mask" "F.Paste")
			(roundrect_rratio 0.25)
			(net 722 "/HDMI + Ethernet/ETH_VDDCR")
			(pintype "passive")
		)
		(pad "2" smd roundrect
			(at 0.48 0 90)
			(size 0.59 0.64)
			(layers "F.Cu" "F.Mask" "F.Paste")
			(roundrect_rratio 0.25)
			(net 1 "GND")
			(pintype "passive")
		)
	)
	(footprint "antmicro-footprints:C_0402_1005Metric"
		(layer "F.Cu")
		(at 164.7 140)
		(descr "Capacitor SMD 0402")
		(tags "capacitor SMD 0402")
		(property "Reference" "C391"
			(at -0.95 -1.5 0)
			(layer "F.SilkS")
			(effects
				(font
					(size 0.7 0.7)
					(thickness 0.15)
				)
				(justify left bottom)
			)
		)
		(property "Value" "C_100n_0402"
			(at 0 1.169 0)
			(layer "F.Fab")
			(effects
				(font
					(size 0.7 0.7)
					(thickness 0.15)
				)
				(justify left bottom)
			)
		)
		(property "Description" "SMD Multilayer Ceramic Capacitor, 0.1 µF, 50 V, 0402 [1005 Metric], ± 10%, X5R, GRM Series"
			(at 0 0 0)
			(layer "F.Fab")
			(hide yes)
			(effects
				(font
					(size 1.27 1.27)
					(thickness 0.15)
				)
			)
		)
		(property "Author" "Antmicro"
			(at 0 0 0)
			(layer "F.Fab")
			(hide yes)
			(effects
				(font
					(size 1 1)
					(thickness 0.15)
				)
			)
		)
		(property "Dielectric" "X5R"
			(at 0 0 0)
			(layer "F.Fab")
			(hide yes)
			(effects
				(font
					(size 1 1)
					(thickness 0.15)
				)
			)
		)
		(property "License" "Apache-2.0"
			(at 0 0 0)
			(layer "F.Fab")
			(hide yes)
			(effects
				(font
					(size 1 1)
					(thickness 0.15)
				)
			)
		)
		(property "MPN" "GRM155R61H104KE14D"
			(at 0 0 0)
			(layer "F.Fab")
			(hide yes)
			(effects
				(font
					(size 1 1)
					(thickness 0.15)
				)
			)
		)
		(property "Manufacturer" "Murata"
			(at 0 0 0)
			(layer "F.Fab")
			(hide yes)
			(effects
				(font
					(size 1 1)
					(thickness 0.15)
				)
			)
		)
		(property "Val" "100n"
			(at 0 0 0)
			(layer "F.Fab")
			(hide yes)
			(effects
				(font
					(size 1 1)
					(thickness 0.15)
				)
			)
		)
		(property "Voltage" "50V"
			(at 0 0 0)
			(layer "F.Fab")
			(hide yes)
			(effects
				(font
					(size 1 1)
					(thickness 0.15)
				)
			)
		)
		(sheetname "DRAM + SRAM")
		(sheetfile "ram.kicad_sch")
		(attr smd)
		(fp_rect
			(start -0.925 -0.47)
			(end 0.925 0.47)
			(stroke
				(width 0.05)
				(type default)
			)
			(fill no)
			(layer "F.CrtYd")
		)
		(fp_line
			(start -0.494 -0.25)
			(end 0.504 -0.25)
			(stroke
				(width 0.15)
				(type solid)
			)
			(layer "F.Fab")
		)
		(fp_line
			(start -0.494 0.248)
			(end -0.494 -0.25)
			(stroke
				(width 0.15)
				(type solid)
			)
			(layer "F.Fab")
		)
		(fp_line
			(start 0.504 -0.25)
			(end 0.504 0.248)
			(stroke
				(width 0.15)
				(type solid)
			)
			(layer "F.Fab")
		)
		(fp_line
			(start 0.504 0.248)
			(end -0.494 0.248)
			(stroke
				(width 0.15)
				(type solid)
			)
			(layer "F.Fab")
		)
		(pad "1" smd roundrect
			(at -0.48 0)
			(size 0.59 0.64)
			(layers "F.Cu" "F.Mask" "F.Paste")
			(roundrect_rratio 0.25)
			(net 1 "GND")
			(pintype "passive")
		)
		(pad "2" smd roundrect
			(at 0.48 0)
			(size 0.59 0.64)
			(layers "F.Cu" "F.Mask" "F.Paste")
			(roundrect_rratio 0.25)
			(net 25 "+1V35")
			(pintype "passive")
		)
	)
	(footprint "antmicro-footprints:R_0402_1005Metric"
		(layer "F.Cu")
		(at 179.5 175.7125)
		(descr "Resistor SMD 0402")
		(tags "resistor SMD 0402")
		(property "Reference" "R313"
			(at -1.775 1.2375 0)
			(layer "F.SilkS")
			(effects
				(font
					(size 0.7 0.7)
					(thickness 0.15)
				)
				(justify left bottom)
			)
		)
		(property "Value" "R_0R_0402"
			(at 0 1.4 0)
			(layer "F.Fab")
			(effects
				(font
					(size 0.7 0.7)
					(thickness 0.15)
				)
				(justify left bottom)
			)
		)
		(property "Description" "SMD Chip Resistor, Jumper, 0 ohm, 100 mW, 0402 [1005 Metric], Thick Film, General Purpose"
			(at 0 0 0)
			(layer "F.Fab")
			(hide yes)
			(effects
				(font
					(size 1.27 1.27)
					(thickness 0.15)
				)
			)
		)
		(property "Author" "Antmicro"
			(at 0 0 0)
			(layer "F.Fab")
			(hide yes)
			(effects
				(font
					(size 1 1)
					(thickness 0.15)
				)
			)
		)
		(property "Current" "1A"
			(at 0 0 0)
			(layer "F.Fab")
			(hide yes)
			(effects
				(font
					(size 1 1)
					(thickness 0.15)
				)
			)
		)
		(property "License" "Apache-2.0"
			(at 0 0 0)
			(layer "F.Fab")
			(hide yes)
			(effects
				(font
					(size 1 1)
					(thickness 0.15)
				)
			)
		)
		(property "MPN" "ERJ2GE0R00X"
			(at 0 0 0)
			(layer "F.Fab")
			(hide yes)
			(effects
				(font
					(size 1 1)
					(thickness 0.15)
				)
			)
		)
		(property "Manufacturer" "Panasonic"
			(at 0 0 0)
			(layer "F.Fab")
			(hide yes)
			(effects
				(font
					(size 1 1)
					(thickness 0.15)
				)
			)
		)
		(property "Tolerance" ""
			(at 0 0 0)
			(layer "F.Fab")
			(hide yes)
			(effects
				(font
					(size 1 1)
					(thickness 0.15)
				)
			)
		)
		(property "Val" "0R"
			(at 0 0 0)
			(layer "F.Fab")
			(hide yes)
			(effects
				(font
					(size 1 1)
					(thickness 0.15)
				)
			)
		)
		(sheetname "DC-DC Converters")
		(sheetfile "dc-dc.kicad_sch")
		(attr smd)
		(fp_rect
			(start -0.925 -0.47)
			(end 0.925 0.47)
			(stroke
				(width 0.05)
				(type default)
			)
			(fill no)
			(layer "F.CrtYd")
		)
		(fp_rect
			(start -0.5 -0.25)
			(end 0.5 0.25)
			(stroke
				(width 0.15)
				(type solid)
			)
			(fill no)
			(layer "F.Fab")
		)
		(pad "1" smd roundrect
			(at -0.48 0)
			(size 0.59 0.64)
			(layers "F.Cu" "F.Mask" "F.Paste")
			(roundrect_rratio 0.25)
			(net 964 "/DC-DC Converters/FB7")
			(pintype "passive")
		)
		(pad "2" smd roundrect
			(at 0.48 0)
			(size 0.59 0.64)
			(layers "F.Cu" "F.Mask" "F.Paste")
			(roundrect_rratio 0.25)
			(net 739 "/DC-DC Converters/5V_local")
			(pintype "passive")
		)
	)
	(footprint "antmicro-footprints:C_0402_1005Metric"
		(layer "F.Cu")
		(at 188.501 148.8 180)
		(descr "Capacitor SMD 0402")
		(tags "capacitor SMD 0402")
		(property "Reference" "C370"
			(at -0.949 0.5 0)
			(layer "F.SilkS")
			(effects
				(font
					(size 0.7 0.7)
					(thickness 0.15)
				)
				(justify right bottom)
			)
		)
		(property "Value" "C_100n_0402"
			(at 0 1.4 0)
			(layer "F.Fab")
			(effects
				(font
					(size 0.7 0.7)
					(thickness 0.15)
				)
				(justify right bottom)
			)
		)
		(property "Description" "SMD Multilayer Ceramic Capacitor, 0.1 µF, 50 V, 0402 [1005 Metric], ± 10%, X5R, GRM Series"
			(at 0 0 180)
			(layer "F.Fab")
			(hide yes)
			(effects
				(font
					(size 1.27 1.27)
					(thickness 0.15)
				)
			)
		)
		(property "Author" "Antmicro"
			(at 377.002 297.6 0)
			(layer "F.Fab")
			(hide yes)
			(effects
				(font
					(size 1 1)
					(thickness 0.15)
				)
			)
		)
		(property "Dielectric" "X5R"
			(at 377.002 297.6 0)
			(layer "F.Fab")
			(hide yes)
			(effects
				(font
					(size 1 1)
					(thickness 0.15)
				)
			)
		)
		(property "License" "Apache-2.0"
			(at 377.002 297.6 0)
			(layer "F.Fab")
			(hide yes)
			(effects
				(font
					(size 1 1)
					(thickness 0.15)
				)
			)
		)
		(property "MPN" "GRM155R61H104KE14D"
			(at 377.002 297.6 0)
			(layer "F.Fab")
			(hide yes)
			(effects
				(font
					(size 1 1)
					(thickness 0.15)
				)
			)
		)
		(property "Manufacturer" "Murata"
			(at 377.002 297.6 0)
			(layer "F.Fab")
			(hide yes)
			(effects
				(font
					(size 1 1)
					(thickness 0.15)
				)
			)
		)
		(property "Val" "100n"
			(at 377.002 297.6 0)
			(layer "F.Fab")
			(hide yes)
			(effects
				(font
					(size 1 1)
					(thickness 0.15)
				)
			)
		)
		(property "Voltage" "50V"
			(at 377.002 297.6 0)
			(layer "F.Fab")
			(hide yes)
			(effects
				(font
					(size 1 1)
					(thickness 0.15)
				)
			)
		)
		(sheetname "Clocks")
		(sheetfile "clocks.kicad_sch")
		(attr smd)
		(fp_rect
			(start -0.925 -0.47)
			(end 0.925 0.47)
			(stroke
				(width 0.05)
				(type default)
			)
			(fill no)
			(layer "F.CrtYd")
		)
		(fp_line
			(start 0.504 0.248)
			(end -0.494 0.248)
			(stroke
				(width 0.15)
				(type solid)
			)
			(layer "F.Fab")
		)
		(fp_line
			(start 0.504 -0.25)
			(end 0.504 0.248)
			(stroke
				(width 0.15)
				(type solid)
			)
			(layer "F.Fab")
		)
		(fp_line
			(start -0.494 0.248)
			(end -0.494 -0.25)
			(stroke
				(width 0.15)
				(type solid)
			)
			(layer "F.Fab")
		)
		(fp_line
			(start -0.494 -0.25)
			(end 0.504 -0.25)
			(stroke
				(width 0.15)
				(type solid)
			)
			(layer "F.Fab")
		)
		(pad "1" smd roundrect
			(at -0.48 0 180)
			(size 0.59 0.64)
			(layers "F.Cu" "F.Mask" "F.Paste")
			(roundrect_rratio 0.25)
			(net 1 "GND")
			(pintype "passive")
		)
		(pad "2" smd roundrect
			(at 0.48 0 180)
			(size 0.59 0.64)
			(layers "F.Cu" "F.Mask" "F.Paste")
			(roundrect_rratio 0.25)
			(net 26 "+1V8")
			(pintype "passive")
		)
	)
	(footprint "antmicro-footprints:R_0402_1005Metric"
		(layer "F.Cu")
		(at 242.15 106.1)
		(descr "Resistor SMD 0402")
		(tags "resistor SMD 0402")
		(property "Reference" "R256"
			(at -3.65 0.35 0)
			(layer "F.SilkS")
			(effects
				(font
					(size 0.7 0.7)
					(thickness 0.15)
				)
				(justify left bottom)
			)
		)
		(property "Value" "R_0R_0402"
			(at 0 1.4 0)
			(layer "F.Fab")
			(effects
				(font
					(size 0.7 0.7)
					(thickness 0.15)
				)
				(justify left bottom)
			)
		)
		(property "Description" "SMD Chip Resistor, Jumper, 0 ohm, 100 mW, 0402 [1005 Metric], Thick Film, General Purpose"
			(at 0 0 0)
			(layer "F.Fab")
			(hide yes)
			(effects
				(font
					(size 1.27 1.27)
					(thickness 0.15)
				)
			)
		)
		(property "Author" "Antmicro"
			(at 0 0 0)
			(layer "F.Fab")
			(hide yes)
			(effects
				(font
					(size 1 1)
					(thickness 0.15)
				)
			)
		)
		(property "Current" "1A"
			(at 0 0 0)
			(layer "F.Fab")
			(hide yes)
			(effects
				(font
					(size 1 1)
					(thickness 0.15)
				)
			)
		)
		(property "License" "Apache-2.0"
			(at 0 0 0)
			(layer "F.Fab")
			(hide yes)
			(effects
				(font
					(size 1 1)
					(thickness 0.15)
				)
			)
		)
		(property "MPN" "ERJ2GE0R00X"
			(at 0 0 0)
			(layer "F.Fab")
			(hide yes)
			(effects
				(font
					(size 1 1)
					(thickness 0.15)
				)
			)
		)
		(property "Manufacturer" "Panasonic"
			(at 0 0 0)
			(layer "F.Fab")
			(hide yes)
			(effects
				(font
					(size 1 1)
					(thickness 0.15)
				)
			)
		)
		(property "Tolerance" ""
			(at 0 0 0)
			(layer "F.Fab")
			(hide yes)
			(effects
				(font
					(size 1 1)
					(thickness 0.15)
				)
			)
		)
		(property "Val" "0R"
			(at 0 0 0)
			(layer "F.Fab")
			(hide yes)
			(effects
				(font
					(size 1 1)
					(thickness 0.15)
				)
			)
		)
		(sheetname "HDMI + Ethernet")
		(sheetfile "hdmi-ethernet.kicad_sch")
		(attr smd)
		(fp_rect
			(start -0.925 -0.47)
			(end 0.925 0.47)
			(stroke
				(width 0.05)
				(type default)
			)
			(fill no)
			(layer "F.CrtYd")
		)
		(fp_rect
			(start -0.5 -0.25)
			(end 0.5 0.25)
			(stroke
				(width 0.15)
				(type solid)
			)
			(fill no)
			(layer "F.Fab")
		)
		(pad "1" smd roundrect
			(at -0.48 0)
			(size 0.59 0.64)
			(layers "F.Cu" "F.Mask" "F.Paste")
			(roundrect_rratio 0.25)
			(net 526 "/FPGA Bank 16 & 17/HDMI.D1_P")
			(pintype "passive")
		)
		(pad "2" smd roundrect
			(at 0.48 0)
			(size 0.59 0.64)
			(layers "F.Cu" "F.Mask" "F.Paste")
			(roundrect_rratio 0.25)
			(net 865 "/HDMI + Ethernet/HDMI_CONN_D1_P")
			(pintype "passive")
		)
	)
	(footprint "antmicro-footprints:SC70-3"
		(layer "F.Cu")
		(at 258.4 79)
		(property "Reference" "Q15"
			(at -1.6 1.1 90)
			(layer "F.SilkS")
			(effects
				(font
					(size 0.7 0.7)
					(thickness 0.15)
				)
				(justify left bottom)
			)
		)
		(property "Value" "BSS138PW"
			(at 0 2.3 0)
			(layer "F.Fab")
			(effects
				(font
					(size 0.7 0.7)
					(thickness 0.15)
				)
				(justify left bottom)
			)
		)
		(property "Description" "Power MOSFET, N Channel, 60 V, 320 mA, 0.9 ohm, SOT-323, Surface Mount"
			(at 0 0 0)
			(layer "F.Fab")
			(hide yes)
			(effects
				(font
					(size 1.27 1.27)
					(thickness 0.15)
				)
			)
		)
		(property "Author" "Antmicro"
			(at 0 0 0)
			(layer "F.Fab")
			(hide yes)
			(effects
				(font
					(size 1 1)
					(thickness 0.15)
				)
			)
		)
		(property "License" "Apache-2.0"
			(at 0 0 0)
			(layer "F.Fab")
			(hide yes)
			(effects
				(font
					(size 1 1)
					(thickness 0.15)
				)
			)
		)
		(property "MPN" "BSS138PW"
			(at 0 0 0)
			(layer "F.Fab")
			(hide yes)
			(effects
				(font
					(size 1 1)
					(thickness 0.15)
				)
			)
		)
		(property "Manufacturer" "Nexperia"
			(at 0 0 0)
			(layer "F.Fab")
			(hide yes)
			(effects
				(font
					(size 1 1)
					(thickness 0.15)
				)
			)
		)
		(sheetname "User GPIO + LED + button + DIP switch")
		(sheetfile "user-gpio.kicad_sch")
		(attr smd)
		(fp_line
			(start -0.3 -1)
			(end 0.627 -0.999)
			(stroke
				(width 0.15)
				(type solid)
			)
			(layer "F.SilkS")
		)
		(fp_line
			(start -0.3 1)
			(end 0.627 1.001)
			(stroke
				(width 0.15)
				(type solid)
			)
			(layer "F.SilkS")
		)
		(fp_line
			(start 0.627 -0.6)
			(end 0.627 -0.999)
			(stroke
				(width 0.15)
				(type solid)
			)
			(layer "F.SilkS")
		)
		(fp_line
			(start 0.627 0.6)
			(end 0.627 1.001)
			(stroke
				(width 0.15)
				(type solid)
			)
			(layer "F.SilkS")
		)
		(fp_line
			(start -1.4 1)
			(end -1.4 -1)
			(stroke
				(width 0.05)
				(type solid)
			)
			(layer "F.CrtYd")
		)
		(fp_line
			(start -0.9 -1.3)
			(end -0.9 -1)
			(stroke
				(width 0.05)
				(type solid)
			)
			(layer "F.CrtYd")
		)
		(fp_line
			(start -0.9 -1.3)
			(end 0.9 -1.3)
			(stroke
				(width 0.05)
				(type solid)
			)
			(layer "F.CrtYd")
		)
		(fp_line
			(start -0.9 -1)
			(end -1.4 -1)
			(stroke
				(width 0.05)
				(type solid)
			)
			(layer "F.CrtYd")
		)
		(fp_line
			(start -0.9 1)
			(end -1.4 1)
			(stroke
				(width 0.05)
				(type solid)
			)
			(layer "F.CrtYd")
		)
		(fp_line
			(start -0.9 1.3)
			(end -0.9 1)
			(stroke
				(width 0.05)
				(type solid)
			)
			(layer "F.CrtYd")
		)
		(fp_line
			(start 0.9 -1.3)
			(end 0.9 -0.4)
			(stroke
				(width 0.05)
				(type solid)
			)
			(layer "F.CrtYd")
		)
		(fp_line
			(start 0.9 -0.4)
			(end 1.4 -0.4)
			(stroke
				(width 0.05)
				(type solid)
			)
			(layer "F.CrtYd")
		)
		(fp_line
			(start 0.9 0.4)
			(end 0.9 1.3)
			(stroke
				(width 0.05)
				(type solid)
			)
			(layer "F.CrtYd")
		)
		(fp_line
			(start 0.9 1.3)
			(end -0.9 1.3)
			(stroke
				(width 0.05)
				(type solid)
			)
			(layer "F.CrtYd")
		)
		(fp_line
			(start 1.4 -0.4)
			(end 1.4 0.4)
			(stroke
				(width 0.05)
				(type solid)
			)
			(layer "F.CrtYd")
		)
		(fp_line
			(start 1.4 0.4)
			(end 0.9 0.4)
			(stroke
				(width 0.05)
				(type solid)
			)
			(layer "F.CrtYd")
		)
		(fp_rect
			(start -0.623 -0.999)
			(end 0.627 1.001)
			(stroke
				(width 0.15)
				(type solid)
			)
			(fill no)
			(layer "F.Fab")
		)
		(pad "1" smd rect
			(at -1.051 -0.65 90)
			(size 0.6 0.6)
			(layers "F.Cu" "F.Mask" "F.Paste")
			(net 1305 "/USER_IO.LED_RED")
			(pinfunction "G")
			(pintype "passive")
		)
		(pad "2" smd rect
			(at -1.051 0.65 90)
			(size 0.6 0.6)
			(layers "F.Cu" "F.Mask" "F.Paste")
			(net 1 "GND")
			(pinfunction "S")
			(pintype "passive")
		)
		(pad "3" smd rect
			(at 1.05 0 90)
			(size 0.6 0.6)
			(layers "F.Cu" "F.Mask" "F.Paste")
			(net 770 "Net-(D24-C)")
			(pinfunction "D")
			(pintype "passive")
		)
	)
	(footprint "antmicro-footprints:R_0402_1005Metric"
		(layer "F.Cu")
		(at 156.2 146.65 90)
		(descr "Resistor SMD 0402")
		(tags "resistor SMD 0402")
		(property "Reference" "R328"
			(at 1.05 -0.5 90)
			(layer "F.SilkS")
			(effects
				(font
					(size 0.7 0.7)
					(thickness 0.15)
				)
				(justify left bottom)
			)
		)
		(property "Value" "R_0R_0402"
			(at 0 1.4 90)
			(layer "F.Fab")
			(effects
				(font
					(size 0.7 0.7)
					(thickness 0.15)
				)
				(justify left bottom)
			)
		)
		(property "Description" "SMD Chip Resistor, Jumper, 0 ohm, 100 mW, 0402 [1005 Metric], Thick Film, General Purpose"
			(at 0 0 90)
			(layer "F.Fab")
			(hide yes)
			(effects
				(font
					(size 1.27 1.27)
					(thickness 0.15)
				)
			)
		)
		(property "Author" "Antmicro"
			(at 302.85 -9.55 0)
			(layer "F.Fab")
			(hide yes)
			(effects
				(font
					(size 1 1)
					(thickness 0.15)
				)
			)
		)
		(property "Current" "1A"
			(at 302.85 -9.55 0)
			(layer "F.Fab")
			(hide yes)
			(effects
				(font
					(size 1 1)
					(thickness 0.15)
				)
			)
		)
		(property "License" "Apache-2.0"
			(at 302.85 -9.55 0)
			(layer "F.Fab")
			(hide yes)
			(effects
				(font
					(size 1 1)
					(thickness 0.15)
				)
			)
		)
		(property "MPN" "ERJ2GE0R00X"
			(at 302.85 -9.55 0)
			(layer "F.Fab")
			(hide yes)
			(effects
				(font
					(size 1 1)
					(thickness 0.15)
				)
			)
		)
		(property "Manufacturer" "Panasonic"
			(at 302.85 -9.55 0)
			(layer "F.Fab")
			(hide yes)
			(effects
				(font
					(size 1 1)
					(thickness 0.15)
				)
			)
		)
		(property "Tolerance" ""
			(at 302.85 -9.55 0)
			(layer "F.Fab")
			(hide yes)
			(effects
				(font
					(size 1 1)
					(thickness 0.15)
				)
			)
		)
		(property "Val" "0R"
			(at 302.85 -9.55 0)
			(layer "F.Fab")
			(hide yes)
			(effects
				(font
					(size 1 1)
					(thickness 0.15)
				)
			)
		)
		(sheetname "DC-DC Converters")
		(sheetfile "dc-dc.kicad_sch")
		(attr smd)
		(fp_rect
			(start -0.925 -0.47)
			(end 0.925 0.47)
			(stroke
				(width 0.05)
				(type default)
			)
			(fill no)
			(layer "F.CrtYd")
		)
		(fp_rect
			(start -0.5 -0.25)
			(end 0.5 0.25)
			(stroke
				(width 0.15)
				(type solid)
			)
			(fill no)
			(layer "F.Fab")
		)
		(pad "1" smd roundrect
			(at -0.48 0 90)
			(size 0.59 0.64)
			(layers "F.Cu" "F.Mask" "F.Paste")
			(roundrect_rratio 0.25)
			(net 622 "+1V85_ADC")
			(pintype "passive")
		)
		(pad "2" smd roundrect
			(at 0.48 0 90)
			(size 0.59 0.64)
			(layers "F.Cu" "F.Mask" "F.Paste")
			(roundrect_rratio 0.25)
			(net 747 "/DC-DC Converters/1V85_OUT")
			(pintype "passive")
		)
	)
	(footprint "antmicro-footprints:R_0603_1608Metric"
		(layer "F.Cu")
		(at 153.5 161.5 90)
		(descr "Resistor SMD 0603")
		(tags "resistor SMD 0603")
		(property "Reference" "R285"
			(at -1.45 -0.6 90)
			(layer "F.SilkS")
			(effects
				(font
					(size 0.7 0.7)
					(thickness 0.15)
				)
				(justify left bottom)
			)
		)
		(property "Value" "R_0R_22.4A_0603"
			(at 0 1.6 90)
			(layer "F.Fab")
			(effects
				(font
					(size 0.7 0.7)
					(thickness 0.15)
				)
				(justify left bottom)
			)
		)
		(property "Description" "SMD Chip Resistor"
			(at 0 0 90)
			(layer "F.Fab")
			(hide yes)
			(effects
				(font
					(size 1.27 1.27)
					(thickness 0.15)
				)
			)
		)
		(property "Author" "Antmicro"
			(at 315 8 0)
			(layer "F.Fab")
			(hide yes)
			(effects
				(font
					(size 1 1)
					(thickness 0.15)
				)
			)
		)
		(property "License" "Apache-2.0"
			(at 315 8 0)
			(layer "F.Fab")
			(hide yes)
			(effects
				(font
					(size 1 1)
					(thickness 0.15)
				)
			)
		)
		(property "MPN" "PMR03EZPJ000"
			(at 315 8 0)
			(layer "F.Fab")
			(hide yes)
			(effects
				(font
					(size 1 1)
					(thickness 0.15)
				)
			)
		)
		(property "Manufacturer" "ROHM Semiconductor"
			(at 315 8 0)
			(layer "F.Fab")
			(hide yes)
			(effects
				(font
					(size 1 1)
					(thickness 0.15)
				)
			)
		)
		(property "Max. Curr." "22.4A"
			(at 315 8 0)
			(layer "F.Fab")
			(hide yes)
			(effects
				(font
					(size 1 1)
					(thickness 0.15)
				)
			)
		)
		(property "Tolerance" "template_tolerance"
			(at 315 8 0)
			(layer "F.Fab")
			(hide yes)
			(effects
				(font
					(size 1 1)
					(thickness 0.15)
				)
			)
		)
		(property "Val" "0R"
			(at 315 8 0)
			(layer "F.Fab")
			(hide yes)
			(effects
				(font
					(size 1 1)
					(thickness 0.15)
				)
			)
		)
		(sheetname "DC-DC Converters")
		(sheetfile "dc-dc.kicad_sch")
		(attr smd)
		(fp_line
			(start -0.15 -0.4)
			(end 0.15 -0.4)
			(stroke
				(width 0.15)
				(type solid)
			)
			(layer "F.SilkS")
		)
		(fp_line
			(start -0.15 0.4)
			(end 0.15 0.4)
			(stroke
				(width 0.15)
				(type solid)
			)
			(layer "F.SilkS")
		)
		(fp_rect
			(start -1.25 -0.65)
			(end 1.25 0.65)
			(stroke
				(width 0.05)
				(type solid)
			)
			(fill no)
			(layer "F.CrtYd")
		)
		(fp_rect
			(start -0.8 -0.4)
			(end 0.8 0.4)
			(stroke
				(width 0.15)
				(type solid)
			)
			(fill no)
			(layer "F.Fab")
		)
		(pad "1" smd roundrect
			(at -0.7 0 90)
			(size 0.8 1)
			(layers "F.Cu" "F.Mask" "F.Paste")
			(roundrect_rratio 0.2)
			(net 733 "/DC-DC Converters/MGTAVCC_local")
			(pintype "passive")
		)
		(pad "2" smd roundrect
			(at 0.7 0 90)
			(size 0.8 1)
			(layers "F.Cu" "F.Mask" "F.Paste")
			(roundrect_rratio 0.2)
			(net 6 "+1V0_MGTAVCC")
			(pintype "passive")
		)
	)
	(footprint "antmicro-footprints:C_0402_1005Metric"
		(layer "F.Cu")
		(at 238.35 133.3)
		(descr "Capacitor SMD 0402")
		(tags "capacitor SMD 0402")
		(property "Reference" "C251"
			(at 2.6 -3.125 0)
			(layer "F.SilkS")
			(effects
				(font
					(size 0.7 0.7)
					(thickness 0.15)
				)
				(justify left bottom)
			)
		)
		(property "Value" "C_100n_0402"
			(at 0 1.169 0)
			(layer "F.Fab")
			(effects
				(font
					(size 0.7 0.7)
					(thickness 0.15)
				)
				(justify left bottom)
			)
		)
		(property "Description" "SMD Multilayer Ceramic Capacitor, 0.1 µF, 50 V, 0402 [1005 Metric], ± 10%, X5R, GRM Series"
			(at 0 0 0)
			(layer "F.Fab")
			(hide yes)
			(effects
				(font
					(size 1.27 1.27)
					(thickness 0.15)
				)
			)
		)
		(property "Author" "Antmicro"
			(at 0 0 0)
			(layer "F.Fab")
			(hide yes)
			(effects
				(font
					(size 1 1)
					(thickness 0.15)
				)
			)
		)
		(property "Dielectric" "X5R"
			(at 0 0 0)
			(layer "F.Fab")
			(hide yes)
			(effects
				(font
					(size 1 1)
					(thickness 0.15)
				)
			)
		)
		(property "License" "Apache-2.0"
			(at 0 0 0)
			(layer "F.Fab")
			(hide yes)
			(effects
				(font
					(size 1 1)
					(thickness 0.15)
				)
			)
		)
		(property "MPN" "GRM155R61H104KE14D"
			(at 0 0 0)
			(layer "F.Fab")
			(hide yes)
			(effects
				(font
					(size 1 1)
					(thickness 0.15)
				)
			)
		)
		(property "Manufacturer" "Murata"
			(at 0 0 0)
			(layer "F.Fab")
			(hide yes)
			(effects
				(font
					(size 1 1)
					(thickness 0.15)
				)
			)
		)
		(property "Val" "100n"
			(at 0 0 0)
			(layer "F.Fab")
			(hide yes)
			(effects
				(font
					(size 1 1)
					(thickness 0.15)
				)
			)
		)
		(property "Voltage" "50V"
			(at 0 0 0)
			(layer "F.Fab")
			(hide yes)
			(effects
				(font
					(size 1 1)
					(thickness 0.15)
				)
			)
		)
		(sheetname "USB PHY")
		(sheetfile "usb-phy.kicad_sch")
		(attr smd)
		(fp_rect
			(start -0.925 -0.47)
			(end 0.925 0.47)
			(stroke
				(width 0.05)
				(type default)
			)
			(fill no)
			(layer "F.CrtYd")
		)
		(fp_line
			(start -0.494 -0.25)
			(end 0.504 -0.25)
			(stroke
				(width 0.15)
				(type solid)
			)
			(layer "F.Fab")
		)
		(fp_line
			(start -0.494 0.248)
			(end -0.494 -0.25)
			(stroke
				(width 0.15)
				(type solid)
			)
			(layer "F.Fab")
		)
		(fp_line
			(start 0.504 -0.25)
			(end 0.504 0.248)
			(stroke
				(width 0.15)
				(type solid)
			)
			(layer "F.Fab")
		)
		(fp_line
			(start 0.504 0.248)
			(end -0.494 0.248)
			(stroke
				(width 0.15)
				(type solid)
			)
			(layer "F.Fab")
		)
		(pad "1" smd roundrect
			(at -0.48 0)
			(size 0.59 0.64)
			(layers "F.Cu" "F.Mask" "F.Paste")
			(roundrect_rratio 0.25)
			(net 1 "GND")
			(pintype "passive")
		)
		(pad "2" smd roundrect
			(at 0.48 0)
			(size 0.59 0.64)
			(layers "F.Cu" "F.Mask" "F.Paste")
			(roundrect_rratio 0.25)
			(net 24 "+3V3")
			(pintype "passive")
		)
	)
	(footprint "antmicro-footprints:R_0402_1005Metric"
		(layer "F.Cu")
		(at 211.9 165.4 90)
		(descr "Resistor SMD 0402")
		(tags "resistor SMD 0402")
		(property "Reference" "R80"
			(at -0.4 -5.25 90)
			(layer "F.SilkS")
			(effects
				(font
					(size 0.7 0.7)
					(thickness 0.15)
				)
				(justify left bottom)
			)
		)
		(property "Value" "R_0R_0402"
			(at 0 1.4 90)
			(layer "F.Fab")
			(effects
				(font
					(size 0.7 0.7)
					(thickness 0.15)
				)
				(justify left bottom)
			)
		)
		(property "Description" "SMD Chip Resistor, Jumper, 0 ohm, 100 mW, 0402 [1005 Metric], Thick Film, General Purpose"
			(at 0 0 90)
			(layer "F.Fab")
			(hide yes)
			(effects
				(font
					(size 1.27 1.27)
					(thickness 0.15)
				)
			)
		)
		(property "Author" "Antmicro"
			(at 377.3 -46.5 0)
			(layer "F.Fab")
			(hide yes)
			(effects
				(font
					(size 1 1)
					(thickness 0.15)
				)
			)
		)
		(property "Current" "1A"
			(at 377.3 -46.5 0)
			(layer "F.Fab")
			(hide yes)
			(effects
				(font
					(size 1 1)
					(thickness 0.15)
				)
			)
		)
		(property "License" "Apache-2.0"
			(at 377.3 -46.5 0)
			(layer "F.Fab")
			(hide yes)
			(effects
				(font
					(size 1 1)
					(thickness 0.15)
				)
			)
		)
		(property "MPN" "ERJ2GE0R00X"
			(at 377.3 -46.5 0)
			(layer "F.Fab")
			(hide yes)
			(effects
				(font
					(size 1 1)
					(thickness 0.15)
				)
			)
		)
		(property "Manufacturer" "Panasonic"
			(at 377.3 -46.5 0)
			(layer "F.Fab")
			(hide yes)
			(effects
				(font
					(size 1 1)
					(thickness 0.15)
				)
			)
		)
		(property "Tolerance" ""
			(at 377.3 -46.5 0)
			(layer "F.Fab")
			(hide yes)
			(effects
				(font
					(size 1 1)
					(thickness 0.15)
				)
			)
		)
		(property "Val" "0R"
			(at 377.3 -46.5 0)
			(layer "F.Fab")
			(hide yes)
			(effects
				(font
					(size 1 1)
					(thickness 0.15)
				)
			)
		)
		(sheetname "SPI Flash + SD Card")
		(sheetfile "spi-flash.kicad_sch")
		(attr smd)
		(fp_rect
			(start -0.925 -0.47)
			(end 0.925 0.47)
			(stroke
				(width 0.05)
				(type default)
			)
			(fill no)
			(layer "F.CrtYd")
		)
		(fp_rect
			(start -0.5 -0.25)
			(end 0.5 0.25)
			(stroke
				(width 0.15)
				(type solid)
			)
			(fill no)
			(layer "F.Fab")
		)
		(pad "1" smd roundrect
			(at -0.48 0 90)
			(size 0.59 0.64)
			(layers "F.Cu" "F.Mask" "F.Paste")
			(roundrect_rratio 0.25)
			(net 407 "/FPGA Bank 33 & 34/USR_FLASH_0.~{CS}")
			(pintype "passive")
		)
		(pad "2" smd roundrect
			(at 0.48 0 90)
			(size 0.59 0.64)
			(layers "F.Cu" "F.Mask" "F.Paste")
			(roundrect_rratio 0.25)
			(net 900 "/SPI Flash + SD Card/USR_FLASH_0_~{CS}")
			(pintype "passive")
		)
	)
	(footprint "antmicro-footprints:FB_0805_2012Metric"
		(layer "F.Cu")
		(at 241 179)
		(descr "FERRITE BEAD 0805")
		(tags "FERRITE BEAD 0805")
		(property "Reference" "FB3"
			(at -1 1.9 0)
			(layer "F.SilkS")
			(effects
				(font
					(size 0.7 0.7)
					(thickness 0.15)
				)
				(justify left bottom)
			)
		)
		(property "Value" "FB_220Z_2A_Murata-BLM21PG_0805"
			(at 0 1.8 0)
			(layer "F.Fab")
			(effects
				(font
					(size 0.7 0.7)
					(thickness 0.15)
				)
				(justify left bottom)
			)
		)
		(property "Description" "Ferrite Bead, 0805 [2012 Metric], 220 ohm, 2 A, BLM21, 0.045 ohm, ± 25%, DC power line"
			(at 0 0 0)
			(layer "F.Fab")
			(hide yes)
			(effects
				(font
					(size 1.27 1.27)
					(thickness 0.15)
				)
			)
		)
		(property "Author" "Antmicro"
			(at 0 0 0)
			(layer "F.Fab")
			(hide yes)
			(effects
				(font
					(size 1 1)
					(thickness 0.15)
				)
			)
		)
		(property "Current" ""
			(at 0 0 0)
			(layer "F.Fab")
			(hide yes)
			(effects
				(font
					(size 1 1)
					(thickness 0.15)
				)
			)
		)
		(property "DNP" "DNP"
			(at 0 0 0)
			(layer "F.Fab")
			(hide yes)
			(effects
				(font
					(size 1 1)
					(thickness 0.15)
				)
			)
		)
		(property "License" "Apache-2.0"
			(at 0 0 0)
			(layer "F.Fab")
			(hide yes)
			(effects
				(font
					(size 1 1)
					(thickness 0.15)
				)
			)
		)
		(property "MPN" "BLM21PG221SN1D"
			(at 0 0 0)
			(layer "F.Fab")
			(hide yes)
			(effects
				(font
					(size 1 1)
					(thickness 0.15)
				)
			)
		)
		(property "Manufacturer" "Murata"
			(at 0 0 0)
			(layer "F.Fab")
			(hide yes)
			(effects
				(font
					(size 1 1)
					(thickness 0.15)
				)
			)
		)
		(property "Val" "220Z/2A"
			(at 0 0 0)
			(layer "F.Fab")
			(hide yes)
			(effects
				(font
					(size 1 1)
					(thickness 0.15)
				)
			)
		)
		(property "dnp" ""
			(at 0 0 0)
			(layer "F.Fab")
			(hide yes)
			(effects
				(font
					(size 1 1)
					(thickness 0.15)
				)
			)
		)
		(property "exclude_from_bom" ""
			(at 0 0 0)
			(layer "F.Fab")
			(hide yes)
			(effects
				(font
					(size 1 1)
					(thickness 0.15)
				)
			)
		)
		(sheetname "Power supply")
		(sheetfile "power-supply.kicad_sch")
		(attr smd exclude_from_bom)
		(fp_line
			(start -0.319 0.698)
			(end 0.281 0.698)
			(stroke
				(width 0.15)
				(type solid)
			)
			(layer "F.SilkS")
		)
		(fp_line
			(start -0.299 -0.698)
			(end 0.299 -0.698)
			(stroke
				(width 0.15)
				(type solid)
			)
			(layer "F.SilkS")
		)
		(fp_rect
			(start 1.95 -0.9)
			(end -1.95 0.9)
			(stroke
				(width 0.05)
				(type default)
			)
			(fill no)
			(layer "F.CrtYd")
		)
		(fp_line
			(start -0.948 -0.681)
			(end 0.948 -0.681)
			(stroke
				(width 0.15)
				(type solid)
			)
			(layer "F.Fab")
		)
		(fp_line
			(start -0.948 -0.676)
			(end -0.948 0.676)
			(stroke
				(width 0.15)
				(type solid)
			)
			(layer "F.Fab")
		)
		(fp_line
			(start -0.948 0.681)
			(end 0.948 0.681)
			(stroke
				(width 0.15)
				(type solid)
			)
			(layer "F.Fab")
		)
		(fp_line
			(start 0.948 -0.676)
			(end 0.948 0.676)
			(stroke
				(width 0.15)
				(type solid)
			)
			(layer "F.Fab")
		)
		(pad "1" smd roundrect
			(at -1.1 0)
			(size 1.2 1.3)
			(layers "F.Cu" "F.Mask" "F.Paste")
			(roundrect_rratio 0.25)
			(net 763 "Net-(D6-Pad2)")
			(pintype "passive")
		)
		(pad "2" smd roundrect
			(at 1.1 0)
			(size 1.2 1.3)
			(layers "F.Cu" "F.Mask" "F.Paste")
			(roundrect_rratio 0.25)
			(net 698 "/Power supply/VDD")
			(pintype "passive")
		)
	)
	(footprint "antmicro-footprints:C_0402_1005Metric"
		(layer "F.Cu")
		(at 232.8 145.4 -90)
		(descr "Capacitor SMD 0402")
		(tags "capacitor SMD 0402")
		(property "Reference" "C243"
			(at -1.15 0.4 0)
			(layer "F.SilkS")
			(effects
				(font
					(size 0.7 0.7)
					(thickness 0.15)
				)
				(justify right bottom)
			)
		)
		(property "Value" "C_1u_0402"
			(at 0 1.4 90)
			(layer "F.Fab")
			(effects
				(font
					(size 0.7 0.7)
					(thickness 0.15)
				)
				(justify right bottom)
			)
		)
		(property "Description" "SMD Multilayer Ceramic Capacitor, 1 µF, 10 V, 0402 [1005 Metric], ± 10%, X6S, C"
			(at 0 0 270)
			(layer "F.Fab")
			(hide yes)
			(effects
				(font
					(size 1.27 1.27)
					(thickness 0.15)
				)
			)
		)
		(property "Author" "Antmicro"
			(at 87.4 378.2 0)
			(layer "F.Fab")
			(hide yes)
			(effects
				(font
					(size 1 1)
					(thickness 0.15)
				)
			)
		)
		(property "Dielectric" ""
			(at 87.4 378.2 0)
			(layer "F.Fab")
			(hide yes)
			(effects
				(font
					(size 1 1)
					(thickness 0.15)
				)
			)
		)
		(property "License" "Apache-2.0"
			(at 87.4 378.2 0)
			(layer "F.Fab")
			(hide yes)
			(effects
				(font
					(size 1 1)
					(thickness 0.15)
				)
			)
		)
		(property "MPN" "C1005X6S1A105K050BC"
			(at 87.4 378.2 0)
			(layer "F.Fab")
			(hide yes)
			(effects
				(font
					(size 1 1)
					(thickness 0.15)
				)
			)
		)
		(property "Manufacturer" "TDK"
			(at 87.4 378.2 0)
			(layer "F.Fab")
			(hide yes)
			(effects
				(font
					(size 1 1)
					(thickness 0.15)
				)
			)
		)
		(property "Val" "1u"
			(at 87.4 378.2 0)
			(layer "F.Fab")
			(hide yes)
			(effects
				(font
					(size 1 1)
					(thickness 0.15)
				)
			)
		)
		(property "Voltage" ""
			(at 87.4 378.2 0)
			(layer "F.Fab")
			(hide yes)
			(effects
				(font
					(size 1 1)
					(thickness 0.15)
				)
			)
		)
		(sheetname "USB PHY")
		(sheetfile "usb-phy.kicad_sch")
		(attr smd)
		(fp_rect
			(start -0.925 -0.47)
			(end 0.925 0.47)
			(stroke
				(width 0.05)
				(type default)
			)
			(fill no)
			(layer "F.CrtYd")
		)
		(fp_line
			(start -0.494 0.248)
			(end -0.494 -0.25)
			(stroke
				(width 0.15)
				(type solid)
			)
			(layer "F.Fab")
		)
		(fp_line
			(start 0.504 0.248)
			(end -0.494 0.248)
			(stroke
				(width 0.15)
				(type solid)
			)
			(layer "F.Fab")
		)
		(fp_line
			(start -0.494 -0.25)
			(end 0.504 -0.25)
			(stroke
				(width 0.15)
				(type solid)
			)
			(layer "F.Fab")
		)
		(fp_line
			(start 0.504 -0.25)
			(end 0.504 0.248)
			(stroke
				(width 0.15)
				(type solid)
			)
			(layer "F.Fab")
		)
		(pad "1" smd roundrect
			(at -0.48 0 270)
			(size 0.59 0.64)
			(layers "F.Cu" "F.Mask" "F.Paste")
			(roundrect_rratio 0.25)
			(net 1 "GND")
			(pintype "passive")
		)
		(pad "2" smd roundrect
			(at 0.48 0 270)
			(size 0.59 0.64)
			(layers "F.Cu" "F.Mask" "F.Paste")
			(roundrect_rratio 0.25)
			(net 24 "+3V3")
			(pintype "passive")
		)
	)
	(footprint "antmicro-footprints:R_0402_1005Metric"
		(layer "F.Cu")
		(at 243.099 113.904 180)
		(descr "Resistor SMD 0402")
		(tags "resistor SMD 0402")
		(property "Reference" "R347"
			(at 1.449 1.704 0)
			(layer "F.SilkS")
			(effects
				(font
					(size 0.7 0.7)
					(thickness 0.15)
				)
				(justify left bottom)
			)
		)
		(property "Value" "R_0R_0402"
			(at 0 1.4 180)
			(layer "F.Fab")
			(effects
				(font
					(size 0.7 0.7)
					(thickness 0.15)
				)
				(justify left bottom)
			)
		)
		(property "Description" "SMD Chip Resistor, Jumper, 0 ohm, 100 mW, 0402 [1005 Metric], Thick Film, General Purpose"
			(at 0 0 180)
			(layer "F.Fab")
			(hide yes)
			(effects
				(font
					(size 1.27 1.27)
					(thickness 0.15)
				)
			)
		)
		(property "Author" "Antmicro"
			(at 486.198 227.808 0)
			(layer "F.Fab")
			(hide yes)
			(effects
				(font
					(size 1 1)
					(thickness 0.15)
				)
			)
		)
		(property "Current" "1A"
			(at 486.198 227.808 0)
			(layer "F.Fab")
			(hide yes)
			(effects
				(font
					(size 1 1)
					(thickness 0.15)
				)
			)
		)
		(property "DNP" "DNP"
			(at 486.198 227.808 0)
			(layer "F.Fab")
			(hide yes)
			(effects
				(font
					(size 1 1)
					(thickness 0.15)
				)
			)
		)
		(property "License" "Apache-2.0"
			(at 486.198 227.808 0)
			(layer "F.Fab")
			(hide yes)
			(effects
				(font
					(size 1 1)
					(thickness 0.15)
				)
			)
		)
		(property "MPN" "ERJ2GE0R00X"
			(at 486.198 227.808 0)
			(layer "F.Fab")
			(hide yes)
			(effects
				(font
					(size 1 1)
					(thickness 0.15)
				)
			)
		)
		(property "Manufacturer" "Panasonic"
			(at 486.198 227.808 0)
			(layer "F.Fab")
			(hide yes)
			(effects
				(font
					(size 1 1)
					(thickness 0.15)
				)
			)
		)
		(property "Tolerance" ""
			(at 486.198 227.808 0)
			(layer "F.Fab")
			(hide yes)
			(effects
				(font
					(size 1 1)
					(thickness 0.15)
				)
			)
		)
		(property "Val" "0R"
			(at 486.198 227.808 0)
			(layer "F.Fab")
			(hide yes)
			(effects
				(font
					(size 1 1)
					(thickness 0.15)
				)
			)
		)
		(property "dnp" ""
			(at 486.198 227.808 0)
			(layer "F.Fab")
			(hide yes)
			(effects
				(font
					(size 1 1)
					(thickness 0.15)
				)
			)
		)
		(property "exclude_from_bom" ""
			(at 486.198 227.808 0)
			(layer "F.Fab")
			(hide yes)
			(effects
				(font
					(size 1 1)
					(thickness 0.15)
				)
			)
		)
		(sheetname "USB PHY")
		(sheetfile "usb-phy.kicad_sch")
		(attr smd exclude_from_bom)
		(fp_rect
			(start -0.925 -0.47)
			(end 0.925 0.47)
			(stroke
				(width 0.05)
				(type default)
			)
			(fill no)
			(layer "F.CrtYd")
		)
		(fp_rect
			(start -0.5 -0.25)
			(end 0.5 0.25)
			(stroke
				(width 0.15)
				(type solid)
			)
			(fill no)
			(layer "F.Fab")
		)
		(pad "1" smd roundrect
			(at -0.48 0 180)
			(size 0.59 0.64)
			(layers "F.Cu" "F.Mask" "F.Paste")
			(roundrect_rratio 0.25)
			(net 703 "+5V")
			(pintype "passive")
		)
		(pad "2" smd roundrect
			(at 0.48 0 180)
			(size 0.59 0.64)
			(layers "F.Cu" "F.Mask" "F.Paste")
			(roundrect_rratio 0.25)
			(net 385 "Net-(U43-EN)")
			(pintype "passive")
		)
	)
	(footprint "antmicro-footprints:R_0402_1005Metric"
		(layer "F.Cu")
		(at 225.025 120.5)
		(descr "Resistor SMD 0402")
		(tags "resistor SMD 0402")
		(property "Reference" "R66"
			(at -2.975 0.4 0)
			(layer "F.SilkS")
			(effects
				(font
					(size 0.7 0.7)
					(thickness 0.15)
				)
				(justify left bottom)
			)
		)
		(property "Value" "R_10k_0402"
			(at 0 1.4 0)
			(layer "F.Fab")
			(effects
				(font
					(size 0.7 0.7)
					(thickness 0.15)
				)
				(justify left bottom)
			)
		)
		(property "Description" "SMD Chip Resistor, 10 kohm, ± 1%, 62.5 mW, 0402 [1005 Metric], Thick Film, General Purpose"
			(at 0 0 0)
			(layer "F.Fab")
			(hide yes)
			(effects
				(font
					(size 1.27 1.27)
					(thickness 0.15)
				)
			)
		)
		(property "Author" "Antmicro"
			(at 0 0 0)
			(layer "F.Fab")
			(hide yes)
			(effects
				(font
					(size 1 1)
					(thickness 0.15)
				)
			)
		)
		(property "License" "Apache-2.0"
			(at 0 0 0)
			(layer "F.Fab")
			(hide yes)
			(effects
				(font
					(size 1 1)
					(thickness 0.15)
				)
			)
		)
		(property "MPN" "CR0402-FX-1002GLF"
			(at 0 0 0)
			(layer "F.Fab")
			(hide yes)
			(effects
				(font
					(size 1 1)
					(thickness 0.15)
				)
			)
		)
		(property "Manufacturer" "Bourns"
			(at 0 0 0)
			(layer "F.Fab")
			(hide yes)
			(effects
				(font
					(size 1 1)
					(thickness 0.15)
				)
			)
		)
		(property "Tolerance" "1%"
			(at 0 0 0)
			(layer "F.Fab")
			(hide yes)
			(effects
				(font
					(size 1 1)
					(thickness 0.15)
				)
			)
		)
		(property "Val" "10k"
			(at 0 0 0)
			(layer "F.Fab")
			(hide yes)
			(effects
				(font
					(size 1 1)
					(thickness 0.15)
				)
			)
		)
		(sheetname "SPI Flash + SD Card")
		(sheetfile "spi-flash.kicad_sch")
		(attr smd)
		(fp_rect
			(start -0.925 -0.47)
			(end 0.925 0.47)
			(stroke
				(width 0.05)
				(type default)
			)
			(fill no)
			(layer "F.CrtYd")
		)
		(fp_rect
			(start -0.5 -0.25)
			(end 0.5 0.25)
			(stroke
				(width 0.15)
				(type solid)
			)
			(fill no)
			(layer "F.Fab")
		)
		(pad "1" smd roundrect
			(at -0.48 0)
			(size 0.59 0.64)
			(layers "F.Cu" "F.Mask" "F.Paste")
			(roundrect_rratio 0.25)
			(net 403 "/FPGA Bank 14 & 15/SYSTEM_FLASH.DQ2")
			(pintype "passive")
		)
		(pad "2" smd roundrect
			(at 0.48 0)
			(size 0.59 0.64)
			(layers "F.Cu" "F.Mask" "F.Paste")
			(roundrect_rratio 0.25)
			(net 24 "+3V3")
			(pintype "passive")
		)
	)
	(footprint "antmicro-footprints:SW_KMR211NGLFS_SMD"
		(layer "F.Cu")
		(at 266.8 93.2 180)
		(property "Reference" "S5"
			(at 0.7 -2.6 180)
			(layer "F.SilkS")
			(effects
				(font
					(size 0.7 0.7)
					(thickness 0.15)
				)
				(justify left bottom)
			)
		)
		(property "Value" "SW_KMR211NGLFS_SMD"
			(at -3 3 180)
			(layer "F.Fab")
			(effects
				(font
					(size 0.7 0.7)
					(thickness 0.15)
				)
				(justify left bottom)
			)
		)
		(property "Description" "Tactile Switch, KMR 2 Series, Top Actuated, Surface Mount, Oval Button, 120 gf, 50mA at 32VDC"
			(at 0 0 180)
			(layer "F.Fab")
			(hide yes)
			(effects
				(font
					(size 1.27 1.27)
					(thickness 0.15)
				)
			)
		)
		(property "Author" "Antmicro"
			(at 533.6 186.4 0)
			(layer "F.Fab")
			(hide yes)
			(effects
				(font
					(size 1 1)
					(thickness 0.15)
				)
			)
		)
		(property "License" "Apache-2.0"
			(at 533.6 186.4 0)
			(layer "F.Fab")
			(hide yes)
			(effects
				(font
					(size 1 1)
					(thickness 0.15)
				)
			)
		)
		(property "MPN" "KMR211NGLFS"
			(at 533.6 186.4 0)
			(layer "F.Fab")
			(hide yes)
			(effects
				(font
					(size 1 1)
					(thickness 0.15)
				)
			)
		)
		(property "Manufacturer" "C&K"
			(at 533.6 186.4 0)
			(layer "F.Fab")
			(hide yes)
			(effects
				(font
					(size 1 1)
					(thickness 0.15)
				)
			)
		)
		(sheetname "User GPIO + LED + button + DIP switch")
		(sheetfile "user-gpio.kicad_sch")
		(attr smd)
		(fp_line
			(start 2.101 1.601)
			(end 2.101 1.48)
			(stroke
				(width 0.15)
				(type solid)
			)
			(layer "F.SilkS")
		)
		(fp_line
			(start 2.101 1.601)
			(end -2.1 1.601)
			(stroke
				(width 0.15)
				(type solid)
			)
			(layer "F.SilkS")
		)
		(fp_line
			(start 2.101 -1.58)
			(end 2.101 -1.459)
			(stroke
				(width 0.15)
				(type solid)
			)
			(layer "F.SilkS")
		)
		(fp_line
			(start 2.101 -1.6)
			(end -2.1 -1.6)
			(stroke
				(width 0.15)
				(type solid)
			)
			(layer "F.SilkS")
		)
		(fp_line
			(start -2.1 1.601)
			(end -2.1 1.48)
			(stroke
				(width 0.15)
				(type solid)
			)
			(layer "F.SilkS")
		)
		(fp_line
			(start -2.1 -1.6)
			(end -2.1 -1.499)
			(stroke
				(width 0.15)
				(type solid)
			)
			(layer "F.SilkS")
		)
		(fp_rect
			(start 2.751 1.75)
			(end -2.748 -1.749)
			(stroke
				(width 0.05)
				(type solid)
			)
			(fill no)
			(layer "F.CrtYd")
		)
		(fp_line
			(start 2.101 1.601)
			(end 2.101 -1.6)
			(stroke
				(width 0.15)
				(type solid)
			)
			(layer "F.Fab")
		)
		(fp_line
			(start 2.101 -1.6)
			(end -2.1 -1.6)
			(stroke
				(width 0.15)
				(type solid)
			)
			(layer "F.Fab")
		)
		(fp_line
			(start 0.25 0.802)
			(end -0.248 0.802)
			(stroke
				(width 0.15)
				(type solid)
			)
			(layer "F.Fab")
		)
		(fp_line
			(start -0.248 -0.8)
			(end 0.25 -0.8)
			(stroke
				(width 0.15)
				(type solid)
			)
			(layer "F.Fab")
		)
		(fp_line
			(start -2.1 1.601)
			(end 2.101 1.601)
			(stroke
				(width 0.15)
				(type solid)
			)
			(layer "F.Fab")
		)
		(fp_line
			(start -2.1 -1.6)
			(end -2.1 1.601)
			(stroke
				(width 0.15)
				(type solid)
			)
			(layer "F.Fab")
		)
		(fp_arc
			(start 0.25 -0.8)
			(mid 1.051001 0.001)
			(end 0.25 0.802)
			(stroke
				(width 0.15)
				(type solid)
			)
			(layer "F.Fab")
		)
		(fp_arc
			(start -0.248 0.802)
			(mid -1.050001 0.001)
			(end -0.248 -0.8)
			(stroke
				(width 0.15)
				(type solid)
			)
			(layer "F.Fab")
		)
		(pad "1" smd rect
			(at -2.048 -0.8)
			(size 0.9 1)
			(layers "F.Cu" "F.Mask" "F.Paste")
			(net 1232 "/USER_IO.BUTTON3")
			(pinfunction "1")
			(pintype "passive")
		)
		(pad "2" smd rect
			(at 2.05 -0.8)
			(size 0.9 1)
			(layers "F.Cu" "F.Mask" "F.Paste")
			(net 1232 "/USER_IO.BUTTON3")
			(pinfunction "2")
			(pintype "passive")
		)
		(pad "3" smd rect
			(at -2.048 0.802)
			(size 0.9 1)
			(layers "F.Cu" "F.Mask" "F.Paste")
			(net 1 "GND")
			(pinfunction "3")
			(pintype "passive")
		)
		(pad "4" smd rect
			(at 2.05 0.802)
			(size 0.9 1)
			(layers "F.Cu" "F.Mask" "F.Paste")
			(net 1 "GND")
			(pinfunction "4")
			(pintype "passive")
		)
	)
	(footprint "antmicro-footprints:NetTie-2_SMD_Pad0.127mm"
		(layer "F.Cu")
		(at 252.1 143.502 -90)
		(descr "Net tie, 2 pin, 0.127mm  SMD pads")
		(tags "net tie")
		(property "Reference" "NT14"
			(at -0.128 -1.345 270)
			(layer "F.SilkS")
			(hide yes)
			(effects
				(font
					(size 0.7 0.7)
					(thickness 0.15)
				)
				(justify left bottom)
			)
		)
		(property "Value" "Net-Tie_2"
			(at 0 1.199 270)
			(layer "F.Fab")
			(effects
				(font
					(size 0.7 0.7)
					(thickness 0.15)
				)
				(justify left bottom)
			)
		)
		(property "Description" "Net tie, 2 pins"
			(at 0 0 270)
			(layer "F.Fab")
			(hide yes)
			(effects
				(font
					(size 1.27 1.27)
					(thickness 0.15)
				)
			)
		)
		(property "Author" "Antmicro"
			(at 108.598 395.602 0)
			(layer "F.Fab")
			(hide yes)
			(effects
				(font
					(size 1 1)
					(thickness 0.15)
				)
			)
		)
		(property "License" "Apache-2.0"
			(at 108.598 395.602 0)
			(layer "F.Fab")
			(hide yes)
			(effects
				(font
					(size 1 1)
					(thickness 0.15)
				)
			)
		)
		(property "MPN" ""
			(at 108.598 395.602 0)
			(layer "F.Fab")
			(hide yes)
			(effects
				(font
					(size 1 1)
					(thickness 0.15)
				)
			)
		)
		(property "Manufacturer" ""
			(at 108.598 395.602 0)
			(layer "F.Fab")
			(hide yes)
			(effects
				(font
					(size 1 1)
					(thickness 0.15)
				)
			)
		)
		(sheetname "FPGA Bank 14 & 15")
		(sheetfile "fpga-bank-14-15.kicad_sch")
		(attr exclude_from_pos_files)
		(net_tie_pad_groups "1, 2")
		(fp_poly
			(pts
				(xy -0.0635 -0.0635) (xy 0.0625 -0.0635) (xy 0.0625 0.0635) (xy -0.0635 0.0635)
			)
			(stroke
				(width 0)
				(type solid)
			)
			(fill yes)
			(layer "F.Cu")
		)
		(pad "1" smd roundrect
			(at -0.127 0 90)
			(size 0.127 0.127)
			(layers "F.Cu")
			(roundrect_rratio 0.5)
			(chamfer_ratio 0)
			(chamfer top_left bottom_left)
			(net 43 "/FPGA Bank 14 & 15/SYSTEM_FLASH.DQ1")
			(pinfunction "1")
			(pintype "passive")
		)
		(pad "2" smd roundrect
			(at 0.126 0 270)
			(size 0.127 0.127)
			(layers "F.Cu")
			(roundrect_rratio 0.5)
			(chamfer_ratio 0)
			(chamfer top_left bottom_left)
			(net 1327 "/SUP_MCU.FPGA_MOSI")
			(pinfunction "2")
			(pintype "passive")
		)
	)
	(footprint "antmicro-footprints:WDFN-8-1EP_6x5mm_P1.27mm_EP3.4x4mm"
		(layer "F.Cu")
		(at 212.89 160.06 90)
		(property "Reference" "U13"
			(at -3.7 -3.2 90)
			(layer "F.SilkS")
			(effects
				(font
					(size 0.7 0.7)
					(thickness 0.15)
				)
				(justify left bottom)
			)
		)
		(property "Value" "MT25QL256ABA1EW7-0SIT"
			(at -10.1 4 90)
			(layer "F.Fab")
			(effects
				(font
					(size 0.7 0.7)
					(thickness 0.15)
				)
				(justify left bottom)
			)
		)
		(property "Description" "Flash Memory, Serial NOR, 256 Mbit, 32M x 8bit, SPI, MLP, 8 Pins"
			(at 0 0 90)
			(layer "F.Fab")
			(hide yes)
			(effects
				(font
					(size 1.27 1.27)
					(thickness 0.15)
				)
			)
		)
		(property "Author" "Antmicro"
			(at 372.95 -52.83 0)
			(layer "F.Fab")
			(hide yes)
			(effects
				(font
					(size 1 1)
					(thickness 0.15)
				)
			)
		)
		(property "DNP" "DNP"
			(at 372.95 -52.83 0)
			(layer "F.Fab")
			(hide yes)
			(effects
				(font
					(size 1 1)
					(thickness 0.15)
				)
			)
		)
		(property "License" "Apache-2.0"
			(at 372.95 -52.83 0)
			(layer "F.Fab")
			(hide yes)
			(effects
				(font
					(size 1 1)
					(thickness 0.15)
				)
			)
		)
		(property "MPN" "MT25QL256ABA1EW7-0SIT"
			(at 372.95 -52.83 0)
			(layer "F.Fab")
			(hide yes)
			(effects
				(font
					(size 1 1)
					(thickness 0.15)
				)
			)
		)
		(property "Manufacturer" "Micron Technology"
			(at 372.95 -52.83 0)
			(layer "F.Fab")
			(hide yes)
			(effects
				(font
					(size 1 1)
					(thickness 0.15)
				)
			)
		)
		(property "dnp" ""
			(at 372.95 -52.83 0)
			(layer "F.Fab")
			(hide yes)
			(effects
				(font
					(size 1 1)
					(thickness 0.15)
				)
			)
		)
		(property "exclude_from_bom" ""
			(at 372.95 -52.83 0)
			(layer "F.Fab")
			(hide yes)
			(effects
				(font
					(size 1 1)
					(thickness 0.15)
				)
			)
		)
		(sheetname "SPI Flash + SD Card")
		(sheetfile "spi-flash.kicad_sch")
		(attr smd exclude_from_bom)
		(fp_line
			(start -2.301 -2.601)
			(end 3.7 -2.601)
			(stroke
				(width 0.15)
				(type solid)
			)
			(layer "F.SilkS")
		)
		(fp_line
			(start -3.801 2.6)
			(end 3.7 2.6)
			(stroke
				(width 0.15)
				(type solid)
			)
			(layer "F.SilkS")
		)
		(fp_circle
			(center -3.3 -2.8)
			(end -3.25 -2.8)
			(stroke
				(width 0.15)
				(type solid)
			)
			(fill yes)
			(layer "F.SilkS")
		)
		(fp_rect
			(start -3.5 -3)
			(end 3.499 2.999)
			(stroke
				(width 0.05)
				(type solid)
			)
			(fill no)
			(layer "F.CrtYd")
		)
		(fp_line
			(start 2.999 -2.5)
			(end -2 -2.5)
			(stroke
				(width 0.15)
				(type solid)
			)
			(layer "F.Fab")
		)
		(fp_line
			(start -2 -2.5)
			(end -3 -1.5)
			(stroke
				(width 0.15)
				(type solid)
			)
			(layer "F.Fab")
		)
		(fp_line
			(start -3 -1.5)
			(end -3 2.499)
			(stroke
				(width 0.15)
				(type solid)
			)
			(layer "F.Fab")
		)
		(fp_line
			(start 2.999 2.499)
			(end 2.999 -2.5)
			(stroke
				(width 0.15)
				(type solid)
			)
			(layer "F.Fab")
		)
		(fp_line
			(start -3 2.499)
			(end 2.999 2.499)
			(stroke
				(width 0.15)
				(type solid)
			)
			(layer "F.Fab")
		)
		(pad "" smd roundrect
			(at -0.802 -1 90)
			(size 1.37 1.61)
			(layers "F.Paste")
			(roundrect_rratio 0.182482)
		)
		(pad "" smd roundrect
			(at -0.802 0.998 90)
			(size 1.37 1.61)
			(layers "F.Paste")
			(roundrect_rratio 0.182482)
		)
		(pad "" smd roundrect
			(at 0.8 -1 90)
			(size 1.37 1.61)
			(layers "F.Paste")
			(roundrect_rratio 0.182482)
		)
		(pad "" smd roundrect
			(at 0.8 0.998 90)
			(size 1.37 1.61)
			(layers "F.Paste")
			(roundrect_rratio 0.182482)
		)
		(pad "1" smd rect
			(at -3 -1.905 180)
			(size 0.5 1.5)
			(layers "F.Cu" "F.Mask" "F.Paste")
			(net 900 "/SPI Flash + SD Card/USR_FLASH_0_~{CS}")
			(pinfunction "~{CS}")
			(pintype "passive")
		)
		(pad "2" smd roundrect
			(at -3 -0.635 180)
			(size 0.5 1.5)
			(layers "F.Cu" "F.Mask" "F.Paste")
			(roundrect_rratio 0.25)
			(net 903 "/SPI Flash + SD Card/USR_FLASH_0_DQ1")
			(pinfunction "DQ1")
			(pintype "passive")
		)
		(pad "3" smd roundrect
			(at -3 0.633 180)
			(size 0.5 1.5)
			(layers "F.Cu" "F.Mask" "F.Paste")
			(roundrect_rratio 0.25)
			(net 904 "/SPI Flash + SD Card/USR_FLASH_0_DQ2")
			(pinfunction "DQ2/~{W}")
			(pintype "passive")
		)
		(pad "4" smd roundrect
			(at -3 1.904 180)
			(size 0.5 1.5)
			(layers "F.Cu" "F.Mask" "F.Paste")
			(roundrect_rratio 0.25)
			(net 1 "GND")
			(pinfunction "GND")
			(pintype "passive")
		)
		(pad "5" smd roundrect
			(at 2.999 1.904 180)
			(size 0.5 1.5)
			(layers "F.Cu" "F.Mask" "F.Paste")
			(roundrect_rratio 0.25)
			(net 902 "/SPI Flash + SD Card/USR_FLASH_0_DQ0")
			(pinfunction "DQ0")
			(pintype "passive")
		)
		(pad "6" smd roundrect
			(at 2.999 0.633 180)
			(size 0.5 1.5)
			(layers "F.Cu" "F.Mask" "F.Paste")
			(roundrect_rratio 0.25)
			(net 901 "/SPI Flash + SD Card/USR_FLASH_0_CLK")
			(pinfunction "CLK")
			(pintype "passive")
		)
		(pad "7" smd roundrect
			(at 2.999 -0.635 180)
			(size 0.5 1.5)
			(layers "F.Cu" "F.Mask" "F.Paste")
			(roundrect_rratio 0.25)
			(net 905 "/SPI Flash + SD Card/USR_FLASH_0_DQ3")
			(pinfunction "DQ3/~{HOLD}")
			(pintype "passive")
		)
		(pad "8" smd roundrect
			(at 2.999 -1.905 180)
			(size 0.5 1.5)
			(layers "F.Cu" "F.Mask" "F.Paste")
			(roundrect_rratio 0.25)
			(net 26 "+1V8")
			(pinfunction "VCC")
			(pintype "passive")
		)
		(pad "9" smd rect
			(at 0 0 90)
			(size 3.4 4)
			(layers "F.Cu" "F.Mask")
			(net 1 "GND")
			(pinfunction "EP")
			(pintype "passive")
			(solder_paste_margin -0.1)
		)
	)
	(footprint "antmicro-footprints:C_0402_1005Metric"
		(layer "F.Cu")
		(at 241.999 118.904)
		(descr "Capacitor SMD 0402")
		(tags "capacitor SMD 0402")
		(property "Reference" "C395"
			(at -1.899 1.246 0)
			(layer "F.SilkS")
			(effects
				(font
					(size 0.7 0.7)
					(thickness 0.15)
				)
				(justify left bottom)
			)
		)
		(property "Value" "C_100n_0402"
			(at 0 1.169 0)
			(layer "F.Fab")
			(effects
				(font
					(size 0.7 0.7)
					(thickness 0.15)
				)
				(justify left bottom)
			)
		)
		(property "Description" "SMD Multilayer Ceramic Capacitor, 0.1 µF, 50 V, 0402 [1005 Metric], ± 10%, X5R, GRM Series"
			(at 0 0 0)
			(layer "F.Fab")
			(hide yes)
			(effects
				(font
					(size 1.27 1.27)
					(thickness 0.15)
				)
			)
		)
		(property "Author" "Antmicro"
			(at 0 0 0)
			(layer "F.Fab")
			(hide yes)
			(effects
				(font
					(size 1 1)
					(thickness 0.15)
				)
			)
		)
		(property "Dielectric" "X5R"
			(at 0 0 0)
			(layer "F.Fab")
			(hide yes)
			(effects
				(font
					(size 1 1)
					(thickness 0.15)
				)
			)
		)
		(property "License" "Apache-2.0"
			(at 0 0 0)
			(layer "F.Fab")
			(hide yes)
			(effects
				(font
					(size 1 1)
					(thickness 0.15)
				)
			)
		)
		(property "MPN" "GRM155R61H104KE14D"
			(at 0 0 0)
			(layer "F.Fab")
			(hide yes)
			(effects
				(font
					(size 1 1)
					(thickness 0.15)
				)
			)
		)
		(property "Manufacturer" "Murata"
			(at 0 0 0)
			(layer "F.Fab")
			(hide yes)
			(effects
				(font
					(size 1 1)
					(thickness 0.15)
				)
			)
		)
		(property "Val" "100n"
			(at 0 0 0)
			(layer "F.Fab")
			(hide yes)
			(effects
				(font
					(size 1 1)
					(thickness 0.15)
				)
			)
		)
		(property "Voltage" "50V"
			(at 0 0 0)
			(layer "F.Fab")
			(hide yes)
			(effects
				(font
					(size 1 1)
					(thickness 0.15)
				)
			)
		)
		(sheetname "USB PHY")
		(sheetfile "usb-phy.kicad_sch")
		(attr smd)
		(fp_rect
			(start -0.925 -0.47)
			(end 0.925 0.47)
			(stroke
				(width 0.05)
				(type default)
			)
			(fill no)
			(layer "F.CrtYd")
		)
		(fp_line
			(start -0.494 -0.25)
			(end 0.504 -0.25)
			(stroke
				(width 0.15)
				(type solid)
			)
			(layer "F.Fab")
		)
		(fp_line
			(start -0.494 0.248)
			(end -0.494 -0.25)
			(stroke
				(width 0.15)
				(type solid)
			)
			(layer "F.Fab")
		)
		(fp_line
			(start 0.504 -0.25)
			(end 0.504 0.248)
			(stroke
				(width 0.15)
				(type solid)
			)
			(layer "F.Fab")
		)
		(fp_line
			(start 0.504 0.248)
			(end -0.494 0.248)
			(stroke
				(width 0.15)
				(type solid)
			)
			(layer "F.Fab")
		)
		(pad "1" smd roundrect
			(at -0.48 0)
			(size 0.59 0.64)
			(layers "F.Cu" "F.Mask" "F.Paste")
			(roundrect_rratio 0.25)
			(net 1 "GND")
			(pintype "passive")
		)
		(pad "2" smd roundrect
			(at 0.48 0)
			(size 0.59 0.64)
			(layers "F.Cu" "F.Mask" "F.Paste")
			(roundrect_rratio 0.25)
			(net 703 "+5V")
			(pintype "passive")
		)
	)
	(footprint "antmicro-footprints:C_0805_2012Metric"
		(layer "F.Cu")
		(at 176.05 178.1125)
		(descr "Capacitor SMD 0805")
		(tags "capacitor SMD 0805")
		(property "Reference" "C317"
			(at -1.3 2.8375 0)
			(layer "F.SilkS")
			(effects
				(font
					(size 0.7 0.7)
					(thickness 0.15)
				)
				(justify left bottom)
			)
		)
		(property "Value" "C_22u_25V_0805"
			(at 0 1.947 0)
			(layer "F.Fab")
			(effects
				(font
					(size 0.7 0.7)
					(thickness 0.15)
				)
				(justify left bottom)
			)
		)
		(property "Description" "SMT Multilayer Ceramic Capacitor, 22uF, +/-20%, 25V, X5R, 0805 [2012 Metric]"
			(at 0 0 0)
			(layer "F.Fab")
			(hide yes)
			(effects
				(font
					(size 1.27 1.27)
					(thickness 0.15)
				)
			)
		)
		(property "Author" "Antmicro"
			(at 0 0 0)
			(layer "F.Fab")
			(hide yes)
			(effects
				(font
					(size 1 1)
					(thickness 0.15)
				)
			)
		)
		(property "Dielectric" "X5R"
			(at 0 0 0)
			(layer "F.Fab")
			(hide yes)
			(effects
				(font
					(size 1 1)
					(thickness 0.15)
				)
			)
		)
		(property "License" "Apache-2.0"
			(at 0 0 0)
			(layer "F.Fab")
			(hide yes)
			(effects
				(font
					(size 1 1)
					(thickness 0.15)
				)
			)
		)
		(property "MPN" "CL21A226MAYNNNE"
			(at 0 0 0)
			(layer "F.Fab")
			(hide yes)
			(effects
				(font
					(size 1 1)
					(thickness 0.15)
				)
			)
		)
		(property "Manufacturer" "Samsung Electro-Mechanics"
			(at 0 0 0)
			(layer "F.Fab")
			(hide yes)
			(effects
				(font
					(size 1 1)
					(thickness 0.15)
				)
			)
		)
		(property "Val" "22u"
			(at 0 0 0)
			(layer "F.Fab")
			(hide yes)
			(effects
				(font
					(size 1 1)
					(thickness 0.15)
				)
			)
		)
		(property "Voltage" "25V"
			(at 0 0 0)
			(layer "F.Fab")
			(hide yes)
			(effects
				(font
					(size 1 1)
					(thickness 0.15)
				)
			)
		)
		(sheetname "DC-DC Converters")
		(sheetfile "dc-dc.kicad_sch")
		(attr smd)
		(fp_line
			(start -0.3 -0.7)
			(end 0.3 -0.7)
			(stroke
				(width 0.15)
				(type solid)
			)
			(layer "F.SilkS")
		)
		(fp_line
			(start -0.3 0.7)
			(end 0.3 0.7)
			(stroke
				(width 0.15)
				(type solid)
			)
			(layer "F.SilkS")
		)
		(fp_rect
			(start 1.95 -0.9)
			(end -1.95 0.9)
			(stroke
				(width 0.05)
				(type default)
			)
			(fill no)
			(layer "F.CrtYd")
		)
		(fp_rect
			(start -0.95 -0.675)
			(end 0.95 0.675)
			(stroke
				(width 0.15)
				(type solid)
			)
			(fill no)
			(layer "F.Fab")
		)
		(pad "1" smd roundrect
			(at -1.1 0)
			(size 1.2 1.3)
			(layers "F.Cu" "F.Mask" "F.Paste")
			(roundrect_rratio 0.25)
			(net 1 "GND")
			(pintype "passive")
		)
		(pad "2" smd roundrect
			(at 1.1 0)
			(size 1.2 1.3)
			(layers "F.Cu" "F.Mask" "F.Paste")
			(roundrect_rratio 0.25)
			(net 702 "VDC")
			(pintype "passive")
		)
	)
	(footprint "antmicro-footprints:NetTie-2_SMD_Pad0.127mm"
		(layer "F.Cu")
		(at 158.5 185.01 -90)
		(descr "Net tie, 2 pin, 0.127mm  SMD pads")
		(tags "net tie")
		(property "Reference" "NT39"
			(at -0.128 -1.345 270)
			(layer "F.SilkS")
			(hide yes)
			(effects
				(font
					(size 0.7 0.7)
					(thickness 0.15)
				)
				(justify left bottom)
			)
		)
		(property "Value" "Net-Tie_2"
			(at 0 1.199 270)
			(layer "F.Fab")
			(effects
				(font
					(size 0.7 0.7)
					(thickness 0.15)
				)
				(justify left bottom)
			)
		)
		(property "Description" "Net tie, 2 pins"
			(at 0 0 270)
			(layer "F.Fab")
			(hide yes)
			(effects
				(font
					(size 1.27 1.27)
					(thickness 0.15)
				)
			)
		)
		(property "Author" "Antmicro"
			(at -26.51 343.51 0)
			(layer "F.Fab")
			(hide yes)
			(effects
				(font
					(size 1 1)
					(thickness 0.15)
				)
			)
		)
		(property "License" "Apache-2.0"
			(at -26.51 343.51 0)
			(layer "F.Fab")
			(hide yes)
			(effects
				(font
					(size 1 1)
					(thickness 0.15)
				)
			)
		)
		(property "MPN" ""
			(at -26.51 343.51 0)
			(layer "F.Fab")
			(hide yes)
			(effects
				(font
					(size 1 1)
					(thickness 0.15)
				)
			)
		)
		(property "Manufacturer" ""
			(at -26.51 343.51 0)
			(layer "F.Fab")
			(hide yes)
			(effects
				(font
					(size 1 1)
					(thickness 0.15)
				)
			)
		)
		(sheetname "DC-DC Converters")
		(sheetfile "dc-dc.kicad_sch")
		(attr exclude_from_pos_files)
		(net_tie_pad_groups "1, 2")
		(fp_poly
			(pts
				(xy -0.0635 -0.0635) (xy 0.0625 -0.0635) (xy 0.0625 0.0635) (xy -0.0635 0.0635)
			)
			(stroke
				(width 0)
				(type solid)
			)
			(fill yes)
			(layer "F.Cu")
		)
		(pad "1" smd roundrect
			(at -0.127 0 90)
			(size 0.127 0.127)
			(layers "F.Cu")
			(roundrect_rratio 0.5)
			(chamfer_ratio 0)
			(chamfer top_left bottom_left)
			(net 279 "/DC-DC Converters/PB_CTRL.~{PB_CTRL_CLR}")
			(pinfunction "1")
			(pintype "passive")
		)
		(pad "2" smd roundrect
			(at 0.126 0 270)
			(size 0.127 0.127)
			(layers "F.Cu")
			(roundrect_rratio 0.5)
			(chamfer_ratio 0)
			(chamfer top_left bottom_left)
			(net 1340 "/SUP_MCU.SW_STATE")
			(pinfunction "2")
			(pintype "passive")
		)
	)
	(footprint "antmicro-footprints:C_0402_1005Metric"
		(layer "F.Cu")
		(at 239.41 148.16 180)
		(descr "Capacitor SMD 0402")
		(tags "capacitor SMD 0402")
		(property "Reference" "C249"
			(at 0.91 -2.24 180)
			(layer "F.SilkS")
			(effects
				(font
					(size 0.7 0.7)
					(thickness 0.15)
				)
				(justify left bottom)
			)
		)
		(property "Value" "C_100n_0402"
			(at 0 1.169 180)
			(layer "F.Fab")
			(effects
				(font
					(size 0.7 0.7)
					(thickness 0.15)
				)
				(justify left bottom)
			)
		)
		(property "Description" "SMD Multilayer Ceramic Capacitor, 0.1 µF, 50 V, 0402 [1005 Metric], ± 10%, X5R, GRM Series"
			(at 0 0 180)
			(layer "F.Fab")
			(hide yes)
			(effects
				(font
					(size 1.27 1.27)
					(thickness 0.15)
				)
			)
		)
		(property "Author" "Antmicro"
			(at 478.82 296.32 0)
			(layer "F.Fab")
			(hide yes)
			(effects
				(font
					(size 1 1)
					(thickness 0.15)
				)
			)
		)
		(property "Dielectric" "X5R"
			(at 478.82 296.32 0)
			(layer "F.Fab")
			(hide yes)
			(effects
				(font
					(size 1 1)
					(thickness 0.15)
				)
			)
		)
		(property "License" "Apache-2.0"
			(at 478.82 296.32 0)
			(layer "F.Fab")
			(hide yes)
			(effects
				(font
					(size 1 1)
					(thickness 0.15)
				)
			)
		)
		(property "MPN" "GRM155R61H104KE14D"
			(at 478.82 296.32 0)
			(layer "F.Fab")
			(hide yes)
			(effects
				(font
					(size 1 1)
					(thickness 0.15)
				)
			)
		)
		(property "Manufacturer" "Murata"
			(at 478.82 296.32 0)
			(layer "F.Fab")
			(hide yes)
			(effects
				(font
					(size 1 1)
					(thickness 0.15)
				)
			)
		)
		(property "Val" "100n"
			(at 478.82 296.32 0)
			(layer "F.Fab")
			(hide yes)
			(effects
				(font
					(size 1 1)
					(thickness 0.15)
				)
			)
		)
		(property "Voltage" "50V"
			(at 478.82 296.32 0)
			(layer "F.Fab")
			(hide yes)
			(effects
				(font
					(size 1 1)
					(thickness 0.15)
				)
			)
		)
		(sheetname "USB PHY")
		(sheetfile "usb-phy.kicad_sch")
		(attr smd)
		(fp_rect
			(start -0.925 -0.47)
			(end 0.925 0.47)
			(stroke
				(width 0.05)
				(type default)
			)
			(fill no)
			(layer "F.CrtYd")
		)
		(fp_line
			(start 0.504 0.248)
			(end -0.494 0.248)
			(stroke
				(width 0.15)
				(type solid)
			)
			(layer "F.Fab")
		)
		(fp_line
			(start 0.504 -0.25)
			(end 0.504 0.248)
			(stroke
				(width 0.15)
				(type solid)
			)
			(layer "F.Fab")
		)
		(fp_line
			(start -0.494 0.248)
			(end -0.494 -0.25)
			(stroke
				(width 0.15)
				(type solid)
			)
			(layer "F.Fab")
		)
		(fp_line
			(start -0.494 -0.25)
			(end 0.504 -0.25)
			(stroke
				(width 0.15)
				(type solid)
			)
			(layer "F.Fab")
		)
		(pad "1" smd roundrect
			(at -0.48 0 180)
			(size 0.59 0.64)
			(layers "F.Cu" "F.Mask" "F.Paste")
			(roundrect_rratio 0.25)
			(net 1 "GND")
			(pintype "passive")
		)
		(pad "2" smd roundrect
			(at 0.48 0 180)
			(size 0.59 0.64)
			(layers "F.Cu" "F.Mask" "F.Paste")
			(roundrect_rratio 0.25)
			(net 24 "+3V3")
			(pintype "passive")
		)
	)
	(footprint "antmicro-footprints:R_0402_1005Metric"
		(layer "F.Cu")
		(at 244.15 104.3)
		(descr "Resistor SMD 0402")
		(tags "resistor SMD 0402")
		(property "Reference" "R254"
			(at 0.8 0.35 0)
			(layer "F.SilkS")
			(effects
				(font
					(size 0.7 0.7)
					(thickness 0.15)
				)
				(justify left bottom)
			)
		)
		(property "Value" "R_0R_0402"
			(at 0 1.4 0)
			(layer "F.Fab")
			(effects
				(font
					(size 0.7 0.7)
					(thickness 0.15)
				)
				(justify left bottom)
			)
		)
		(property "Description" "SMD Chip Resistor, Jumper, 0 ohm, 100 mW, 0402 [1005 Metric], Thick Film, General Purpose"
			(at 0 0 0)
			(layer "F.Fab")
			(hide yes)
			(effects
				(font
					(size 1.27 1.27)
					(thickness 0.15)
				)
			)
		)
		(property "Author" "Antmicro"
			(at 0 0 0)
			(layer "F.Fab")
			(hide yes)
			(effects
				(font
					(size 1 1)
					(thickness 0.15)
				)
			)
		)
		(property "Current" "1A"
			(at 0 0 0)
			(layer "F.Fab")
			(hide yes)
			(effects
				(font
					(size 1 1)
					(thickness 0.15)
				)
			)
		)
		(property "License" "Apache-2.0"
			(at 0 0 0)
			(layer "F.Fab")
			(hide yes)
			(effects
				(font
					(size 1 1)
					(thickness 0.15)
				)
			)
		)
		(property "MPN" "ERJ2GE0R00X"
			(at 0 0 0)
			(layer "F.Fab")
			(hide yes)
			(effects
				(font
					(size 1 1)
					(thickness 0.15)
				)
			)
		)
		(property "Manufacturer" "Panasonic"
			(at 0 0 0)
			(layer "F.Fab")
			(hide yes)
			(effects
				(font
					(size 1 1)
					(thickness 0.15)
				)
			)
		)
		(property "Tolerance" ""
			(at 0 0 0)
			(layer "F.Fab")
			(hide yes)
			(effects
				(font
					(size 1 1)
					(thickness 0.15)
				)
			)
		)
		(property "Val" "0R"
			(at 0 0 0)
			(layer "F.Fab")
			(hide yes)
			(effects
				(font
					(size 1 1)
					(thickness 0.15)
				)
			)
		)
		(sheetname "HDMI + Ethernet")
		(sheetfile "hdmi-ethernet.kicad_sch")
		(attr smd)
		(fp_rect
			(start -0.925 -0.47)
			(end 0.925 0.47)
			(stroke
				(width 0.05)
				(type default)
			)
			(fill no)
			(layer "F.CrtYd")
		)
		(fp_rect
			(start -0.5 -0.25)
			(end 0.5 0.25)
			(stroke
				(width 0.15)
				(type solid)
			)
			(fill no)
			(layer "F.Fab")
		)
		(pad "1" smd roundrect
			(at -0.48 0)
			(size 0.59 0.64)
			(layers "F.Cu" "F.Mask" "F.Paste")
			(roundrect_rratio 0.25)
			(net 524 "/FPGA Bank 16 & 17/HDMI.D2_P")
			(pintype "passive")
		)
		(pad "2" smd roundrect
			(at 0.48 0)
			(size 0.59 0.64)
			(layers "F.Cu" "F.Mask" "F.Paste")
			(roundrect_rratio 0.25)
			(net 867 "/HDMI + Ethernet/HDMI_CONN_D2_P")
			(pintype "passive")
		)
	)
	(footprint "antmicro-footprints:R_0402_1005Metric"
		(layer "F.Cu")
		(at 218.4 149.8)
		(descr "Resistor SMD 0402")
		(tags "resistor SMD 0402")
		(property "Reference" "R197"
			(at -3.6 0.35 0)
			(layer "F.SilkS")
			(effects
				(font
					(size 0.7 0.7)
					(thickness 0.15)
				)
				(justify left bottom)
			)
		)
		(property "Value" "R_10k_0402"
			(at 0 1.4 0)
			(layer "F.Fab")
			(effects
				(font
					(size 0.7 0.7)
					(thickness 0.15)
				)
				(justify left bottom)
			)
		)
		(property "Description" "SMD Chip Resistor, 10 kohm, ± 1%, 62.5 mW, 0402 [1005 Metric], Thick Film, General Purpose"
			(at 0 0 0)
			(layer "F.Fab")
			(hide yes)
			(effects
				(font
					(size 1.27 1.27)
					(thickness 0.15)
				)
			)
		)
		(property "Author" "Antmicro"
			(at 0 0 0)
			(layer "F.Fab")
			(hide yes)
			(effects
				(font
					(size 1 1)
					(thickness 0.15)
				)
			)
		)
		(property "License" "Apache-2.0"
			(at 0 0 0)
			(layer "F.Fab")
			(hide yes)
			(effects
				(font
					(size 1 1)
					(thickness 0.15)
				)
			)
		)
		(property "MPN" "CR0402-FX-1002GLF"
			(at 0 0 0)
			(layer "F.Fab")
			(hide yes)
			(effects
				(font
					(size 1 1)
					(thickness 0.15)
				)
			)
		)
		(property "Manufacturer" "Bourns"
			(at 0 0 0)
			(layer "F.Fab")
			(hide yes)
			(effects
				(font
					(size 1 1)
					(thickness 0.15)
				)
			)
		)
		(property "Tolerance" "1%"
			(at 0 0 0)
			(layer "F.Fab")
			(hide yes)
			(effects
				(font
					(size 1 1)
					(thickness 0.15)
				)
			)
		)
		(property "Val" "10k"
			(at 0 0 0)
			(layer "F.Fab")
			(hide yes)
			(effects
				(font
					(size 1 1)
					(thickness 0.15)
				)
			)
		)
		(sheetname "HDMI + Ethernet")
		(sheetfile "hdmi-ethernet.kicad_sch")
		(attr smd)
		(fp_rect
			(start -0.925 -0.47)
			(end 0.925 0.47)
			(stroke
				(width 0.05)
				(type default)
			)
			(fill no)
			(layer "F.CrtYd")
		)
		(fp_rect
			(start -0.5 -0.25)
			(end 0.5 0.25)
			(stroke
				(width 0.15)
				(type solid)
			)
			(fill no)
			(layer "F.Fab")
		)
		(pad "1" smd roundrect
			(at -0.48 0)
			(size 0.59 0.64)
			(layers "F.Cu" "F.Mask" "F.Paste")
			(roundrect_rratio 0.25)
			(net 26 "+1V8")
			(pintype "passive")
		)
		(pad "2" smd roundrect
			(at 0.48 0)
			(size 0.59 0.64)
			(layers "F.Cu" "F.Mask" "F.Paste")
			(roundrect_rratio 0.25)
			(net 501 "/FPGA Bank 18 & 32/ETH_RMII.~{RESET}")
			(pintype "passive")
		)
	)
	(footprint "antmicro-footprints:C_0603_1608Metric"
		(layer "F.Cu")
		(at 177.5 165.5)
		(descr "Capacitor SMD 0603")
		(tags "capacitor 0603")
		(property "Reference" "C325"
			(at 1 0.4 0)
			(layer "F.SilkS")
			(effects
				(font
					(size 0.7 0.7)
					(thickness 0.15)
				)
				(justify left bottom)
			)
		)
		(property "Value" "C_22u_0603"
			(at 0 1.6 0)
			(layer "F.Fab")
			(effects
				(font
					(size 0.7 0.7)
					(thickness 0.15)
				)
				(justify left bottom)
			)
		)
		(property "Description" "SMD Multilayer Ceramic Capacitor, 22 µF, 6.3 V, 0603 [1608 Metric], ± 20%, X5R, GRM Series"
			(at 0 0 0)
			(layer "F.Fab")
			(hide yes)
			(effects
				(font
					(size 1.27 1.27)
					(thickness 0.15)
				)
			)
		)
		(property "Author" "Antmicro"
			(at 0 0 0)
			(layer "F.Fab")
			(hide yes)
			(effects
				(font
					(size 1 1)
					(thickness 0.15)
				)
			)
		)
		(property "Dielectric" ""
			(at 0 0 0)
			(layer "F.Fab")
			(hide yes)
			(effects
				(font
					(size 1 1)
					(thickness 0.15)
				)
			)
		)
		(property "License" "Apache-2.0"
			(at 0 0 0)
			(layer "F.Fab")
			(hide yes)
			(effects
				(font
					(size 1 1)
					(thickness 0.15)
				)
			)
		)
		(property "MPN" "GRM188R60J226MEA0D"
			(at 0 0 0)
			(layer "F.Fab")
			(hide yes)
			(effects
				(font
					(size 1 1)
					(thickness 0.15)
				)
			)
		)
		(property "Manufacturer" "Murata"
			(at 0 0 0)
			(layer "F.Fab")
			(hide yes)
			(effects
				(font
					(size 1 1)
					(thickness 0.15)
				)
			)
		)
		(property "Val" "22u"
			(at 0 0 0)
			(layer "F.Fab")
			(hide yes)
			(effects
				(font
					(size 1 1)
					(thickness 0.15)
				)
			)
		)
		(property "Voltage" ""
			(at 0 0 0)
			(layer "F.Fab")
			(hide yes)
			(effects
				(font
					(size 1 1)
					(thickness 0.15)
				)
			)
		)
		(sheetname "DC-DC Converters")
		(sheetfile "dc-dc.kicad_sch")
		(attr smd)
		(fp_line
			(start -0.15 -0.4)
			(end 0.15 -0.4)
			(stroke
				(width 0.15)
				(type solid)
			)
			(layer "F.SilkS")
		)
		(fp_line
			(start -0.15 0.4)
			(end 0.15 0.4)
			(stroke
				(width 0.15)
				(type solid)
			)
			(layer "F.SilkS")
		)
		(fp_rect
			(start -1.25 -0.65)
			(end 1.25 0.65)
			(stroke
				(width 0.05)
				(type solid)
			)
			(fill no)
			(layer "F.CrtYd")
		)
		(fp_rect
			(start -0.8 -0.4)
			(end 0.8 0.4)
			(stroke
				(width 0.15)
				(type solid)
			)
			(fill no)
			(layer "F.Fab")
		)
		(pad "1" smd roundrect
			(at -0.7 0)
			(size 0.8 1)
			(layers "F.Cu" "F.Mask" "F.Paste")
			(roundrect_rratio 0.2)
			(net 1 "GND")
			(pintype "passive")
		)
		(pad "2" smd roundrect
			(at 0.7 0)
			(size 0.8 1)
			(layers "F.Cu" "F.Mask" "F.Paste")
			(roundrect_rratio 0.2)
			(net 736 "/DC-DC Converters/3V3_local_2")
			(pintype "passive")
		)
	)
	(footprint "antmicro-footprints:R_0402_1005Metric"
		(layer "F.Cu")
		(at 209.86 81.74)
		(descr "Resistor SMD 0402")
		(tags "resistor SMD 0402")
		(property "Reference" "R6"
			(at -0.16 1.26 0)
			(layer "F.SilkS")
			(effects
				(font
					(size 0.7 0.7)
					(thickness 0.15)
				)
				(justify left bottom)
			)
		)
		(property "Value" "R_10k_0402"
			(at 0 1.4 0)
			(layer "F.Fab")
			(effects
				(font
					(size 0.7 0.7)
					(thickness 0.15)
				)
				(justify left bottom)
			)
		)
		(property "Description" "SMD Chip Resistor, 10 kohm, ± 1%, 62.5 mW, 0402 [1005 Metric], Thick Film, General Purpose"
			(at 0 0 0)
			(layer "F.Fab")
			(hide yes)
			(effects
				(font
					(size 1.27 1.27)
					(thickness 0.15)
				)
			)
		)
		(property "Author" "Antmicro"
			(at 0 0 0)
			(layer "F.Fab")
			(hide yes)
			(effects
				(font
					(size 1 1)
					(thickness 0.15)
				)
			)
		)
		(property "License" "Apache-2.0"
			(at 0 0 0)
			(layer "F.Fab")
			(hide yes)
			(effects
				(font
					(size 1 1)
					(thickness 0.15)
				)
			)
		)
		(property "MPN" "CR0402-FX-1002GLF"
			(at 0 0 0)
			(layer "F.Fab")
			(hide yes)
			(effects
				(font
					(size 1 1)
					(thickness 0.15)
				)
			)
		)
		(property "Manufacturer" "Bourns"
			(at 0 0 0)
			(layer "F.Fab")
			(hide yes)
			(effects
				(font
					(size 1 1)
					(thickness 0.15)
				)
			)
		)
		(property "Tolerance" "1%"
			(at 0 0 0)
			(layer "F.Fab")
			(hide yes)
			(effects
				(font
					(size 1 1)
					(thickness 0.15)
				)
			)
		)
		(property "Val" "10k"
			(at 0 0 0)
			(layer "F.Fab")
			(hide yes)
			(effects
				(font
					(size 1 1)
					(thickness 0.15)
				)
			)
		)
		(sheetname "FPGA Config")
		(sheetfile "fpga-config.kicad_sch")
		(attr smd)
		(fp_rect
			(start -0.925 -0.47)
			(end 0.925 0.47)
			(stroke
				(width 0.05)
				(type default)
			)
			(fill no)
			(layer "F.CrtYd")
		)
		(fp_rect
			(start -0.5 -0.25)
			(end 0.5 0.25)
			(stroke
				(width 0.15)
				(type solid)
			)
			(fill no)
			(layer "F.Fab")
		)
		(pad "1" smd roundrect
			(at -0.48 0)
			(size 0.59 0.64)
			(layers "F.Cu" "F.Mask" "F.Paste")
			(roundrect_rratio 0.25)
			(net 257 "/FPGA Config/INIT_B")
			(pintype "passive")
		)
		(pad "2" smd roundrect
			(at 0.48 0)
			(size 0.59 0.64)
			(layers "F.Cu" "F.Mask" "F.Paste")
			(roundrect_rratio 0.25)
			(net 24 "+3V3")
			(pintype "passive")
		)
	)
	(footprint "antmicro-footprints:C_Pol_EIA-B"
		(layer "F.Cu")
		(at 206.161 149.4)
		(property "Reference" "C1"
			(at -0.891 -1.69 0)
			(layer "F.SilkS")
			(effects
				(font
					(size 0.7 0.7)
					(thickness 0.15)
				)
				(justify left bottom)
			)
		)
		(property "Value" "C_Pol_330u_6.3V_KEMET-T520-B"
			(at -2.34 2.45 0)
			(layer "F.Fab")
			(effects
				(font
					(size 0.7 0.7)
					(thickness 0.15)
				)
				(justify left bottom)
			)
		)
		(property "Description" "Tantalum Polymer Capacitor, KO-CAP®, 330 µF, ± 20%, 6.3 V, B, 0.04 ohm, 1411 [3528 Metric]"
			(at 0 0 0)
			(layer "F.Fab")
			(hide yes)
			(effects
				(font
					(size 1.27 1.27)
					(thickness 0.15)
				)
			)
		)
		(property "Author" "Antmicro"
			(at 0 0 0)
			(layer "F.Fab")
			(hide yes)
			(effects
				(font
					(size 1 1)
					(thickness 0.15)
				)
			)
		)
		(property "Dielectric" ""
			(at 0 0 0)
			(layer "F.Fab")
			(hide yes)
			(effects
				(font
					(size 1 1)
					(thickness 0.15)
				)
			)
		)
		(property "License" "Apache-2.0"
			(at 0 0 0)
			(layer "F.Fab")
			(hide yes)
			(effects
				(font
					(size 1 1)
					(thickness 0.15)
				)
			)
		)
		(property "MPN" "T520B337M006ATE040"
			(at 0 0 0)
			(layer "F.Fab")
			(hide yes)
			(effects
				(font
					(size 1 1)
					(thickness 0.15)
				)
			)
		)
		(property "Manufacturer" "KEMET"
			(at 0 0 0)
			(layer "F.Fab")
			(hide yes)
			(effects
				(font
					(size 1 1)
					(thickness 0.15)
				)
			)
		)
		(property "Val" "330u"
			(at 0 0 0)
			(layer "F.Fab")
			(hide yes)
			(effects
				(font
					(size 1 1)
					(thickness 0.15)
				)
			)
		)
		(property "Voltage" "6.3V"
			(at 0 0 0)
			(layer "F.Fab")
			(hide yes)
			(effects
				(font
					(size 1 1)
					(thickness 0.15)
				)
			)
		)
		(sheetname "FPGA supply")
		(sheetfile "fpga-supply.kicad_sch")
		(attr smd)
		(fp_line
			(start -2.521 -1.676)
			(end -2.123 -1.676)
			(stroke
				(width 0.15)
				(type solid)
			)
			(layer "F.SilkS")
		)
		(fp_line
			(start -2.325 -1.475)
			(end -2.325 -1.878)
			(stroke
				(width 0.15)
				(type solid)
			)
			(layer "F.SilkS")
		)
		(fp_line
			(start -1.8 -1.6)
			(end 1.8 -1.6)
			(stroke
				(width 0.15)
				(type solid)
			)
			(layer "F.SilkS")
		)
		(fp_line
			(start -1.8 -1.3)
			(end -1.8 -1.6)
			(stroke
				(width 0.15)
				(type solid)
			)
			(layer "F.SilkS")
		)
		(fp_line
			(start -1.8 1.3)
			(end -1.8 1.6)
			(stroke
				(width 0.15)
				(type solid)
			)
			(layer "F.SilkS")
		)
		(fp_line
			(start 1.8 -1.3)
			(end 1.8 -1.6)
			(stroke
				(width 0.15)
				(type solid)
			)
			(layer "F.SilkS")
		)
		(fp_line
			(start 1.8 1.3)
			(end 1.8 1.6)
			(stroke
				(width 0.15)
				(type solid)
			)
			(layer "F.SilkS")
		)
		(fp_line
			(start 1.8 1.6)
			(end -1.8 1.6)
			(stroke
				(width 0.15)
				(type solid)
			)
			(layer "F.SilkS")
		)
		(fp_line
			(start -2.411 -1.35)
			(end -2.41 1.35)
			(stroke
				(width 0.05)
				(type solid)
			)
			(layer "F.CrtYd")
		)
		(fp_line
			(start -1.97 -1.75)
			(end -1.97 -1.35)
			(stroke
				(width 0.05)
				(type solid)
			)
			(layer "F.CrtYd")
		)
		(fp_line
			(start -1.97 -1.35)
			(end -2.41 -1.35)
			(stroke
				(width 0.05)
				(type solid)
			)
			(layer "F.CrtYd")
		)
		(fp_line
			(start -1.97 1.35)
			(end -2.41 1.35)
			(stroke
				(width 0.05)
				(type solid)
			)
			(layer "F.CrtYd")
		)
		(fp_line
			(start -1.97 1.35)
			(end -1.97 1.75)
			(stroke
				(width 0.05)
				(type solid)
			)
			(layer "F.CrtYd")
		)
		(fp_line
			(start 1.959 -1.75)
			(end -1.971 -1.75)
			(stroke
				(width 0.05)
				(type solid)
			)
			(layer "F.CrtYd")
		)
		(fp_line
			(start 1.959 -1.75)
			(end 1.959 -1.35)
			(stroke
				(width 0.05)
				(type solid)
			)
			(layer "F.CrtYd")
		)
		(fp_line
			(start 1.96 1.35)
			(end 1.96 1.75)
			(stroke
				(width 0.05)
				(type solid)
			)
			(layer "F.CrtYd")
		)
		(fp_line
			(start 1.96 1.75)
			(end -1.97 1.75)
			(stroke
				(width 0.05)
				(type solid)
			)
			(layer "F.CrtYd")
		)
		(fp_line
			(start 2.399 -1.35)
			(end 1.959 -1.35)
			(stroke
				(width 0.05)
				(type solid)
			)
			(layer "F.CrtYd")
		)
		(fp_line
			(start 2.399 -1.35)
			(end 2.4 1.35)
			(stroke
				(width 0.05)
				(type solid)
			)
			(layer "F.CrtYd")
		)
		(fp_line
			(start 2.4 1.35)
			(end 1.96 1.35)
			(stroke
				(width 0.05)
				(type solid)
			)
			(layer "F.CrtYd")
		)
		(fp_line
			(start -1.7 1.324)
			(end -1.551 1.475)
			(stroke
				(width 0.15)
				(type solid)
			)
			(layer "F.Fab")
		)
		(fp_rect
			(start -1.72 -1.5)
			(end 1.719 1.499)
			(stroke
				(width 0.15)
				(type solid)
			)
			(fill no)
			(layer "F.Fab")
		)
		(pad "1" smd roundrect
			(at -1.551 0)
			(size 1.2 2.2)
			(layers "F.Cu" "F.Mask" "F.Paste")
			(roundrect_rratio 0.1)
			(net 650 "+1V0")
			(pintype "passive")
		)
		(pad "2" smd roundrect
			(at 1.55 0)
			(size 1.2 2.2)
			(layers "F.Cu" "F.Mask" "F.Paste")
			(roundrect_rratio 0.1)
			(net 1 "GND")
			(pintype "passive")
		)
	)
	(footprint "antmicro-footprints:R_0402_1005Metric"
		(layer "F.Cu")
		(at 206.69 75.44 -90)
		(descr "Resistor SMD 0402")
		(tags "resistor SMD 0402")
		(property "Reference" "R9"
			(at -0.74 -0.41 270)
			(layer "F.SilkS")
			(effects
				(font
					(size 0.7 0.7)
					(thickness 0.15)
				)
				(justify left bottom)
			)
		)
		(property "Value" "R_330R_0402"
			(at 0 1.4 270)
			(layer "F.Fab")
			(effects
				(font
					(size 0.7 0.7)
					(thickness 0.15)
				)
				(justify left bottom)
			)
		)
		(property "Description" "SMD Chip Resistor, 330 ohm, ± 1%, 62.5 mW, 0402 [1005 Metric], Thick Film, General Purpose"
			(at 0 0 270)
			(layer "F.Fab")
			(hide yes)
			(effects
				(font
					(size 1.27 1.27)
					(thickness 0.15)
				)
			)
		)
		(property "Author" "Antmicro"
			(at 131.25 282.13 0)
			(layer "F.Fab")
			(hide yes)
			(effects
				(font
					(size 1 1)
					(thickness 0.15)
				)
			)
		)
		(property "License" "Apache-2.0"
			(at 131.25 282.13 0)
			(layer "F.Fab")
			(hide yes)
			(effects
				(font
					(size 1 1)
					(thickness 0.15)
				)
			)
		)
		(property "MPN" "CR0402-FX-3300GLF"
			(at 131.25 282.13 0)
			(layer "F.Fab")
			(hide yes)
			(effects
				(font
					(size 1 1)
					(thickness 0.15)
				)
			)
		)
		(property "Manufacturer" "Bourns"
			(at 131.25 282.13 0)
			(layer "F.Fab")
			(hide yes)
			(effects
				(font
					(size 1 1)
					(thickness 0.15)
				)
			)
		)
		(property "Tolerance" "1%"
			(at 131.25 282.13 0)
			(layer "F.Fab")
			(hide yes)
			(effects
				(font
					(size 1 1)
					(thickness 0.15)
				)
			)
		)
		(property "Val" "330R"
			(at 131.25 282.13 0)
			(layer "F.Fab")
			(hide yes)
			(effects
				(font
					(size 1 1)
					(thickness 0.15)
				)
			)
		)
		(sheetname "FPGA Config")
		(sheetfile "fpga-config.kicad_sch")
		(attr smd)
		(fp_rect
			(start -0.925 -0.47)
			(end 0.925 0.47)
			(stroke
				(width 0.05)
				(type default)
			)
			(fill no)
			(layer "F.CrtYd")
		)
		(fp_rect
			(start -0.5 -0.25)
			(end 0.5 0.25)
			(stroke
				(width 0.15)
				(type solid)
			)
			(fill no)
			(layer "F.Fab")
		)
		(pad "1" smd roundrect
			(at -0.48 0 270)
			(size 0.59 0.64)
			(layers "F.Cu" "F.Mask" "F.Paste")
			(roundrect_rratio 0.25)
			(net 17 "Net-(D1-C)")
			(pintype "passive")
		)
		(pad "2" smd roundrect
			(at 0.48 0 270)
			(size 0.59 0.64)
			(layers "F.Cu" "F.Mask" "F.Paste")
			(roundrect_rratio 0.25)
			(net 333 "Net-(Q1-D)")
			(pintype "passive")
		)
	)
	(footprint "antmicro-footprints:C_0402_1005Metric"
		(layer "F.Cu")
		(at 220.8 165.7 180)
		(descr "Capacitor SMD 0402")
		(tags "capacitor SMD 0402")
		(property "Reference" "C164"
			(at -3.65 -0.4 0)
			(layer "F.SilkS")
			(effects
				(font
					(size 0.7 0.7)
					(thickness 0.15)
				)
				(justify right bottom)
			)
		)
		(property "Value" "C_100n_0402"
			(at 0 1.4 0)
			(layer "F.Fab")
			(effects
				(font
					(size 0.7 0.7)
					(thickness 0.15)
				)
				(justify right bottom)
			)
		)
		(property "Description" "SMD Multilayer Ceramic Capacitor, 0.1 µF, 50 V, 0402 [1005 Metric], ± 10%, X5R, GRM Series"
			(at 0 0 180)
			(layer "F.Fab")
			(hide yes)
			(effects
				(font
					(size 1.27 1.27)
					(thickness 0.15)
				)
			)
		)
		(property "Author" "Antmicro"
			(at 441.6 331.4 0)
			(layer "F.Fab")
			(hide yes)
			(effects
				(font
					(size 1 1)
					(thickness 0.15)
				)
			)
		)
		(property "Dielectric" "X5R"
			(at 441.6 331.4 0)
			(layer "F.Fab")
			(hide yes)
			(effects
				(font
					(size 1 1)
					(thickness 0.15)
				)
			)
		)
		(property "License" "Apache-2.0"
			(at 441.6 331.4 0)
			(layer "F.Fab")
			(hide yes)
			(effects
				(font
					(size 1 1)
					(thickness 0.15)
				)
			)
		)
		(property "MPN" "GRM155R61H104KE14D"
			(at 441.6 331.4 0)
			(layer "F.Fab")
			(hide yes)
			(effects
				(font
					(size 1 1)
					(thickness 0.15)
				)
			)
		)
		(property "Manufacturer" "Murata"
			(at 441.6 331.4 0)
			(layer "F.Fab")
			(hide yes)
			(effects
				(font
					(size 1 1)
					(thickness 0.15)
				)
			)
		)
		(property "Val" "100n"
			(at 441.6 331.4 0)
			(layer "F.Fab")
			(hide yes)
			(effects
				(font
					(size 1 1)
					(thickness 0.15)
				)
			)
		)
		(property "Voltage" "50V"
			(at 441.6 331.4 0)
			(layer "F.Fab")
			(hide yes)
			(effects
				(font
					(size 1 1)
					(thickness 0.15)
				)
			)
		)
		(sheetname "FPGA Config")
		(sheetfile "fpga-config.kicad_sch")
		(attr smd)
		(fp_rect
			(start -0.925 -0.47)
			(end 0.925 0.47)
			(stroke
				(width 0.05)
				(type default)
			)
			(fill no)
			(layer "F.CrtYd")
		)
		(fp_line
			(start 0.504 0.248)
			(end -0.494 0.248)
			(stroke
				(width 0.15)
				(type solid)
			)
			(layer "F.Fab")
		)
		(fp_line
			(start 0.504 -0.25)
			(end 0.504 0.248)
			(stroke
				(width 0.15)
				(type solid)
			)
			(layer "F.Fab")
		)
		(fp_line
			(start -0.494 0.248)
			(end -0.494 -0.25)
			(stroke
				(width 0.15)
				(type solid)
			)
			(layer "F.Fab")
		)
		(fp_line
			(start -0.494 -0.25)
			(end 0.504 -0.25)
			(stroke
				(width 0.15)
				(type solid)
			)
			(layer "F.Fab")
		)
		(pad "1" smd roundrect
			(at -0.48 0 180)
			(size 0.59 0.64)
			(layers "F.Cu" "F.Mask" "F.Paste")
			(roundrect_rratio 0.25)
			(net 1 "GND")
			(pintype "passive")
		)
		(pad "2" smd roundrect
			(at 0.48 0 180)
			(size 0.59 0.64)
			(layers "F.Cu" "F.Mask" "F.Paste")
			(roundrect_rratio 0.25)
			(net 24 "+3V3")
			(pintype "passive")
		)
	)
	(footprint "antmicro-footprints:L_Bourns-SRP6050CA"
		(layer "F.Cu")
		(at 200.5 159.424 90)
		(property "Reference" "L1"
			(at -4.376 2.2 180)
			(layer "F.SilkS")
			(effects
				(font
					(size 0.7 0.7)
					(thickness 0.15)
				)
				(justify left bottom)
			)
		)
		(property "Value" "L_1u5_17A_Bourns-SRP6050CA"
			(at -5.41 4.27 90)
			(layer "F.Fab")
			(effects
				(font
					(size 0.7 0.7)
					(thickness 0.15)
				)
				(justify left bottom)
			)
		)
		(property "Description" "Power Inductor (SMT), 1.5 µH, 17 A, Shielded, 19.5 A, SRP6050CA"
			(at 0 0 90)
			(layer "F.Fab")
			(hide yes)
			(effects
				(font
					(size 1.27 1.27)
					(thickness 0.15)
				)
			)
		)
		(property "Author" "Antmicro"
			(at 359.924 -41.076 0)
			(layer "F.Fab")
			(hide yes)
			(effects
				(font
					(size 1 1)
					(thickness 0.15)
				)
			)
		)
		(property "IMax" "17 A"
			(at 359.924 -41.076 0)
			(layer "F.Fab")
			(hide yes)
			(effects
				(font
					(size 1 1)
					(thickness 0.15)
				)
			)
		)
		(property "ISat" "19.5 A"
			(at 359.924 -41.076 0)
			(layer "F.Fab")
			(hide yes)
			(effects
				(font
					(size 1 1)
					(thickness 0.15)
				)
			)
		)
		(property "License" "Apache-2.0"
			(at 359.924 -41.076 0)
			(layer "F.Fab")
			(hide yes)
			(effects
				(font
					(size 1 1)
					(thickness 0.15)
				)
			)
		)
		(property "MPN" "SRP6050CA-1R5M"
			(at 359.924 -41.076 0)
			(layer "F.Fab")
			(hide yes)
			(effects
				(font
					(size 1 1)
					(thickness 0.15)
				)
			)
		)
		(property "Manufacturer" "Bourns"
			(at 359.924 -41.076 0)
			(layer "F.Fab")
			(hide yes)
			(effects
				(font
					(size 1 1)
					(thickness 0.15)
				)
			)
		)
		(property "Size" "6.6x6.6"
			(at 359.924 -41.076 0)
			(layer "F.Fab")
			(hide yes)
			(effects
				(font
					(size 1 1)
					(thickness 0.15)
				)
			)
		)
		(property "Val" "1u5/17A"
			(at 359.924 -41.076 0)
			(layer "F.Fab")
			(hide yes)
			(effects
				(font
					(size 1 1)
					(thickness 0.15)
				)
			)
		)
		(sheetname "DC-DC Converters")
		(sheetfile "dc-dc.kicad_sch")
		(attr smd)
		(fp_line
			(start 3.2 -3.301)
			(end 3.2 3.298)
			(stroke
				(width 0.15)
				(type solid)
			)
			(layer "F.SilkS")
		)
		(fp_line
			(start -3.2 -3.301)
			(end 3.2 -3.301)
			(stroke
				(width 0.15)
				(type solid)
			)
			(layer "F.SilkS")
		)
		(fp_line
			(start -3.2 -3.301)
			(end -3.2 3.298)
			(stroke
				(width 0.15)
				(type solid)
			)
			(layer "F.SilkS")
		)
		(fp_line
			(start 3.2 3.298)
			(end -3.2 3.298)
			(stroke
				(width 0.15)
				(type solid)
			)
			(layer "F.SilkS")
		)
		(fp_rect
			(start -3.45 -3.55)
			(end 3.45 3.55)
			(stroke
				(width 0.05)
				(type solid)
			)
			(fill no)
			(layer "F.CrtYd")
		)
		(fp_rect
			(start -3.202 -3.301)
			(end 3.2 3.298)
			(stroke
				(width 0.15)
				(type solid)
			)
			(fill no)
			(layer "F.Fab")
		)
		(pad "1" smd roundrect
			(at -2.025 0 90)
			(size 1.55 5.6)
			(layers "F.Cu" "F.Mask" "F.Paste")
			(roundrect_rratio 0.1)
			(net 746 "/DC-DC Converters/1V0_SW")
			(pintype "passive")
		)
		(pad "2" smd roundrect
			(at 2.025 0 90)
			(size 1.55 5.6)
			(layers "F.Cu" "F.Mask" "F.Paste")
			(roundrect_rratio 0.1)
			(net 751 "/DC-DC Converters/1V0_REG")
			(pintype "passive")
		)
	)
	(footprint "antmicro-footprints:SC70-3"
		(layer "F.Cu")
		(at 258.4 88.6)
		(property "Reference" "Q10"
			(at -1.6 1.1 90)
			(layer "F.SilkS")
			(effects
				(font
					(size 0.7 0.7)
					(thickness 0.15)
				)
				(justify left bottom)
			)
		)
		(property "Value" "BSS138PW"
			(at 0 2.3 0)
			(layer "F.Fab")
			(effects
				(font
					(size 0.7 0.7)
					(thickness 0.15)
				)
				(justify left bottom)
			)
		)
		(property "Description" "Power MOSFET, N Channel, 60 V, 320 mA, 0.9 ohm, SOT-323, Surface Mount"
			(at 0 0 0)
			(layer "F.Fab")
			(hide yes)
			(effects
				(font
					(size 1.27 1.27)
					(thickness 0.15)
				)
			)
		)
		(property "Author" "Antmicro"
			(at 0 0 0)
			(layer "F.Fab")
			(hide yes)
			(effects
				(font
					(size 1 1)
					(thickness 0.15)
				)
			)
		)
		(property "License" "Apache-2.0"
			(at 0 0 0)
			(layer "F.Fab")
			(hide yes)
			(effects
				(font
					(size 1 1)
					(thickness 0.15)
				)
			)
		)
		(property "MPN" "BSS138PW"
			(at 0 0 0)
			(layer "F.Fab")
			(hide yes)
			(effects
				(font
					(size 1 1)
					(thickness 0.15)
				)
			)
		)
		(property "Manufacturer" "Nexperia"
			(at 0 0 0)
			(layer "F.Fab")
			(hide yes)
			(effects
				(font
					(size 1 1)
					(thickness 0.15)
				)
			)
		)
		(sheetname "User GPIO + LED + button + DIP switch")
		(sheetfile "user-gpio.kicad_sch")
		(attr smd)
		(fp_line
			(start -0.3 -1)
			(end 0.627 -0.999)
			(stroke
				(width 0.15)
				(type solid)
			)
			(layer "F.SilkS")
		)
		(fp_line
			(start -0.3 1)
			(end 0.627 1.001)
			(stroke
				(width 0.15)
				(type solid)
			)
			(layer "F.SilkS")
		)
		(fp_line
			(start 0.627 -0.6)
			(end 0.627 -0.999)
			(stroke
				(width 0.15)
				(type solid)
			)
			(layer "F.SilkS")
		)
		(fp_line
			(start 0.627 0.6)
			(end 0.627 1.001)
			(stroke
				(width 0.15)
				(type solid)
			)
			(layer "F.SilkS")
		)
		(fp_line
			(start -1.4 1)
			(end -1.4 -1)
			(stroke
				(width 0.05)
				(type solid)
			)
			(layer "F.CrtYd")
		)
		(fp_line
			(start -0.9 -1.3)
			(end -0.9 -1)
			(stroke
				(width 0.05)
				(type solid)
			)
			(layer "F.CrtYd")
		)
		(fp_line
			(start -0.9 -1.3)
			(end 0.9 -1.3)
			(stroke
				(width 0.05)
				(type solid)
			)
			(layer "F.CrtYd")
		)
		(fp_line
			(start -0.9 -1)
			(end -1.4 -1)
			(stroke
				(width 0.05)
				(type solid)
			)
			(layer "F.CrtYd")
		)
		(fp_line
			(start -0.9 1)
			(end -1.4 1)
			(stroke
				(width 0.05)
				(type solid)
			)
			(layer "F.CrtYd")
		)
		(fp_line
			(start -0.9 1.3)
			(end -0.9 1)
			(stroke
				(width 0.05)
				(type solid)
			)
			(layer "F.CrtYd")
		)
		(fp_line
			(start 0.9 -1.3)
			(end 0.9 -0.4)
			(stroke
				(width 0.05)
				(type solid)
			)
			(layer "F.CrtYd")
		)
		(fp_line
			(start 0.9 -0.4)
			(end 1.4 -0.4)
			(stroke
				(width 0.05)
				(type solid)
			)
			(layer "F.CrtYd")
		)
		(fp_line
			(start 0.9 0.4)
			(end 0.9 1.3)
			(stroke
				(width 0.05)
				(type solid)
			)
			(layer "F.CrtYd")
		)
		(fp_line
			(start 0.9 1.3)
			(end -0.9 1.3)
			(stroke
				(width 0.05)
				(type solid)
			)
			(layer "F.CrtYd")
		)
		(fp_line
			(start 1.4 -0.4)
			(end 1.4 0.4)
			(stroke
				(width 0.05)
				(type solid)
			)
			(layer "F.CrtYd")
		)
		(fp_line
			(start 1.4 0.4)
			(end 0.9 0.4)
			(stroke
				(width 0.05)
				(type solid)
			)
			(layer "F.CrtYd")
		)
		(fp_rect
			(start -0.623 -0.999)
			(end 0.627 1.001)
			(stroke
				(width 0.15)
				(type solid)
			)
			(fill no)
			(layer "F.Fab")
		)
		(pad "1" smd rect
			(at -1.051 -0.65 90)
			(size 0.6 0.6)
			(layers "F.Cu" "F.Mask" "F.Paste")
			(net 1301 "/USER_IO.LED_GREEN2")
			(pinfunction "G")
			(pintype "passive")
		)
		(pad "2" smd rect
			(at -1.051 0.65 90)
			(size 0.6 0.6)
			(layers "F.Cu" "F.Mask" "F.Paste")
			(net 1 "GND")
			(pinfunction "S")
			(pintype "passive")
		)
		(pad "3" smd rect
			(at 1.05 0 90)
			(size 0.6 0.6)
			(layers "F.Cu" "F.Mask" "F.Paste")
			(net 22 "Net-(D20-C)")
			(pinfunction "D")
			(pintype "passive")
		)
	)
	(footprint "antmicro-footprints:LED_0603_1608Metric_G"
		(layer "F.Cu")
		(at 209.52 74.97 90)
		(descr "LED SMD 0603 Green")
		(tags "LED SMD 0603 Green")
		(property "Reference" "D2"
			(at -2.23 0.78 0)
			(layer "F.SilkS")
			(effects
				(font
					(size 0.7 0.7)
					(thickness 0.15)
				)
				(justify right bottom)
			)
		)
		(property "Value" "LED_G_0603_KP-1608CGCK"
			(at 0 1.6 90)
			(layer "F.Fab")
			(effects
				(font
					(size 0.7 0.7)
					(thickness 0.15)
				)
				(justify left bottom)
			)
		)
		(property "Description" "LED, Green, SMD, 0603, 20 mA, 2.1 V, 570 nm"
			(at 0 0 90)
			(layer "F.Fab")
			(hide yes)
			(effects
				(font
					(size 1.27 1.27)
					(thickness 0.15)
				)
			)
		)
		(property "Author" "Antmicro"
			(at 284.49 -134.55 0)
			(layer "F.Fab")
			(hide yes)
			(effects
				(font
					(size 1 1)
					(thickness 0.15)
				)
			)
		)
		(property "Color" "Green"
			(at 284.49 -134.55 0)
			(layer "F.Fab")
			(hide yes)
			(effects
				(font
					(size 1 1)
					(thickness 0.15)
				)
			)
		)
		(property "License" "Apache-2.0"
			(at 284.49 -134.55 0)
			(layer "F.Fab")
			(hide yes)
			(effects
				(font
					(size 1 1)
					(thickness 0.15)
				)
			)
		)
		(property "MPN" "KP-1608CGCK"
			(at 284.49 -134.55 0)
			(layer "F.Fab")
			(hide yes)
			(effects
				(font
					(size 1 1)
					(thickness 0.15)
				)
			)
		)
		(property "Manufacturer" "Kingbright"
			(at 284.49 -134.55 0)
			(layer "F.Fab")
			(hide yes)
			(effects
				(font
					(size 1 1)
					(thickness 0.15)
				)
			)
		)
		(sheetname "FPGA Config")
		(sheetfile "fpga-config.kicad_sch")
		(attr smd)
		(fp_line
			(start 0.22 -0.35)
			(end -0.22 -0.35)
			(stroke
				(width 0.15)
				(type solid)
			)
			(layer "F.SilkS")
		)
		(fp_line
			(start -1.18 -0.319)
			(end -1.18 0.321)
			(stroke
				(width 0.15)
				(type solid)
			)
			(layer "F.SilkS")
		)
		(fp_line
			(start 0.105328 0.001008)
			(end 0.24 0.001)
			(stroke
				(width 0.1)
				(type solid)
			)
			(layer "F.SilkS")
		)
		(fp_line
			(start -0.094672 0.001008)
			(end 0.105328 -0.198992)
			(stroke
				(width 0.1)
				(type solid)
			)
			(layer "F.SilkS")
		)
		(fp_line
			(start -0.094672 0.001008)
			(end -0.24 0.001008)
			(stroke
				(width 0.1)
				(type solid)
			)
			(layer "F.SilkS")
		)
		(fp_line
			(start 0.105328 0.201008)
			(end 0.105328 -0.198992)
			(stroke
				(width 0.1)
				(type solid)
			)
			(layer "F.SilkS")
		)
		(fp_line
			(start 0.105328 0.201008)
			(end -0.094672 0.001008)
			(stroke
				(width 0.1)
				(type solid)
			)
			(layer "F.SilkS")
		)
		(fp_line
			(start -0.094672 0.201008)
			(end -0.094672 -0.198992)
			(stroke
				(width 0.1)
				(type solid)
			)
			(layer "F.SilkS")
		)
		(fp_line
			(start 0.22 0.35)
			(end -0.22 0.35)
			(stroke
				(width 0.15)
				(type solid)
			)
			(layer "F.SilkS")
		)
		(fp_rect
			(start 1.25 0.65)
			(end -1.25 -0.65)
			(stroke
				(width 0.05)
				(type solid)
			)
			(fill no)
			(layer "F.CrtYd")
		)
		(fp_line
			(start 0.201 -0.202)
			(end -0.101 0)
			(stroke
				(width 0.15)
				(type solid)
			)
			(layer "F.Fab")
		)
		(fp_line
			(start -0.199 -0.202)
			(end -0.199 0.1)
			(stroke
				(width 0.15)
				(type solid)
			)
			(layer "F.Fab")
		)
		(fp_line
			(start 0.599 0)
			(end 0.201 0)
			(stroke
				(width 0.15)
				(type solid)
			)
			(layer "F.Fab")
		)
		(fp_line
			(start 0.201 0)
			(end 0.201 -0.202)
			(stroke
				(width 0.15)
				(type solid)
			)
			(layer "F.Fab")
		)
		(fp_line
			(start -0.101 0)
			(end 0.201 0.2)
			(stroke
				(width 0.15)
				(type solid)
			)
			(layer "F.Fab")
		)
		(fp_line
			(start -0.199 0)
			(end -0.597 0)
			(stroke
				(width 0.15)
				(type solid)
			)
			(layer "F.Fab")
		)
		(fp_line
			(start 0.201 0.2)
			(end 0.201 0)
			(stroke
				(width 0.15)
				(type solid)
			)
			(layer "F.Fab")
		)
		(fp_line
			(start -0.199 0.2)
			(end -0.199 0.1)
			(stroke
				(width 0.15)
				(type solid)
			)
			(layer "F.Fab")
		)
		(fp_rect
			(start 0.848 0.4)
			(end -0.85 -0.402)
			(stroke
				(width 0.15)
				(type solid)
			)
			(fill no)
			(layer "F.Fab")
		)
		(pad "1" smd roundrect
			(at -0.7 0 270)
			(size 0.8 1)
			(layers "F.Cu" "F.Mask" "F.Paste")
			(roundrect_rratio 0.2)
			(net 754 "Net-(D2-C)")
			(pinfunction "C")
			(pintype "passive")
		)
		(pad "2" smd roundrect
			(at 0.7 0 270)
			(size 0.8 1)
			(layers "F.Cu" "F.Mask" "F.Paste")
			(roundrect_rratio 0.2)
			(net 24 "+3V3")
			(pinfunction "A")
			(pintype "passive")
		)
	)
	(footprint "antmicro-footprints:Nexperia_SOD128"
		(layer "F.Cu")
		(at 188.675 172.349)
		(property "Reference" "D16"
			(at -3.225 -0.049 90)
			(layer "F.SilkS")
			(effects
				(font
					(size 0.7 0.7)
					(thickness 0.15)
				)
			)
		)
		(property "Value" "PMEG3050EP,115"
			(at 0 2.4765 0)
			(layer "F.Fab")
			(effects
				(font
					(size 1 1)
					(thickness 0.15)
				)
			)
		)
		(property "Description" "Schottky Rectifier, 30 V, 5 A, Single, SOD-128, 2 Pins, 360 mV"
			(at 0 0 0)
			(layer "F.Fab")
			(hide yes)
			(effects
				(font
					(size 1.27 1.27)
					(thickness 0.15)
				)
			)
		)
		(property "Author" "Antmicro"
			(at 0 0 0)
			(layer "F.Fab")
			(hide yes)
			(effects
				(font
					(size 1 1)
					(thickness 0.15)
				)
			)
		)
		(property "DNP" "DNP"
			(at 0 0 0)
			(layer "F.Fab")
			(hide yes)
			(effects
				(font
					(size 1 1)
					(thickness 0.15)
				)
			)
		)
		(property "License" "Apache-2.0"
			(at 0 0 0)
			(layer "F.Fab")
			(hide yes)
			(effects
				(font
					(size 1 1)
					(thickness 0.15)
				)
			)
		)
		(property "MPN" "PMEG3050EP,115"
			(at 0 0 0)
			(layer "F.Fab")
			(hide yes)
			(effects
				(font
					(size 1 1)
					(thickness 0.15)
				)
			)
		)
		(property "Manufacturer" "Nexperia"
			(at 0 0 0)
			(layer "F.Fab")
			(hide yes)
			(effects
				(font
					(size 1 1)
					(thickness 0.15)
				)
			)
		)
		(property "dnp" ""
			(at 0 0 0)
			(layer "F.Fab")
			(hide yes)
			(effects
				(font
					(size 1 1)
					(thickness 0.15)
				)
			)
		)
		(property "exclude_from_bom" ""
			(at 0 0 0)
			(layer "F.Fab")
			(hide yes)
			(effects
				(font
					(size 1 1)
					(thickness 0.15)
				)
			)
		)
		(sheetname "Power supply")
		(sheetfile "power-supply.kicad_sch")
		(attr smd exclude_from_bom)
		(fp_line
			(start -2.121 -1.474)
			(end -2.121 -1.287)
			(stroke
				(width 0.15)
				(type solid)
			)
			(layer "F.SilkS")
		)
		(fp_line
			(start -2.121 1.284)
			(end -2.121 1.473)
			(stroke
				(width 0.15)
				(type solid)
			)
			(layer "F.SilkS")
		)
		(fp_line
			(start -2.121 1.473)
			(end 2.12 1.473)
			(stroke
				(width 0.15)
				(type solid)
			)
			(layer "F.SilkS")
		)
		(fp_line
			(start -1.6 -1.4)
			(end -1.6 1.4)
			(stroke
				(width 0.12)
				(type solid)
			)
			(layer "F.SilkS")
		)
		(fp_line
			(start 2.12 -1.474)
			(end -2.121 -1.474)
			(stroke
				(width 0.15)
				(type solid)
			)
			(layer "F.SilkS")
		)
		(fp_line
			(start 2.12 -1.287)
			(end 2.12 -1.474)
			(stroke
				(width 0.15)
				(type solid)
			)
			(layer "F.SilkS")
		)
		(fp_line
			(start 2.12 1.473)
			(end 2.12 1.284)
			(stroke
				(width 0.15)
				(type solid)
			)
			(layer "F.SilkS")
		)
		(fp_rect
			(start -2.8 -1.6)
			(end 2.8 1.6)
			(stroke
				(width 0.05)
				(type solid)
			)
			(fill no)
			(layer "F.CrtYd")
		)
		(fp_line
			(start -2.503 -0.954)
			(end -2.503 0.952)
			(stroke
				(width 0.15)
				(type solid)
			)
			(layer "F.Fab")
		)
		(fp_line
			(start -2.503 0.952)
			(end -1.994 0.952)
			(stroke
				(width 0.15)
				(type solid)
			)
			(layer "F.Fab")
		)
		(fp_line
			(start -1.994 -1.347)
			(end -1.994 1.346)
			(stroke
				(width 0.15)
				(type solid)
			)
			(layer "F.Fab")
		)
		(fp_line
			(start -1.994 -0.954)
			(end -2.503 -0.954)
			(stroke
				(width 0.15)
				(type solid)
			)
			(layer "F.Fab")
		)
		(fp_line
			(start -1.994 -0.675)
			(end -1.321 -1.347)
			(stroke
				(width 0.15)
				(type solid)
			)
			(layer "F.Fab")
		)
		(fp_line
			(start -1.994 0.673)
			(end -1.321 1.346)
			(stroke
				(width 0.15)
				(type solid)
			)
			(layer "F.Fab")
		)
		(fp_line
			(start -1.994 0.952)
			(end -1.994 -0.954)
			(stroke
				(width 0.15)
				(type solid)
			)
			(layer "F.Fab")
		)
		(fp_line
			(start -1.994 1.346)
			(end 1.993 1.346)
			(stroke
				(width 0.15)
				(type solid)
			)
			(layer "F.Fab")
		)
		(fp_line
			(start 1.993 -1.347)
			(end -1.994 -1.347)
			(stroke
				(width 0.15)
				(type solid)
			)
			(layer "F.Fab")
		)
		(fp_line
			(start 1.993 -0.954)
			(end 1.993 0.952)
			(stroke
				(width 0.15)
				(type solid)
			)
			(layer "F.Fab")
		)
		(fp_line
			(start 1.993 0.952)
			(end 2.5 0.952)
			(stroke
				(width 0.15)
				(type solid)
			)
			(layer "F.Fab")
		)
		(fp_line
			(start 1.993 1.346)
			(end 1.993 -1.347)
			(stroke
				(width 0.15)
				(type solid)
			)
			(layer "F.Fab")
		)
		(fp_line
			(start 2.5 -0.954)
			(end 1.993 -0.954)
			(stroke
				(width 0.15)
				(type solid)
			)
			(layer "F.Fab")
		)
		(fp_line
			(start 2.5 0.952)
			(end 2.5 -0.954)
			(stroke
				(width 0.15)
				(type solid)
			)
			(layer "F.Fab")
		)
		(pad "1" smd rect
			(at -2.298 0)
			(size 0.8096 1.905)
			(layers "F.Cu" "F.Mask" "F.Paste")
			(net 702 "VDC")
			(pinfunction "1")
			(pintype "passive")
		)
		(pad "2" smd rect
			(at 2.297 0)
			(size 0.8096 1.905)
			(layers "F.Cu" "F.Mask" "F.Paste")
			(net 700 "/Power supply/USB_PD_VBUS")
			(pinfunction "2")
			(pintype "passive")
		)
	)
	(footprint "antmicro-footprints:R_0402_1005Metric"
		(layer "F.Cu")
		(at 170.7 152)
		(descr "Resistor SMD 0402")
		(tags "resistor SMD 0402")
		(property "Reference" "R35"
			(at -0.95 1.4 0)
			(layer "F.SilkS")
			(effects
				(font
					(size 0.7 0.7)
					(thickness 0.15)
				)
				(justify left bottom)
			)
		)
		(property "Value" "R_240R_0402"
			(at 0 1.4 0)
			(layer "F.Fab")
			(effects
				(font
					(size 0.7 0.7)
					(thickness 0.15)
				)
				(justify left bottom)
			)
		)
		(property "Description" "SMD Chip Resistor, 240 ohm, ± 1%, 63 mW, 0402 [1005 Metric], Thick Film, General Purpose"
			(at 0 0 0)
			(layer "F.Fab")
			(hide yes)
			(effects
				(font
					(size 1.27 1.27)
					(thickness 0.15)
				)
			)
		)
		(property "Author" "Antmicro"
			(at 0 0 0)
			(layer "F.Fab")
			(hide yes)
			(effects
				(font
					(size 1 1)
					(thickness 0.15)
				)
			)
		)
		(property "License" "Apache-2.0"
			(at 0 0 0)
			(layer "F.Fab")
			(hide yes)
			(effects
				(font
					(size 1 1)
					(thickness 0.15)
				)
			)
		)
		(property "MPN" "CR0402-FX-2400GLF"
			(at 0 0 0)
			(layer "F.Fab")
			(hide yes)
			(effects
				(font
					(size 1 1)
					(thickness 0.15)
				)
			)
		)
		(property "Manufacturer" "Bourns"
			(at 0 0 0)
			(layer "F.Fab")
			(hide yes)
			(effects
				(font
					(size 1 1)
					(thickness 0.15)
				)
			)
		)
		(property "Tolerance" "1%"
			(at 0 0 0)
			(layer "F.Fab")
			(hide yes)
			(effects
				(font
					(size 1 1)
					(thickness 0.15)
				)
			)
		)
		(property "Val" "240R"
			(at 0 0 0)
			(layer "F.Fab")
			(hide yes)
			(effects
				(font
					(size 1 1)
					(thickness 0.15)
				)
			)
		)
		(sheetname "DRAM + SRAM")
		(sheetfile "ram.kicad_sch")
		(attr smd)
		(fp_rect
			(start -0.925 -0.47)
			(end 0.925 0.47)
			(stroke
				(width 0.05)
				(type default)
			)
			(fill no)
			(layer "F.CrtYd")
		)
		(fp_rect
			(start -0.5 -0.25)
			(end 0.5 0.25)
			(stroke
				(width 0.15)
				(type solid)
			)
			(fill no)
			(layer "F.Fab")
		)
		(pad "1" smd roundrect
			(at -0.48 0)
			(size 0.59 0.64)
			(layers "F.Cu" "F.Mask" "F.Paste")
			(roundrect_rratio 0.25)
			(net 1 "GND")
			(pintype "passive")
		)
		(pad "2" smd roundrect
			(at 0.48 0)
			(size 0.59 0.64)
			(layers "F.Cu" "F.Mask" "F.Paste")
			(roundrect_rratio 0.25)
			(net 555 "/DRAM + SRAM/DDR_ZQ")
			(pintype "passive")
		)
	)
	(footprint "antmicro-footprints:R_0402_1005Metric"
		(layer "F.Cu")
		(at 214.88 154.7 90)
		(descr "Resistor SMD 0402")
		(tags "resistor SMD 0402")
		(property "Reference" "R73"
			(at 0.95 -0.33 270)
			(layer "F.SilkS")
			(effects
				(font
					(size 0.7 0.7)
					(thickness 0.15)
				)
				(justify left bottom)
			)
		)
		(property "Value" "R_100R_0402"
			(at 0 1.4 90)
			(layer "F.Fab")
			(effects
				(font
					(size 0.7 0.7)
					(thickness 0.15)
				)
				(justify left bottom)
			)
		)
		(property "Description" "SMD Chip Resistor, 100 ohm, ± 1%, 62.5 mW, 0402 [1005 Metric], Thick Film, General Purpose"
			(at 0 0 90)
			(layer "F.Fab")
			(hide yes)
			(effects
				(font
					(size 1.27 1.27)
					(thickness 0.15)
				)
			)
		)
		(property "Author" "Antmicro"
			(at 369.58 -60.18 0)
			(layer "F.Fab")
			(hide yes)
			(effects
				(font
					(size 1 1)
					(thickness 0.15)
				)
			)
		)
		(property "DNP" "DNP"
			(at 369.58 -60.18 0)
			(layer "F.Fab")
			(hide yes)
			(effects
				(font
					(size 1 1)
					(thickness 0.15)
				)
			)
		)
		(property "License" "Apache-2.0"
			(at 369.58 -60.18 0)
			(layer "F.Fab")
			(hide yes)
			(effects
				(font
					(size 1 1)
					(thickness 0.15)
				)
			)
		)
		(property "MPN" "CR0402-FX-1000GLF"
			(at 369.58 -60.18 0)
			(layer "F.Fab")
			(hide yes)
			(effects
				(font
					(size 1 1)
					(thickness 0.15)
				)
			)
		)
		(property "Manufacturer" "Bourns"
			(at 369.58 -60.18 0)
			(layer "F.Fab")
			(hide yes)
			(effects
				(font
					(size 1 1)
					(thickness 0.15)
				)
			)
		)
		(property "Tolerance" "1%"
			(at 369.58 -60.18 0)
			(layer "F.Fab")
			(hide yes)
			(effects
				(font
					(size 1 1)
					(thickness 0.15)
				)
			)
		)
		(property "Val" "100R"
			(at 369.58 -60.18 0)
			(layer "F.Fab")
			(hide yes)
			(effects
				(font
					(size 1 1)
					(thickness 0.15)
				)
			)
		)
		(property "dnp" ""
			(at 369.58 -60.18 0)
			(layer "F.Fab")
			(hide yes)
			(effects
				(font
					(size 1 1)
					(thickness 0.15)
				)
			)
		)
		(property "exclude_from_bom" ""
			(at 369.58 -60.18 0)
			(layer "F.Fab")
			(hide yes)
			(effects
				(font
					(size 1 1)
					(thickness 0.15)
				)
			)
		)
		(sheetname "SPI Flash + SD Card")
		(sheetfile "spi-flash.kicad_sch")
		(attr smd exclude_from_bom)
		(fp_rect
			(start -0.925 -0.47)
			(end 0.925 0.47)
			(stroke
				(width 0.05)
				(type default)
			)
			(fill no)
			(layer "F.CrtYd")
		)
		(fp_rect
			(start -0.5 -0.25)
			(end 0.5 0.25)
			(stroke
				(width 0.15)
				(type solid)
			)
			(fill no)
			(layer "F.Fab")
		)
		(pad "1" smd roundrect
			(at -0.48 0 90)
			(size 0.59 0.64)
			(layers "F.Cu" "F.Mask" "F.Paste")
			(roundrect_rratio 0.25)
			(net 1 "GND")
			(pintype "passive")
		)
		(pad "2" smd roundrect
			(at 0.48 0 90)
			(size 0.59 0.64)
			(layers "F.Cu" "F.Mask" "F.Paste")
			(roundrect_rratio 0.25)
			(net 408 "/FPGA Bank 33 & 34/USR_FLASH_0.CLK")
			(pintype "passive")
		)
	)
	(footprint "antmicro-footprints:C_0402_1005Metric"
		(layer "F.Cu")
		(at 153.8 146.65 -90)
		(descr "Capacitor SMD 0402")
		(tags "capacitor SMD 0402")
		(property "Reference" "C343"
			(at -3.65 -0.4 90)
			(layer "F.SilkS")
			(effects
				(font
					(size 0.7 0.7)
					(thickness 0.15)
				)
				(justify right bottom)
			)
		)
		(property "Value" "C_100n_0402"
			(at 0 1.4 90)
			(layer "F.Fab")
			(effects
				(font
					(size 0.7 0.7)
					(thickness 0.15)
				)
				(justify right bottom)
			)
		)
		(property "Description" "SMD Multilayer Ceramic Capacitor, 0.1 µF, 50 V, 0402 [1005 Metric], ± 10%, X5R, GRM Series"
			(at 0 0 270)
			(layer "F.Fab")
			(hide yes)
			(effects
				(font
					(size 1.27 1.27)
					(thickness 0.15)
				)
			)
		)
		(property "Author" "Antmicro"
			(at 7.15 300.45 0)
			(layer "F.Fab")
			(hide yes)
			(effects
				(font
					(size 1 1)
					(thickness 0.15)
				)
			)
		)
		(property "Dielectric" "X5R"
			(at 7.15 300.45 0)
			(layer "F.Fab")
			(hide yes)
			(effects
				(font
					(size 1 1)
					(thickness 0.15)
				)
			)
		)
		(property "License" "Apache-2.0"
			(at 7.15 300.45 0)
			(layer "F.Fab")
			(hide yes)
			(effects
				(font
					(size 1 1)
					(thickness 0.15)
				)
			)
		)
		(property "MPN" "GRM155R61H104KE14D"
			(at 7.15 300.45 0)
			(layer "F.Fab")
			(hide yes)
			(effects
				(font
					(size 1 1)
					(thickness 0.15)
				)
			)
		)
		(property "Manufacturer" "Murata"
			(at 7.15 300.45 0)
			(layer "F.Fab")
			(hide yes)
			(effects
				(font
					(size 1 1)
					(thickness 0.15)
				)
			)
		)
		(property "Val" "100n"
			(at 7.15 300.45 0)
			(layer "F.Fab")
			(hide yes)
			(effects
				(font
					(size 1 1)
					(thickness 0.15)
				)
			)
		)
		(property "Voltage" "50V"
			(at 7.15 300.45 0)
			(layer "F.Fab")
			(hide yes)
			(effects
				(font
					(size 1 1)
					(thickness 0.15)
				)
			)
		)
		(sheetname "DC-DC Converters")
		(sheetfile "dc-dc.kicad_sch")
		(attr smd)
		(fp_rect
			(start -0.925 -0.47)
			(end 0.925 0.47)
			(stroke
				(width 0.05)
				(type default)
			)
			(fill no)
			(layer "F.CrtYd")
		)
		(fp_line
			(start -0.494 0.248)
			(end -0.494 -0.25)
			(stroke
				(width 0.15)
				(type solid)
			)
			(layer "F.Fab")
		)
		(fp_line
			(start 0.504 0.248)
			(end -0.494 0.248)
			(stroke
				(width 0.15)
				(type solid)
			)
			(layer "F.Fab")
		)
		(fp_line
			(start -0.494 -0.25)
			(end 0.504 -0.25)
			(stroke
				(width 0.15)
				(type solid)
			)
			(layer "F.Fab")
		)
		(fp_line
			(start 0.504 -0.25)
			(end 0.504 0.248)
			(stroke
				(width 0.15)
				(type solid)
			)
			(layer "F.Fab")
		)
		(pad "1" smd roundrect
			(at -0.48 0 270)
			(size 0.59 0.64)
			(layers "F.Cu" "F.Mask" "F.Paste")
			(roundrect_rratio 0.25)
			(net 1 "GND")
			(pintype "passive")
		)
		(pad "2" smd roundrect
			(at 0.48 0 270)
			(size 0.59 0.64)
			(layers "F.Cu" "F.Mask" "F.Paste")
			(roundrect_rratio 0.25)
			(net 24 "+3V3")
			(pintype "passive")
		)
	)
	(footprint "antmicro-footprints:QFN-2L_1.6x1x0.55mm"
		(layer "F.Cu")
		(at 225.05 159.8)
		(property "Reference" "D14"
			(at -1.2 1.4 0)
			(layer "F.SilkS")
			(effects
				(font
					(size 0.7 0.7)
					(thickness 0.15)
				)
				(justify left bottom)
			)
		)
		(property "Value" "ESDA25P35-1U1M"
			(at 0 1.7 0)
			(layer "F.Fab")
			(effects
				(font
					(size 0.7 0.7)
					(thickness 0.15)
				)
				(justify left bottom)
			)
		)
		(property "Description" "Unidirectional TVS, 30 kV, QFN-2L, 22 V, 195 pF"
			(at 0 0 0)
			(layer "F.Fab")
			(hide yes)
			(effects
				(font
					(size 1.27 1.27)
					(thickness 0.15)
				)
			)
		)
		(property "Author" "Antmicro"
			(at 0 0 0)
			(layer "F.Fab")
			(hide yes)
			(effects
				(font
					(size 1 1)
					(thickness 0.15)
				)
			)
		)
		(property "License" "Apache-2.0"
			(at 0 0 0)
			(layer "F.Fab")
			(hide yes)
			(effects
				(font
					(size 1 1)
					(thickness 0.15)
				)
			)
		)
		(property "MPN" "ESDA25P35-1U1M"
			(at 0 0 0)
			(layer "F.Fab")
			(hide yes)
			(effects
				(font
					(size 1 1)
					(thickness 0.15)
				)
			)
		)
		(property "Manufacturer" "STMicroelectronics"
			(at 0 0 0)
			(layer "F.Fab")
			(hide yes)
			(effects
				(font
					(size 1 1)
					(thickness 0.15)
				)
			)
		)
		(property "Public" "False"
			(at 0 0 0)
			(layer "F.Fab")
			(hide yes)
			(effects
				(font
					(size 1 1)
					(thickness 0.15)
				)
			)
		)
		(sheetname "Power supply")
		(sheetfile "power-supply.kicad_sch")
		(attr smd)
		(fp_line
			(start -1.2 -0.4)
			(end -1.2 0.4)
			(stroke
				(width 0.15)
				(type solid)
			)
			(layer "F.SilkS")
		)
		(fp_line
			(start 0.27 -0.3)
			(end -0.27 -0.3)
			(stroke
				(width 0.15)
				(type solid)
			)
			(layer "F.SilkS")
		)
		(fp_line
			(start 0.27 0.3)
			(end -0.27 0.3)
			(stroke
				(width 0.15)
				(type solid)
			)
			(layer "F.SilkS")
		)
		(fp_rect
			(start 1.25 0.65)
			(end -1.25 -0.65)
			(stroke
				(width 0.05)
				(type solid)
			)
			(fill no)
			(layer "F.CrtYd")
		)
		(fp_line
			(start -0.199 -0.202)
			(end -0.199 0.1)
			(stroke
				(width 0.15)
				(type solid)
			)
			(layer "F.Fab")
		)
		(fp_line
			(start -0.199 0)
			(end -0.597 0)
			(stroke
				(width 0.15)
				(type solid)
			)
			(layer "F.Fab")
		)
		(fp_line
			(start -0.199 0.2)
			(end -0.199 0.1)
			(stroke
				(width 0.15)
				(type solid)
			)
			(layer "F.Fab")
		)
		(fp_line
			(start -0.101 0)
			(end 0.201 0.2)
			(stroke
				(width 0.15)
				(type solid)
			)
			(layer "F.Fab")
		)
		(fp_line
			(start 0.201 -0.202)
			(end -0.101 0)
			(stroke
				(width 0.15)
				(type solid)
			)
			(layer "F.Fab")
		)
		(fp_line
			(start 0.201 0)
			(end 0.201 -0.202)
			(stroke
				(width 0.15)
				(type solid)
			)
			(layer "F.Fab")
		)
		(fp_line
			(start 0.201 0.2)
			(end 0.201 0)
			(stroke
				(width 0.15)
				(type solid)
			)
			(layer "F.Fab")
		)
		(fp_line
			(start 0.599 0)
			(end 0.201 0)
			(stroke
				(width 0.15)
				(type solid)
			)
			(layer "F.Fab")
		)
		(fp_rect
			(start 0.848 0.4)
			(end -0.85 -0.402)
			(stroke
				(width 0.15)
				(type solid)
			)
			(fill no)
			(layer "F.Fab")
		)
		(pad "1" smd roundrect
			(at -0.7 0 180)
			(size 0.8 1)
			(layers "F.Cu" "F.Mask" "F.Paste")
			(roundrect_rratio 0.2)
			(net 700 "/Power supply/USB_PD_VBUS")
			(pinfunction "C")
			(pintype "passive")
		)
		(pad "2" smd roundrect
			(at 0.7 0 180)
			(size 0.8 1)
			(layers "F.Cu" "F.Mask" "F.Paste")
			(roundrect_rratio 0.2)
			(net 1 "GND")
			(pinfunction "A")
			(pintype "passive")
		)
	)
	(footprint "antmicro-footprints:R_0402_1005Metric"
		(layer "F.Cu")
		(at 173.570001 105.523751)
		(descr "Resistor SMD 0402")
		(tags "resistor SMD 0402")
		(property "Reference" "R271"
			(at 0.929999 0.376249 0)
			(layer "F.SilkS")
			(effects
				(font
					(size 0.7 0.7)
					(thickness 0.15)
				)
				(justify left bottom)
			)
		)
		(property "Value" "R_33R_0402"
			(at 0 1.4 0)
			(layer "F.Fab")
			(effects
				(font
					(size 0.7 0.7)
					(thickness 0.15)
				)
				(justify left bottom)
			)
		)
		(property "Description" "SMD Chip Resistor, 33 ohm, ± 1%, 62.5 mW, 0402 [1005 Metric], Thick Film, General Purpose"
			(at 0 0 0)
			(layer "F.Fab")
			(hide yes)
			(effects
				(font
					(size 1.27 1.27)
					(thickness 0.15)
				)
			)
		)
		(property "Author" "Antmicro"
			(at 0 0 0)
			(layer "F.Fab")
			(hide yes)
			(effects
				(font
					(size 1 1)
					(thickness 0.15)
				)
			)
		)
		(property "License" "Apache-2.0"
			(at 0 0 0)
			(layer "F.Fab")
			(hide yes)
			(effects
				(font
					(size 1 1)
					(thickness 0.15)
				)
			)
		)
		(property "MPN" "CR0402-FX-33R0GLF"
			(at 0 0 0)
			(layer "F.Fab")
			(hide yes)
			(effects
				(font
					(size 1 1)
					(thickness 0.15)
				)
			)
		)
		(property "Manufacturer" "Bourns"
			(at 0 0 0)
			(layer "F.Fab")
			(hide yes)
			(effects
				(font
					(size 1 1)
					(thickness 0.15)
				)
			)
		)
		(property "Tolerance" "1%"
			(at 0 0 0)
			(layer "F.Fab")
			(hide yes)
			(effects
				(font
					(size 1 1)
					(thickness 0.15)
				)
			)
		)
		(property "Val" "33R"
			(at 0 0 0)
			(layer "F.Fab")
			(hide yes)
			(effects
				(font
					(size 1 1)
					(thickness 0.15)
				)
			)
		)
		(sheetname "FMC+ HSPC")
		(sheetfile "fmc-hspc.kicad_sch")
		(attr smd)
		(fp_rect
			(start -0.925 -0.47)
			(end 0.925 0.47)
			(stroke
				(width 0.05)
				(type default)
			)
			(fill no)
			(layer "F.CrtYd")
		)
		(fp_rect
			(start -0.5 -0.25)
			(end 0.5 0.25)
			(stroke
				(width 0.15)
				(type solid)
			)
			(fill no)
			(layer "F.Fab")
		)
		(pad "1" smd roundrect
			(at -0.48 0)
			(size 0.59 0.64)
			(layers "F.Cu" "F.Mask" "F.Paste")
			(roundrect_rratio 0.25)
			(net 499 "/FMC+ HSPC/GTR_REFCLK1_R_P")
			(pintype "passive")
		)
		(pad "2" smd roundrect
			(at 0.48 0)
			(size 0.59 0.64)
			(layers "F.Cu" "F.Mask" "F.Paste")
			(roundrect_rratio 0.25)
			(net 591 "/FMC+ HSPC/GTX115.REFCLK1_P")
			(pintype "passive")
		)
	)
	(footprint "antmicro-footprints:R_0402_1005Metric"
		(layer "F.Cu")
		(at 158 184 -90)
		(descr "Resistor SMD 0402")
		(tags "resistor SMD 0402")
		(property "Reference" "R367"
			(at -0.7 -0.4 270)
			(layer "F.SilkS")
			(effects
				(font
					(size 0.7 0.7)
					(thickness 0.15)
				)
				(justify left bottom)
			)
		)
		(property "Value" "R_47k_0402"
			(at 0 1.4 270)
			(layer "F.Fab")
			(effects
				(font
					(size 0.7 0.7)
					(thickness 0.15)
				)
				(justify left bottom)
			)
		)
		(property "Description" "SMD Chip Resistor, 47 kohm, ± 1%, 62.5 mW, 0402 [1005 Metric], Thick Film, General Purpose"
			(at 0 0 270)
			(layer "F.Fab")
			(hide yes)
			(effects
				(font
					(size 1.27 1.27)
					(thickness 0.15)
				)
			)
		)
		(property "Author" "Antmicro"
			(at -26 342 0)
			(layer "F.Fab")
			(hide yes)
			(effects
				(font
					(size 1 1)
					(thickness 0.15)
				)
			)
		)
		(property "License" "Apache-2.0"
			(at -26 342 0)
			(layer "F.Fab")
			(hide yes)
			(effects
				(font
					(size 1 1)
					(thickness 0.15)
				)
			)
		)
		(property "MPN" "CR0402-FX-4702GLF"
			(at -26 342 0)
			(layer "F.Fab")
			(hide yes)
			(effects
				(font
					(size 1 1)
					(thickness 0.15)
				)
			)
		)
		(property "Manufacturer" "Bourns"
			(at -26 342 0)
			(layer "F.Fab")
			(hide yes)
			(effects
				(font
					(size 1 1)
					(thickness 0.15)
				)
			)
		)
		(property "Tolerance" "1%"
			(at -26 342 0)
			(layer "F.Fab")
			(hide yes)
			(effects
				(font
					(size 1 1)
					(thickness 0.15)
				)
			)
		)
		(property "Val" "47k"
			(at -26 342 0)
			(layer "F.Fab")
			(hide yes)
			(effects
				(font
					(size 1 1)
					(thickness 0.15)
				)
			)
		)
		(sheetname "DC-DC Converters")
		(sheetfile "dc-dc.kicad_sch")
		(attr smd)
		(fp_rect
			(start -0.925 -0.47)
			(end 0.925 0.47)
			(stroke
				(width 0.05)
				(type default)
			)
			(fill no)
			(layer "F.CrtYd")
		)
		(fp_rect
			(start -0.5 -0.25)
			(end 0.5 0.25)
			(stroke
				(width 0.15)
				(type solid)
			)
			(fill no)
			(layer "F.Fab")
		)
		(pad "1" smd roundrect
			(at -0.48 0 270)
			(size 0.59 0.64)
			(layers "F.Cu" "F.Mask" "F.Paste")
			(roundrect_rratio 0.25)
			(net 974 "/DC-DC Converters/~{PB_CTRL_IN}")
			(pintype "passive")
		)
		(pad "2" smd roundrect
			(at 0.48 0 270)
			(size 0.59 0.64)
			(layers "F.Cu" "F.Mask" "F.Paste")
			(roundrect_rratio 0.25)
			(net 37 "+3V3_AON")
			(pintype "passive")
		)
	)
	(footprint "antmicro-footprints:SOT-23-6"
		(layer "F.Cu")
		(at 189.425 183.798999 90)
		(property "Reference" "U9"
			(at 0.898999 -3.325 180)
			(layer "F.SilkS")
			(effects
				(font
					(size 0.7 0.7)
					(thickness 0.15)
				)
				(justify left bottom)
			)
		)
		(property "Value" "LTC4412IS6"
			(at -1.75 2.75 90)
			(layer "F.Fab")
			(effects
				(font
					(size 0.7 0.7)
					(thickness 0.15)
				)
				(justify left bottom)
			)
		)
		(property "Description" "Ideal diode controller"
			(at 0 0 90)
			(layer "F.Fab")
			(hide yes)
			(effects
				(font
					(size 1.27 1.27)
					(thickness 0.15)
				)
			)
		)
		(property "Author" "Antmicro"
			(at 373.223999 -5.626001 0)
			(layer "F.Fab")
			(hide yes)
			(effects
				(font
					(size 1 1)
					(thickness 0.15)
				)
			)
		)
		(property "License" "Apache-2.0"
			(at 373.223999 -5.626001 0)
			(layer "F.Fab")
			(hide yes)
			(effects
				(font
					(size 1 1)
					(thickness 0.15)
				)
			)
		)
		(property "MPN" "LTC4412IS6#TRMPBF"
			(at 373.223999 -5.626001 0)
			(layer "F.Fab")
			(hide yes)
			(effects
				(font
					(size 1 1)
					(thickness 0.15)
				)
			)
		)
		(property "Manufacturer" "Analog Devices"
			(at 373.223999 -5.626001 0)
			(layer "F.Fab")
			(hide yes)
			(effects
				(font
					(size 1 1)
					(thickness 0.15)
				)
			)
		)
		(sheetname "Power supply")
		(sheetfile "power-supply.kicad_sch")
		(attr smd)
		(fp_line
			(start 1.45 -0.7)
			(end 1.45 -0.4)
			(stroke
				(width 0.12)
				(type solid)
			)
			(layer "F.SilkS")
		)
		(fp_line
			(start 1.3 -0.7)
			(end 1.45 -0.7)
			(stroke
				(width 0.12)
				(type solid)
			)
			(layer "F.SilkS")
		)
		(fp_line
			(start -1.3 -0.7)
			(end -1.45 -0.7)
			(stroke
				(width 0.12)
				(type solid)
			)
			(layer "F.SilkS")
		)
		(fp_line
			(start -1.45 -0.7)
			(end -1.45 -0.4)
			(stroke
				(width 0.12)
				(type solid)
			)
			(layer "F.SilkS")
		)
		(fp_line
			(start 1.45 0.7)
			(end 1.45 0.4)
			(stroke
				(width 0.12)
				(type solid)
			)
			(layer "F.SilkS")
		)
		(fp_line
			(start 1.3 0.7)
			(end 1.45 0.7)
			(stroke
				(width 0.12)
				(type solid)
			)
			(layer "F.SilkS")
		)
		(fp_line
			(start -1.45 0.7)
			(end -1.45 0.4)
			(stroke
				(width 0.12)
				(type solid)
			)
			(layer "F.SilkS")
		)
		(fp_rect
			(start -1.55 -1.85)
			(end 1.55 1.75)
			(stroke
				(width 0.05)
				(type solid)
			)
			(fill no)
			(layer "F.CrtYd")
		)
		(fp_line
			(start 1.5 -0.7)
			(end 1.5 0.7)
			(stroke
				(width 0.1)
				(type solid)
			)
			(layer "F.Fab")
		)
		(fp_line
			(start -1.5 -0.7)
			(end 1.5 -0.7)
			(stroke
				(width 0.1)
				(type solid)
			)
			(layer "F.Fab")
		)
		(fp_line
			(start 1.5 0.7)
			(end -1.5 0.7)
			(stroke
				(width 0.1)
				(type solid)
			)
			(layer "F.Fab")
		)
		(fp_line
			(start -1.5 0.7)
			(end -1.5 -0.7)
			(stroke
				(width 0.1)
				(type solid)
			)
			(layer "F.Fab")
		)
		(fp_text user "."
			(at -1.4 1.2 270)
			(layer "F.SilkS")
			(effects
				(font
					(size 1 1)
					(thickness 0.15)
				)
			)
		)
		(pad "1" smd roundrect
			(at -0.954 1.1 90)
			(size 0.55 1)
			(layers "F.Cu" "F.Mask" "F.Paste")
			(roundrect_rratio 0.15)
			(net 4 "/Power supply/DC_IN")
			(pinfunction "IN")
			(pintype "power_in")
		)
		(pad "2" smd roundrect
			(at -0.003 1.1 90)
			(size 0.55 1)
			(layers "F.Cu" "F.Mask" "F.Paste")
			(roundrect_rratio 0.15)
			(net 1 "GND")
			(pinfunction "GND")
			(pintype "power_in")
		)
		(pad "3" smd roundrect
			(at 0.947 1.1 90)
			(size 0.55 1)
			(layers "F.Cu" "F.Mask" "F.Paste")
			(roundrect_rratio 0.15)
			(net 1 "GND")
			(pinfunction "CTL")
			(pintype "input")
		)
		(pad "4" smd roundrect
			(at 0.947 -1.214 90)
			(size 0.55 1)
			(layers "F.Cu" "F.Mask" "F.Paste")
			(roundrect_rratio 0.15)
			(net 1156 "unconnected-(U9-STAT-Pad4)")
			(pinfunction "STAT")
			(pintype "output+no_connect")
		)
		(pad "5" smd roundrect
			(at -0.003 -1.214 90)
			(size 0.55 1)
			(layers "F.Cu" "F.Mask" "F.Paste")
			(roundrect_rratio 0.15)
			(net 338 "Net-(Q5-G)")
			(pinfunction "GATE")
			(pintype "output")
		)
		(pad "6" smd roundrect
			(at -0.954 -1.214 90)
			(size 0.55 1)
			(layers "F.Cu" "F.Mask" "F.Paste")
			(roundrect_rratio 0.15)
			(net 702 "VDC")
			(pinfunction "SENSE")
			(pintype "input")
		)
	)
	(footprint "antmicro-footprints:LED_0603_1608Metric_B"
		(layer "F.Cu")
		(at 261.5 81.4)
		(descr "LED SMD 0603 Blue")
		(tags "LED SMD 0603 Blue")
		(property "Reference" "D25"
			(at -1.1 1.5 0)
			(layer "F.SilkS")
			(effects
				(font
					(size 0.7 0.7)
					(thickness 0.15)
				)
				(justify left bottom)
			)
		)
		(property "Value" "LED_B_0603_KP-1608QBC-D"
			(at 0 1.6 0)
			(layer "F.Fab")
			(effects
				(font
					(size 0.7 0.7)
					(thickness 0.15)
				)
				(justify left bottom)
			)
		)
		(property "Description" "LED, Blue, SMD, 0603, 20 mA, 3.3 V, 465 nm"
			(at 0 0 0)
			(layer "F.Fab")
			(hide yes)
			(effects
				(font
					(size 1.27 1.27)
					(thickness 0.15)
				)
			)
		)
		(property "Author" "Antmicro"
			(at 0 0 0)
			(layer "F.Fab")
			(hide yes)
			(effects
				(font
					(size 1 1)
					(thickness 0.15)
				)
			)
		)
		(property "Color" "Blue"
			(at 0 0 0)
			(layer "F.Fab")
			(hide yes)
			(effects
				(font
					(size 1 1)
					(thickness 0.15)
				)
			)
		)
		(property "License" "Apache-2.0"
			(at 0 0 0)
			(layer "F.Fab")
			(hide yes)
			(effects
				(font
					(size 1 1)
					(thickness 0.15)
				)
			)
		)
		(property "MPN" "KP-1608QBC-D"
			(at 0 0 0)
			(layer "F.Fab")
			(hide yes)
			(effects
				(font
					(size 1 1)
					(thickness 0.15)
				)
			)
		)
		(property "Manufacturer" "Kingbright"
			(at 0 0 0)
			(layer "F.Fab")
			(hide yes)
			(effects
				(font
					(size 1 1)
					(thickness 0.15)
				)
			)
		)
		(property "Public" "False"
			(at 0 0 0)
			(layer "F.Fab")
			(hide yes)
			(effects
				(font
					(size 1 1)
					(thickness 0.15)
				)
			)
		)
		(sheetname "User GPIO + LED + button + DIP switch")
		(sheetfile "user-gpio.kicad_sch")
		(attr smd)
		(fp_line
			(start -1.18 -0.319)
			(end -1.18 0.321)
			(stroke
				(width 0.15)
				(type solid)
			)
			(layer "F.SilkS")
		)
		(fp_line
			(start -0.094672 0.001008)
			(end -0.24 0.001008)
			(stroke
				(width 0.1)
				(type solid)
			)
			(layer "F.SilkS")
		)
		(fp_line
			(start -0.094672 0.001008)
			(end 0.105328 -0.198992)
			(stroke
				(width 0.1)
				(type solid)
			)
			(layer "F.SilkS")
		)
		(fp_line
			(start -0.094672 0.201008)
			(end -0.094672 -0.198992)
			(stroke
				(width 0.1)
				(type solid)
			)
			(layer "F.SilkS")
		)
		(fp_line
			(start 0.105328 0.001008)
			(end 0.24 0.001)
			(stroke
				(width 0.1)
				(type solid)
			)
			(layer "F.SilkS")
		)
		(fp_line
			(start 0.105328 0.201008)
			(end -0.094672 0.001008)
			(stroke
				(width 0.1)
				(type solid)
			)
			(layer "F.SilkS")
		)
		(fp_line
			(start 0.105328 0.201008)
			(end 0.105328 -0.198992)
			(stroke
				(width 0.1)
				(type solid)
			)
			(layer "F.SilkS")
		)
		(fp_line
			(start 0.22 -0.35)
			(end -0.22 -0.35)
			(stroke
				(width 0.15)
				(type solid)
			)
			(layer "F.SilkS")
		)
		(fp_line
			(start 0.22 0.35)
			(end -0.22 0.35)
			(stroke
				(width 0.15)
				(type solid)
			)
			(layer "F.SilkS")
		)
		(fp_rect
			(start 1.25 0.65)
			(end -1.25 -0.65)
			(stroke
				(width 0.05)
				(type solid)
			)
			(fill no)
			(layer "F.CrtYd")
		)
		(fp_line
			(start -0.199 -0.202)
			(end -0.199 0.1)
			(stroke
				(width 0.15)
				(type solid)
			)
			(layer "F.Fab")
		)
		(fp_line
			(start -0.199 0)
			(end -0.597 0)
			(stroke
				(width 0.15)
				(type solid)
			)
			(layer "F.Fab")
		)
		(fp_line
			(start -0.199 0.2)
			(end -0.199 0.1)
			(stroke
				(width 0.15)
				(type solid)
			)
			(layer "F.Fab")
		)
		(fp_line
			(start -0.101 0)
			(end 0.201 0.2)
			(stroke
				(width 0.15)
				(type solid)
			)
			(layer "F.Fab")
		)
		(fp_line
			(start 0.201 -0.202)
			(end -0.101 0)
			(stroke
				(width 0.15)
				(type solid)
			)
			(layer "F.Fab")
		)
		(fp_line
			(start 0.201 0)
			(end 0.201 -0.202)
			(stroke
				(width 0.15)
				(type solid)
			)
			(layer "F.Fab")
		)
		(fp_line
			(start 0.201 0.2)
			(end 0.201 0)
			(stroke
				(width 0.15)
				(type solid)
			)
			(layer "F.Fab")
		)
		(fp_line
			(start 0.599 0)
			(end 0.201 0)
			(stroke
				(width 0.15)
				(type solid)
			)
			(layer "F.Fab")
		)
		(fp_rect
			(start 0.848 0.4)
			(end -0.85 -0.402)
			(stroke
				(width 0.15)
				(type solid)
			)
			(fill no)
			(layer "F.Fab")
		)
		(pad "1" smd roundrect
			(at -0.7 0 180)
			(size 0.8 1)
			(layers "F.Cu" "F.Mask" "F.Paste")
			(roundrect_rratio 0.2)
			(net 787 "Net-(D25-C)")
			(pinfunction "C")
			(pintype "passive")
		)
		(pad "2" smd roundrect
			(at 0.7 0 180)
			(size 0.8 1)
			(layers "F.Cu" "F.Mask" "F.Paste")
			(roundrect_rratio 0.2)
			(net 789 "Net-(D25-A)")
			(pinfunction "A")
			(pintype "passive")
		)
	)
	(footprint "antmicro-footprints:R_0402_1005Metric"
		(layer "F.Cu")
		(at 244.15 106.8)
		(descr "Resistor SMD 0402")
		(tags "resistor SMD 0402")
		(property "Reference" "R259"
			(at 0.8 0.35 0)
			(layer "F.SilkS")
			(effects
				(font
					(size 0.7 0.7)
					(thickness 0.15)
				)
				(justify left bottom)
			)
		)
		(property "Value" "R_0R_0402"
			(at 0 1.4 0)
			(layer "F.Fab")
			(effects
				(font
					(size 0.7 0.7)
					(thickness 0.15)
				)
				(justify left bottom)
			)
		)
		(property "Description" "SMD Chip Resistor, Jumper, 0 ohm, 100 mW, 0402 [1005 Metric], Thick Film, General Purpose"
			(at 0 0 0)
			(layer "F.Fab")
			(hide yes)
			(effects
				(font
					(size 1.27 1.27)
					(thickness 0.15)
				)
			)
		)
		(property "Author" "Antmicro"
			(at 0 0 0)
			(layer "F.Fab")
			(hide yes)
			(effects
				(font
					(size 1 1)
					(thickness 0.15)
				)
			)
		)
		(property "Current" "1A"
			(at 0 0 0)
			(layer "F.Fab")
			(hide yes)
			(effects
				(font
					(size 1 1)
					(thickness 0.15)
				)
			)
		)
		(property "License" "Apache-2.0"
			(at 0 0 0)
			(layer "F.Fab")
			(hide yes)
			(effects
				(font
					(size 1 1)
					(thickness 0.15)
				)
			)
		)
		(property "MPN" "ERJ2GE0R00X"
			(at 0 0 0)
			(layer "F.Fab")
			(hide yes)
			(effects
				(font
					(size 1 1)
					(thickness 0.15)
				)
			)
		)
		(property "Manufacturer" "Panasonic"
			(at 0 0 0)
			(layer "F.Fab")
			(hide yes)
			(effects
				(font
					(size 1 1)
					(thickness 0.15)
				)
			)
		)
		(property "Tolerance" ""
			(at 0 0 0)
			(layer "F.Fab")
			(hide yes)
			(effects
				(font
					(size 1 1)
					(thickness 0.15)
				)
			)
		)
		(property "Val" "0R"
			(at 0 0 0)
			(layer "F.Fab")
			(hide yes)
			(effects
				(font
					(size 1 1)
					(thickness 0.15)
				)
			)
		)
		(sheetname "HDMI + Ethernet")
		(sheetfile "hdmi-ethernet.kicad_sch")
		(attr smd)
		(fp_rect
			(start -0.925 -0.47)
			(end 0.925 0.47)
			(stroke
				(width 0.05)
				(type default)
			)
			(fill no)
			(layer "F.CrtYd")
		)
		(fp_rect
			(start -0.5 -0.25)
			(end 0.5 0.25)
			(stroke
				(width 0.15)
				(type solid)
			)
			(fill no)
			(layer "F.Fab")
		)
		(pad "1" smd roundrect
			(at -0.48 0)
			(size 0.59 0.64)
			(layers "F.Cu" "F.Mask" "F.Paste")
			(roundrect_rratio 0.25)
			(net 529 "/FPGA Bank 16 & 17/HDMI.D0_N")
			(pintype "passive")
		)
		(pad "2" smd roundrect
			(at 0.48 0)
			(size 0.59 0.64)
			(layers "F.Cu" "F.Mask" "F.Paste")
			(roundrect_rratio 0.25)
			(net 862 "/HDMI + Ethernet/HDMI_CONN_D0_N")
			(pintype "passive")
		)
	)
	(footprint "antmicro-footprints:R_0603_1608Metric"
		(layer "F.Cu")
		(at 199.3 153.624 90)
		(descr "Resistor SMD 0603")
		(tags "resistor SMD 0603")
		(property "Reference" "R333"
			(at -1.416 1.44 90)
			(layer "F.SilkS")
			(effects
				(font
					(size 0.7 0.7)
					(thickness 0.15)
				)
				(justify left bottom)
			)
		)
		(property "Value" "R_0R_22.4A_0603"
			(at 0 1.6 90)
			(layer "F.Fab")
			(effects
				(font
					(size 0.7 0.7)
					(thickness 0.15)
				)
				(justify left bottom)
			)
		)
		(property "Description" "SMD Chip Resistor"
			(at 0 0 90)
			(layer "F.Fab")
			(hide yes)
			(effects
				(font
					(size 1.27 1.27)
					(thickness 0.15)
				)
			)
		)
		(property "Author" "Antmicro"
			(at 352.924 -45.676 0)
			(layer "F.Fab")
			(hide yes)
			(effects
				(font
					(size 1 1)
					(thickness 0.15)
				)
			)
		)
		(property "License" "Apache-2.0"
			(at 352.924 -45.676 0)
			(layer "F.Fab")
			(hide yes)
			(effects
				(font
					(size 1 1)
					(thickness 0.15)
				)
			)
		)
		(property "MPN" "PMR03EZPJ000"
			(at 352.924 -45.676 0)
			(layer "F.Fab")
			(hide yes)
			(effects
				(font
					(size 1 1)
					(thickness 0.15)
				)
			)
		)
		(property "Manufacturer" "ROHM Semiconductor"
			(at 352.924 -45.676 0)
			(layer "F.Fab")
			(hide yes)
			(effects
				(font
					(size 1 1)
					(thickness 0.15)
				)
			)
		)
		(property "Max. Curr." "22.4A"
			(at 352.924 -45.676 0)
			(layer "F.Fab")
			(hide yes)
			(effects
				(font
					(size 1 1)
					(thickness 0.15)
				)
			)
		)
		(property "Tolerance" "template_tolerance"
			(at 352.924 -45.676 0)
			(layer "F.Fab")
			(hide yes)
			(effects
				(font
					(size 1 1)
					(thickness 0.15)
				)
			)
		)
		(property "Val" "0R"
			(at 352.924 -45.676 0)
			(layer "F.Fab")
			(hide yes)
			(effects
				(font
					(size 1 1)
					(thickness 0.15)
				)
			)
		)
		(sheetname "DC-DC Converters")
		(sheetfile "dc-dc.kicad_sch")
		(attr smd)
		(fp_line
			(start -0.15 -0.4)
			(end 0.15 -0.4)
			(stroke
				(width 0.15)
				(type solid)
			)
			(layer "F.SilkS")
		)
		(fp_line
			(start -0.15 0.4)
			(end 0.15 0.4)
			(stroke
				(width 0.15)
				(type solid)
			)
			(layer "F.SilkS")
		)
		(fp_rect
			(start -1.25 -0.65)
			(end 1.25 0.65)
			(stroke
				(width 0.05)
				(type solid)
			)
			(fill no)
			(layer "F.CrtYd")
		)
		(fp_rect
			(start -0.8 -0.4)
			(end 0.8 0.4)
			(stroke
				(width 0.15)
				(type solid)
			)
			(fill no)
			(layer "F.Fab")
		)
		(pad "1" smd roundrect
			(at -0.7 0 90)
			(size 0.8 1)
			(layers "F.Cu" "F.Mask" "F.Paste")
			(roundrect_rratio 0.2)
			(net 751 "/DC-DC Converters/1V0_REG")
			(pintype "passive")
		)
		(pad "2" smd roundrect
			(at 0.7 0 90)
			(size 0.8 1)
			(layers "F.Cu" "F.Mask" "F.Paste")
			(roundrect_rratio 0.2)
			(net 650 "+1V0")
			(pintype "passive")
		)
	)
	(footprint "antmicro-footprints:FB_0805_2012Metric"
		(layer "F.Cu")
		(at 245 179)
		(descr "FERRITE BEAD 0805")
		(tags "FERRITE BEAD 0805")
		(property "Reference" "FB4"
			(at -1 1.9 0)
			(layer "F.SilkS")
			(effects
				(font
					(size 0.7 0.7)
					(thickness 0.15)
				)
				(justify left bottom)
			)
		)
		(property "Value" "FB_220Z_2A_Murata-BLM21PG_0805"
			(at 0 1.8 0)
			(layer "F.Fab")
			(effects
				(font
					(size 0.7 0.7)
					(thickness 0.15)
				)
				(justify left bottom)
			)
		)
		(property "Description" "Ferrite Bead, 0805 [2012 Metric], 220 ohm, 2 A, BLM21, 0.045 ohm, ± 25%, DC power line"
			(at 0 0 0)
			(layer "F.Fab")
			(hide yes)
			(effects
				(font
					(size 1.27 1.27)
					(thickness 0.15)
				)
			)
		)
		(property "Author" "Antmicro"
			(at 0 0 0)
			(layer "F.Fab")
			(hide yes)
			(effects
				(font
					(size 1 1)
					(thickness 0.15)
				)
			)
		)
		(property "Current" ""
			(at 0 0 0)
			(layer "F.Fab")
			(hide yes)
			(effects
				(font
					(size 1 1)
					(thickness 0.15)
				)
			)
		)
		(property "DNP" "DNP"
			(at 0 0 0)
			(layer "F.Fab")
			(hide yes)
			(effects
				(font
					(size 1 1)
					(thickness 0.15)
				)
			)
		)
		(property "License" "Apache-2.0"
			(at 0 0 0)
			(layer "F.Fab")
			(hide yes)
			(effects
				(font
					(size 1 1)
					(thickness 0.15)
				)
			)
		)
		(property "MPN" "BLM21PG221SN1D"
			(at 0 0 0)
			(layer "F.Fab")
			(hide yes)
			(effects
				(font
					(size 1 1)
					(thickness 0.15)
				)
			)
		)
		(property "Manufacturer" "Murata"
			(at 0 0 0)
			(layer "F.Fab")
			(hide yes)
			(effects
				(font
					(size 1 1)
					(thickness 0.15)
				)
			)
		)
		(property "Val" "220Z/2A"
			(at 0 0 0)
			(layer "F.Fab")
			(hide yes)
			(effects
				(font
					(size 1 1)
					(thickness 0.15)
				)
			)
		)
		(property "dnp" ""
			(at 0 0 0)
			(layer "F.Fab")
			(hide yes)
			(effects
				(font
					(size 1 1)
					(thickness 0.15)
				)
			)
		)
		(property "exclude_from_bom" ""
			(at 0 0 0)
			(layer "F.Fab")
			(hide yes)
			(effects
				(font
					(size 1 1)
					(thickness 0.15)
				)
			)
		)
		(sheetname "Power supply")
		(sheetfile "power-supply.kicad_sch")
		(attr smd exclude_from_bom)
		(fp_line
			(start -0.319 0.698)
			(end 0.281 0.698)
			(stroke
				(width 0.15)
				(type solid)
			)
			(layer "F.SilkS")
		)
		(fp_line
			(start -0.299 -0.698)
			(end 0.299 -0.698)
			(stroke
				(width 0.15)
				(type solid)
			)
			(layer "F.SilkS")
		)
		(fp_rect
			(start 1.95 -0.9)
			(end -1.95 0.9)
			(stroke
				(width 0.05)
				(type default)
			)
			(fill no)
			(layer "F.CrtYd")
		)
		(fp_line
			(start -0.948 -0.681)
			(end 0.948 -0.681)
			(stroke
				(width 0.15)
				(type solid)
			)
			(layer "F.Fab")
		)
		(fp_line
			(start -0.948 -0.676)
			(end -0.948 0.676)
			(stroke
				(width 0.15)
				(type solid)
			)
			(layer "F.Fab")
		)
		(fp_line
			(start -0.948 0.681)
			(end 0.948 0.681)
			(stroke
				(width 0.15)
				(type solid)
			)
			(layer "F.Fab")
		)
		(fp_line
			(start 0.948 -0.676)
			(end 0.948 0.676)
			(stroke
				(width 0.15)
				(type solid)
			)
			(layer "F.Fab")
		)
		(pad "1" smd roundrect
			(at -1.1 0)
			(size 1.2 1.3)
			(layers "F.Cu" "F.Mask" "F.Paste")
			(roundrect_rratio 0.25)
			(net 762 "Net-(D6-Pad1)")
			(pintype "passive")
		)
		(pad "2" smd roundrect
			(at 1.1 0)
			(size 1.2 1.3)
			(layers "F.Cu" "F.Mask" "F.Paste")
			(roundrect_rratio 0.25)
			(net 697 "/Power supply/VSS")
			(pintype "passive")
		)
	)
	(footprint "antmicro-footprints:C_0402_1005Metric"
		(layer "F.Cu")
		(at 207.353752 102.0365 90)
		(descr "Capacitor SMD 0402")
		(tags "capacitor SMD 0402")
		(property "Reference" "C256"
			(at -9.6635 6.546248 90)
			(layer "F.SilkS")
			(effects
				(font
					(size 0.7 0.7)
					(thickness 0.15)
				)
				(justify left bottom)
			)
		)
		(property "Value" "C_22p_0402"
			(at 0 1.4 90)
			(layer "F.Fab")
			(effects
				(font
					(size 0.7 0.7)
					(thickness 0.15)
				)
				(justify left bottom)
			)
		)
		(property "Description" "SMD Multilayer Ceramic Capacitor, 22 pF, 50 V, 0402 [1005 Metric], ± 5%, C0G / NP0, CC Series"
			(at 0 0 90)
			(layer "F.Fab")
			(hide yes)
			(effects
				(font
					(size 1.27 1.27)
					(thickness 0.15)
				)
			)
		)
		(property "Author" "Antmicro"
			(at 309.390252 -105.317252 0)
			(layer "F.Fab")
			(hide yes)
			(effects
				(font
					(size 1 1)
					(thickness 0.15)
				)
			)
		)
		(property "Dielectric" ""
			(at 309.390252 -105.317252 0)
			(layer "F.Fab")
			(hide yes)
			(effects
				(font
					(size 1 1)
					(thickness 0.15)
				)
			)
		)
		(property "License" "Apache-2.0"
			(at 309.390252 -105.317252 0)
			(layer "F.Fab")
			(hide yes)
			(effects
				(font
					(size 1 1)
					(thickness 0.15)
				)
			)
		)
		(property "MPN" "CC0402JRNPO9BN220"
			(at 309.390252 -105.317252 0)
			(layer "F.Fab")
			(hide yes)
			(effects
				(font
					(size 1 1)
					(thickness 0.15)
				)
			)
		)
		(property "Manufacturer" "YAGEO"
			(at 309.390252 -105.317252 0)
			(layer "F.Fab")
			(hide yes)
			(effects
				(font
					(size 1 1)
					(thickness 0.15)
				)
			)
		)
		(property "Val" "22p"
			(at 309.390252 -105.317252 0)
			(layer "F.Fab")
			(hide yes)
			(effects
				(font
					(size 1 1)
					(thickness 0.15)
				)
			)
		)
		(property "Voltage" ""
			(at 309.390252 -105.317252 0)
			(layer "F.Fab")
			(hide yes)
			(effects
				(font
					(size 1 1)
					(thickness 0.15)
				)
			)
		)
		(sheetname "HDMI + Ethernet")
		(sheetfile "hdmi-ethernet.kicad_sch")
		(attr smd)
		(fp_rect
			(start -0.925 -0.47)
			(end 0.925 0.47)
			(stroke
				(width 0.05)
				(type default)
			)
			(fill no)
			(layer "F.CrtYd")
		)
		(fp_line
			(start 0.504 -0.25)
			(end 0.504 0.248)
			(stroke
				(width 0.15)
				(type solid)
			)
			(layer "F.Fab")
		)
		(fp_line
			(start -0.494 -0.25)
			(end 0.504 -0.25)
			(stroke
				(width 0.15)
				(type solid)
			)
			(layer "F.Fab")
		)
		(fp_line
			(start 0.504 0.248)
			(end -0.494 0.248)
			(stroke
				(width 0.15)
				(type solid)
			)
			(layer "F.Fab")
		)
		(fp_line
			(start -0.494 0.248)
			(end -0.494 -0.25)
			(stroke
				(width 0.15)
				(type solid)
			)
			(layer "F.Fab")
		)
		(pad "1" smd roundrect
			(at -0.48 0 90)
			(size 0.59 0.64)
			(layers "F.Cu" "F.Mask" "F.Paste")
			(roundrect_rratio 0.25)
			(net 1 "GND")
			(pintype "passive")
		)
		(pad "2" smd roundrect
			(at 0.48 0 90)
			(size 0.59 0.64)
			(layers "F.Cu" "F.Mask" "F.Paste")
			(roundrect_rratio 0.25)
			(net 718 "/HDMI + Ethernet/GBE_XI")
			(pintype "passive")
		)
	)
	(footprint "antmicro-footprints:C_2220_5650Metric"
		(layer "F.Cu")
		(at 252.675 185.575 90)
		(descr "Capacitor SMD 2220")
		(tags "capacitor SMD 2220")
		(property "Reference" "C195"
			(at 3.675 -1.425 180)
			(layer "F.SilkS")
			(effects
				(font
					(size 0.7 0.7)
					(thickness 0.15)
				)
				(justify left bottom)
			)
		)
		(property "Value" "C_22u_100V_2220"
			(at 0 3.9 90)
			(layer "F.Fab")
			(effects
				(font
					(size 0.7 0.7)
					(thickness 0.15)
				)
				(justify left bottom)
			)
		)
		(property "Description" "SMT Multilayer Ceramic Capacitor, 22 µF, 100 V, 2220 [5750 Metric], ± 20%, X7S, C"
			(at 0 0 90)
			(layer "F.Fab")
			(hide yes)
			(effects
				(font
					(size 1.27 1.27)
					(thickness 0.15)
				)
			)
		)
		(property "Author" "Antmicro"
			(at 438.25 -67.1 0)
			(layer "F.Fab")
			(hide yes)
			(effects
				(font
					(size 1 1)
					(thickness 0.15)
				)
			)
		)
		(property "Dielectric" "X7S"
			(at 438.25 -67.1 0)
			(layer "F.Fab")
			(hide yes)
			(effects
				(font
					(size 1 1)
					(thickness 0.15)
				)
			)
		)
		(property "License" "Apache-2.0"
			(at 438.25 -67.1 0)
			(layer "F.Fab")
			(hide yes)
			(effects
				(font
					(size 1 1)
					(thickness 0.15)
				)
			)
		)
		(property "MPN" "C5750X7S2A226M280KB"
			(at 438.25 -67.1 0)
			(layer "F.Fab")
			(hide yes)
			(effects
				(font
					(size 1 1)
					(thickness 0.15)
				)
			)
		)
		(property "Manufacturer" "TDK"
			(at 438.25 -67.1 0)
			(layer "F.Fab")
			(hide yes)
			(effects
				(font
					(size 1 1)
					(thickness 0.15)
				)
			)
		)
		(property "Val" "22u"
			(at 438.25 -67.1 0)
			(layer "F.Fab")
			(hide yes)
			(effects
				(font
					(size 1 1)
					(thickness 0.15)
				)
			)
		)
		(property "Voltage" "100V"
			(at 438.25 -67.1 0)
			(layer "F.Fab")
			(hide yes)
			(effects
				(font
					(size 1 1)
					(thickness 0.15)
				)
			)
		)
		(sheetname "Power supply")
		(sheetfile "power-supply.kicad_sch")
		(attr smd)
		(fp_line
			(start -1.415 -2.61)
			(end 1.415 -2.61)
			(stroke
				(width 0.15)
				(type solid)
			)
			(layer "F.SilkS")
		)
		(fp_line
			(start -1.415 2.61)
			(end 1.415 2.61)
			(stroke
				(width 0.15)
				(type solid)
			)
			(layer "F.SilkS")
		)
		(fp_rect
			(start -3.7 -2.95)
			(end 3.7 2.95)
			(stroke
				(width 0.05)
				(type solid)
			)
			(fill no)
			(layer "F.CrtYd")
		)
		(fp_rect
			(start -2.85 -2.5)
			(end 2.85 2.5)
			(stroke
				(width 0.15)
				(type solid)
			)
			(fill no)
			(layer "F.Fab")
		)
		(pad "1" smd roundrect
			(at -2.55 0 90)
			(size 1.8 5.4)
			(layers "F.Cu" "F.Mask" "F.Paste")
			(roundrect_rratio 0.138889)
			(net 699 "GNDD")
			(pintype "passive")
		)
		(pad "2" smd roundrect
			(at 2.55 0 90)
			(size 1.8 5.4)
			(layers "F.Cu" "F.Mask" "F.Paste")
			(roundrect_rratio 0.138889)
			(net 698 "/Power supply/VDD")
			(pintype "passive")
		)
	)
	(footprint "antmicro-footprints:DFN3538"
		(layer "F.Cu")
		(at 240.8 174.5 180)
		(property "Reference" "D6"
			(at 0.7 -3.3 0)
			(unlocked yes)
			(layer "F.SilkS")
			(effects
				(font
					(size 0.7 0.7)
					(thickness 0.15)
				)
				(justify left bottom)
			)
		)
		(property "Value" "CD-MMBL110S"
			(at 0 3.5 180)
			(unlocked yes)
			(layer "F.Fab")
			(effects
				(font
					(size 0.7 0.7)
					(thickness 0.15)
				)
				(justify left bottom)
			)
		)
		(property "Description" "TVS diode"
			(at 0 0 180)
			(layer "F.Fab")
			(hide yes)
			(effects
				(font
					(size 1.27 1.27)
					(thickness 0.15)
				)
			)
		)
		(property "Author" "Antmicro"
			(at 481.6 349 0)
			(layer "F.Fab")
			(hide yes)
			(effects
				(font
					(size 1 1)
					(thickness 0.15)
				)
			)
		)
		(property "DNP" "DNP"
			(at 481.6 349 0)
			(layer "F.Fab")
			(hide yes)
			(effects
				(font
					(size 1 1)
					(thickness 0.15)
				)
			)
		)
		(property "License" "Apache-2.0"
			(at 481.6 349 0)
			(layer "F.Fab")
			(hide yes)
			(effects
				(font
					(size 1 1)
					(thickness 0.15)
				)
			)
		)
		(property "MPN" "CD-MMBL110S"
			(at 481.6 349 0)
			(layer "F.Fab")
			(hide yes)
			(effects
				(font
					(size 1 1)
					(thickness 0.15)
				)
			)
		)
		(property "Manufacturer" "Bourns"
			(at 481.6 349 0)
			(layer "F.Fab")
			(hide yes)
			(effects
				(font
					(size 1 1)
					(thickness 0.15)
				)
			)
		)
		(property "dnp" ""
			(at 481.6 349 0)
			(layer "F.Fab")
			(hide yes)
			(effects
				(font
					(size 1 1)
					(thickness 0.15)
				)
			)
		)
		(property "exclude_from_bom" ""
			(at 481.6 349 0)
			(layer "F.Fab")
			(hide yes)
			(effects
				(font
					(size 1 1)
					(thickness 0.15)
				)
			)
		)
		(sheetname "Power supply")
		(sheetfile "power-supply.kicad_sch")
		(attr smd exclude_from_bom)
		(fp_line
			(start 1.8 -2)
			(end 1.8 2.05)
			(stroke
				(width 0.15)
				(type solid)
			)
			(layer "F.SilkS")
		)
		(fp_line
			(start 1.6 2.05)
			(end 1.8 2.05)
			(stroke
				(width 0.15)
				(type solid)
			)
			(layer "F.SilkS")
		)
		(fp_line
			(start 1.6 -2)
			(end 1.8 -2)
			(stroke
				(width 0.15)
				(type solid)
			)
			(layer "F.SilkS")
		)
		(fp_line
			(start 0.9 -2.301)
			(end 0.598 -2.301)
			(stroke
				(width 0.15)
				(type solid)
			)
			(layer "F.SilkS")
		)
		(fp_line
			(start 0.748 -2.452)
			(end 0.748 -2.15)
			(stroke
				(width 0.15)
				(type solid)
			)
			(layer "F.SilkS")
		)
		(fp_line
			(start -0.902 -2.25)
			(end -0.6 -2.25)
			(stroke
				(width 0.15)
				(type solid)
			)
			(layer "F.SilkS")
		)
		(fp_line
			(start -0.95 2.05)
			(end 0.95 2.05)
			(stroke
				(width 0.15)
				(type solid)
			)
			(layer "F.SilkS")
		)
		(fp_line
			(start -0.95 -2)
			(end 0.95 -2)
			(stroke
				(width 0.15)
				(type solid)
			)
			(layer "F.SilkS")
		)
		(fp_line
			(start -1.8 2.05)
			(end -1.6 2.05)
			(stroke
				(width 0.15)
				(type solid)
			)
			(layer "F.SilkS")
		)
		(fp_line
			(start -1.8 -1.5)
			(end -1.8 2.05)
			(stroke
				(width 0.15)
				(type solid)
			)
			(layer "F.SilkS")
		)
		(fp_rect
			(start -2.1 -2.6)
			(end 2.1 2.6)
			(stroke
				(width 0.05)
				(type solid)
			)
			(fill no)
			(layer "F.CrtYd")
		)
		(fp_line
			(start -1.051 -2)
			(end -1.801 -1.25)
			(stroke
				(width 0.15)
				(type solid)
			)
			(layer "F.Fab")
		)
		(fp_rect
			(start 1.8 2.048)
			(end -1.8 -2)
			(stroke
				(width 0.15)
				(type solid)
			)
			(fill no)
			(layer "F.Fab")
		)
		(fp_text user "~"
			(at -0.31 2.59 180)
			(unlocked yes)
			(layer "F.SilkS")
			(effects
				(font
					(size 0.7 0.7)
					(thickness 0.15)
				)
				(justify left bottom)
			)
		)
		(pad "1" smd roundrect
			(at -1.27 -1.85 270)
			(size 1.4 0.48)
			(layers "F.Cu" "F.Mask" "F.Paste")
			(roundrect_rratio 0.25)
			(net 762 "Net-(D6-Pad1)")
			(pinfunction "1")
			(pintype "output")
		)
		(pad "2" smd roundrect
			(at 1.27 -1.85 270)
			(size 1.4 0.48)
			(layers "F.Cu" "F.Mask" "F.Paste")
			(roundrect_rratio 0.25)
			(net 763 "Net-(D6-Pad2)")
			(pinfunction "2")
			(pintype "output")
		)
		(pad "3" smd roundrect
			(at -1.27 1.85 270)
			(size 1.4 0.48)
			(layers "F.Cu" "F.Mask" "F.Paste")
			(roundrect_rratio 0.25)
			(net 765 "/HDMI + Ethernet/POE_ETH.VC2")
			(pinfunction "3")
			(pintype "input")
		)
		(pad "4" smd roundrect
			(at 1.27 1.85 270)
			(size 1.4 0.48)
			(layers "F.Cu" "F.Mask" "F.Paste")
			(roundrect_rratio 0.25)
			(net 764 "/HDMI + Ethernet/POE_ETH.VC1")
			(pinfunction "4")
			(pintype "input")
		)
	)
	(footprint "antmicro-footprints:R_0402_1005Metric"
		(layer "F.Cu")
		(at 235.915 121.5)
		(descr "Resistor SMD 0402")
		(tags "resistor SMD 0402")
		(property "Reference" "R71"
			(at 0.735 0.4 0)
			(layer "F.SilkS")
			(effects
				(font
					(size 0.7 0.7)
					(thickness 0.15)
				)
				(justify left bottom)
			)
		)
		(property "Value" "R_100R_0402"
			(at 0 1.4 0)
			(layer "F.Fab")
			(effects
				(font
					(size 0.7 0.7)
					(thickness 0.15)
				)
				(justify left bottom)
			)
		)
		(property "Description" "SMD Chip Resistor, 100 ohm, ± 1%, 62.5 mW, 0402 [1005 Metric], Thick Film, General Purpose"
			(at 0 0 0)
			(layer "F.Fab")
			(hide yes)
			(effects
				(font
					(size 1.27 1.27)
					(thickness 0.15)
				)
			)
		)
		(property "Author" "Antmicro"
			(at 0 0 0)
			(layer "F.Fab")
			(hide yes)
			(effects
				(font
					(size 1 1)
					(thickness 0.15)
				)
			)
		)
		(property "DNP" "DNP"
			(at 0 0 0)
			(layer "F.Fab")
			(hide yes)
			(effects
				(font
					(size 1 1)
					(thickness 0.15)
				)
			)
		)
		(property "License" "Apache-2.0"
			(at 0 0 0)
			(layer "F.Fab")
			(hide yes)
			(effects
				(font
					(size 1 1)
					(thickness 0.15)
				)
			)
		)
		(property "MPN" "CR0402-FX-1000GLF"
			(at 0 0 0)
			(layer "F.Fab")
			(hide yes)
			(effects
				(font
					(size 1 1)
					(thickness 0.15)
				)
			)
		)
		(property "Manufacturer" "Bourns"
			(at 0 0 0)
			(layer "F.Fab")
			(hide yes)
			(effects
				(font
					(size 1 1)
					(thickness 0.15)
				)
			)
		)
		(property "Tolerance" "1%"
			(at 0 0 0)
			(layer "F.Fab")
			(hide yes)
			(effects
				(font
					(size 1 1)
					(thickness 0.15)
				)
			)
		)
		(property "Val" "100R"
			(at 0 0 0)
			(layer "F.Fab")
			(hide yes)
			(effects
				(font
					(size 1 1)
					(thickness 0.15)
				)
			)
		)
		(property "dnp" ""
			(at 0 0 0)
			(layer "F.Fab")
			(hide yes)
			(effects
				(font
					(size 1 1)
					(thickness 0.15)
				)
			)
		)
		(property "exclude_from_bom" ""
			(at 0 0 0)
			(layer "F.Fab")
			(hide yes)
			(effects
				(font
					(size 1 1)
					(thickness 0.15)
				)
			)
		)
		(sheetname "SPI Flash + SD Card")
		(sheetfile "spi-flash.kicad_sch")
		(attr smd exclude_from_bom)
		(fp_rect
			(start -0.925 -0.47)
			(end 0.925 0.47)
			(stroke
				(width 0.05)
				(type default)
			)
			(fill no)
			(layer "F.CrtYd")
		)
		(fp_rect
			(start -0.5 -0.25)
			(end 0.5 0.25)
			(stroke
				(width 0.15)
				(type solid)
			)
			(fill no)
			(layer "F.Fab")
		)
		(pad "1" smd roundrect
			(at -0.48 0)
			(size 0.59 0.64)
			(layers "F.Cu" "F.Mask" "F.Paste")
			(roundrect_rratio 0.25)
			(net 1 "GND")
			(pintype "passive")
		)
		(pad "2" smd roundrect
			(at 0.48 0)
			(size 0.59 0.64)
			(layers "F.Cu" "F.Mask" "F.Paste")
			(roundrect_rratio 0.25)
			(net 56 "/FPGA Bank 14 & 15/SYSTEM_FLASH.CLK")
			(pintype "passive")
		)
	)
	(footprint "antmicro-footprints:R_0402_1005Metric"
		(layer "F.Cu")
		(at 225.1 112.2)
		(descr "Resistor SMD 0402")
		(tags "resistor SMD 0402")
		(property "Reference" "R99"
			(at -3.65 0.4 0)
			(layer "F.SilkS")
			(effects
				(font
					(size 0.7 0.7)
					(thickness 0.15)
				)
				(justify left bottom)
			)
		)
		(property "Value" "R_0R_0402"
			(at 0 1.4 0)
			(layer "F.Fab")
			(effects
				(font
					(size 0.7 0.7)
					(thickness 0.15)
				)
				(justify left bottom)
			)
		)
		(property "Description" "SMD Chip Resistor, Jumper, 0 ohm, 100 mW, 0402 [1005 Metric], Thick Film, General Purpose"
			(at 0 0 0)
			(layer "F.Fab")
			(hide yes)
			(effects
				(font
					(size 1.27 1.27)
					(thickness 0.15)
				)
			)
		)
		(property "Author" "Antmicro"
			(at 0 0 0)
			(layer "F.Fab")
			(hide yes)
			(effects
				(font
					(size 1 1)
					(thickness 0.15)
				)
			)
		)
		(property "Current" "1A"
			(at 0 0 0)
			(layer "F.Fab")
			(hide yes)
			(effects
				(font
					(size 1 1)
					(thickness 0.15)
				)
			)
		)
		(property "License" "Apache-2.0"
			(at 0 0 0)
			(layer "F.Fab")
			(hide yes)
			(effects
				(font
					(size 1 1)
					(thickness 0.15)
				)
			)
		)
		(property "MPN" "ERJ2GE0R00X"
			(at 0 0 0)
			(layer "F.Fab")
			(hide yes)
			(effects
				(font
					(size 1 1)
					(thickness 0.15)
				)
			)
		)
		(property "Manufacturer" "Panasonic"
			(at 0 0 0)
			(layer "F.Fab")
			(hide yes)
			(effects
				(font
					(size 1 1)
					(thickness 0.15)
				)
			)
		)
		(property "Tolerance" ""
			(at 0 0 0)
			(layer "F.Fab")
			(hide yes)
			(effects
				(font
					(size 1 1)
					(thickness 0.15)
				)
			)
		)
		(property "Val" "0R"
			(at 0 0 0)
			(layer "F.Fab")
			(hide yes)
			(effects
				(font
					(size 1 1)
					(thickness 0.15)
				)
			)
		)
		(sheetname "SPI Flash + SD Card")
		(sheetfile "spi-flash.kicad_sch")
		(attr smd)
		(fp_rect
			(start -0.925 -0.47)
			(end 0.925 0.47)
			(stroke
				(width 0.05)
				(type default)
			)
			(fill no)
			(layer "F.CrtYd")
		)
		(fp_rect
			(start -0.5 -0.25)
			(end 0.5 0.25)
			(stroke
				(width 0.15)
				(type solid)
			)
			(fill no)
			(layer "F.Fab")
		)
		(pad "1" smd roundrect
			(at -0.48 0)
			(size 0.59 0.64)
			(layers "F.Cu" "F.Mask" "F.Paste")
			(roundrect_rratio 0.25)
			(net 420 "/FPGA Bank 16 & 17/USR_FLASH_1.~{CS}")
			(pintype "passive")
		)
		(pad "2" smd roundrect
			(at 0.48 0)
			(size 0.59 0.64)
			(layers "F.Cu" "F.Mask" "F.Paste")
			(roundrect_rratio 0.25)
			(net 906 "/SPI Flash + SD Card/USR_FLASH_1_~{CS}")
			(pintype "passive")
		)
	)
	(footprint "antmicro-footprints:C_0402_1005Metric"
		(layer "F.Cu")
		(at 232.6 137.1)
		(descr "Capacitor SMD 0402")
		(tags "capacitor SMD 0402")
		(property "Reference" "C367"
			(at -1.35 -0.55 0)
			(layer "F.SilkS")
			(effects
				(font
					(size 0.7 0.7)
					(thickness 0.15)
				)
				(justify left bottom)
			)
		)
		(property "Value" "C_22p_0402"
			(at 0 1.4 0)
			(layer "F.Fab")
			(effects
				(font
					(size 0.7 0.7)
					(thickness 0.15)
				)
				(justify left bottom)
			)
		)
		(property "Description" "SMD Multilayer Ceramic Capacitor, 22 pF, 50 V, 0402 [1005 Metric], ± 5%, C0G / NP0, CC Series"
			(at 0 0 0)
			(layer "F.Fab")
			(hide yes)
			(effects
				(font
					(size 1.27 1.27)
					(thickness 0.15)
				)
			)
		)
		(property "Author" "Antmicro"
			(at 0 0 0)
			(layer "F.Fab")
			(hide yes)
			(effects
				(font
					(size 1 1)
					(thickness 0.15)
				)
			)
		)
		(property "Dielectric" ""
			(at 0 0 0)
			(layer "F.Fab")
			(hide yes)
			(effects
				(font
					(size 1 1)
					(thickness 0.15)
				)
			)
		)
		(property "License" "Apache-2.0"
			(at 0 0 0)
			(layer "F.Fab")
			(hide yes)
			(effects
				(font
					(size 1 1)
					(thickness 0.15)
				)
			)
		)
		(property "MPN" "CC0402JRNPO9BN220"
			(at 0 0 0)
			(layer "F.Fab")
			(hide yes)
			(effects
				(font
					(size 1 1)
					(thickness 0.15)
				)
			)
		)
		(property "Manufacturer" "YAGEO"
			(at 0 0 0)
			(layer "F.Fab")
			(hide yes)
			(effects
				(font
					(size 1 1)
					(thickness 0.15)
				)
			)
		)
		(property "Val" "22p"
			(at 0 0 0)
			(layer "F.Fab")
			(hide yes)
			(effects
				(font
					(size 1 1)
					(thickness 0.15)
				)
			)
		)
		(property "Voltage" ""
			(at 0 0 0)
			(layer "F.Fab")
			(hide yes)
			(effects
				(font
					(size 1 1)
					(thickness 0.15)
				)
			)
		)
		(sheetname "Clocks")
		(sheetfile "clocks.kicad_sch")
		(attr smd)
		(fp_rect
			(start -0.925 -0.47)
			(end 0.925 0.47)
			(stroke
				(width 0.05)
				(type default)
			)
			(fill no)
			(layer "F.CrtYd")
		)
		(fp_line
			(start -0.494 -0.25)
			(end 0.504 -0.25)
			(stroke
				(width 0.15)
				(type solid)
			)
			(layer "F.Fab")
		)
		(fp_line
			(start -0.494 0.248)
			(end -0.494 -0.25)
			(stroke
				(width 0.15)
				(type solid)
			)
			(layer "F.Fab")
		)
		(fp_line
			(start 0.504 -0.25)
			(end 0.504 0.248)
			(stroke
				(width 0.15)
				(type solid)
			)
			(layer "F.Fab")
		)
		(fp_line
			(start 0.504 0.248)
			(end -0.494 0.248)
			(stroke
				(width 0.15)
				(type solid)
			)
			(layer "F.Fab")
		)
		(pad "1" smd roundrect
			(at -0.48 0)
			(size 0.59 0.64)
			(layers "F.Cu" "F.Mask" "F.Paste")
			(roundrect_rratio 0.25)
			(net 1 "GND")
			(pintype "passive")
		)
		(pad "2" smd roundrect
			(at 0.48 0)
			(size 0.59 0.64)
			(layers "F.Cu" "F.Mask" "F.Paste")
			(roundrect_rratio 0.25)
			(net 753 "/Clocks/PLL_XO")
			(pintype "passive")
		)
	)
	(footprint "antmicro-footprints:C_2220_5650Metric"
		(layer "F.Cu")
		(at 246.475 185.575 90)
		(descr "Capacitor SMD 2220")
		(tags "capacitor SMD 2220")
		(property "Reference" "C197"
			(at 3.675 -1.425 180)
			(layer "F.SilkS")
			(effects
				(font
					(size 0.7 0.7)
					(thickness 0.15)
				)
				(justify left bottom)
			)
		)
		(property "Value" "C_22u_100V_2220"
			(at 0 3.9 90)
			(layer "F.Fab")
			(effects
				(font
					(size 0.7 0.7)
					(thickness 0.15)
				)
				(justify left bottom)
			)
		)
		(property "Description" "SMT Multilayer Ceramic Capacitor, 22 µF, 100 V, 2220 [5750 Metric], ± 20%, X7S, C"
			(at 0 0 90)
			(layer "F.Fab")
			(hide yes)
			(effects
				(font
					(size 1.27 1.27)
					(thickness 0.15)
				)
			)
		)
		(property "Author" "Antmicro"
			(at 432.05 -60.9 0)
			(layer "F.Fab")
			(hide yes)
			(effects
				(font
					(size 1 1)
					(thickness 0.15)
				)
			)
		)
		(property "Dielectric" "X7S"
			(at 432.05 -60.9 0)
			(layer "F.Fab")
			(hide yes)
			(effects
				(font
					(size 1 1)
					(thickness 0.15)
				)
			)
		)
		(property "License" "Apache-2.0"
			(at 432.05 -60.9 0)
			(layer "F.Fab")
			(hide yes)
			(effects
				(font
					(size 1 1)
					(thickness 0.15)
				)
			)
		)
		(property "MPN" "C5750X7S2A226M280KB"
			(at 432.05 -60.9 0)
			(layer "F.Fab")
			(hide yes)
			(effects
				(font
					(size 1 1)
					(thickness 0.15)
				)
			)
		)
		(property "Manufacturer" "TDK"
			(at 432.05 -60.9 0)
			(layer "F.Fab")
			(hide yes)
			(effects
				(font
					(size 1 1)
					(thickness 0.15)
				)
			)
		)
		(property "Val" "22u"
			(at 432.05 -60.9 0)
			(layer "F.Fab")
			(hide yes)
			(effects
				(font
					(size 1 1)
					(thickness 0.15)
				)
			)
		)
		(property "Voltage" "100V"
			(at 432.05 -60.9 0)
			(layer "F.Fab")
			(hide yes)
			(effects
				(font
					(size 1 1)
					(thickness 0.15)
				)
			)
		)
		(sheetname "Power supply")
		(sheetfile "power-supply.kicad_sch")
		(attr smd)
		(fp_line
			(start -1.415 -2.61)
			(end 1.415 -2.61)
			(stroke
				(width 0.15)
				(type solid)
			)
			(layer "F.SilkS")
		)
		(fp_line
			(start -1.415 2.61)
			(end 1.415 2.61)
			(stroke
				(width 0.15)
				(type solid)
			)
			(layer "F.SilkS")
		)
		(fp_rect
			(start -3.7 -2.95)
			(end 3.7 2.95)
			(stroke
				(width 0.05)
				(type solid)
			)
			(fill no)
			(layer "F.CrtYd")
		)
		(fp_rect
			(start -2.85 -2.5)
			(end 2.85 2.5)
			(stroke
				(width 0.15)
				(type solid)
			)
			(fill no)
			(layer "F.Fab")
		)
		(pad "1" smd roundrect
			(at -2.55 0 90)
			(size 1.8 5.4)
			(layers "F.Cu" "F.Mask" "F.Paste")
			(roundrect_rratio 0.138889)
			(net 699 "GNDD")
			(pintype "passive")
		)
		(pad "2" smd roundrect
			(at 2.55 0 90)
			(size 1.8 5.4)
			(layers "F.Cu" "F.Mask" "F.Paste")
			(roundrect_rratio 0.138889)
			(net 698 "/Power supply/VDD")
			(pintype "passive")
		)
	)
	(footprint "antmicro-footprints:C_0603_1608Metric"
		(layer "F.Cu")
		(at 195.6 156.849)
		(descr "Capacitor SMD 0603")
		(tags "capacitor 0603")
		(property "Reference" "C357"
			(at -3.89 0.401 0)
			(layer "F.SilkS")
			(effects
				(font
					(size 0.7 0.7)
					(thickness 0.15)
				)
				(justify left bottom)
			)
		)
		(property "Value" "C_22u_0603"
			(at 0 1.6 0)
			(layer "F.Fab")
			(effects
				(font
					(size 0.7 0.7)
					(thickness 0.15)
				)
				(justify left bottom)
			)
		)
		(property "Description" "SMD Multilayer Ceramic Capacitor, 22 µF, 6.3 V, 0603 [1608 Metric], ± 20%, X5R, GRM Series"
			(at 0 0 0)
			(layer "F.Fab")
			(hide yes)
			(effects
				(font
					(size 1.27 1.27)
					(thickness 0.15)
				)
			)
		)
		(property "Author" "Antmicro"
			(at 0 0 0)
			(layer "F.Fab")
			(hide yes)
			(effects
				(font
					(size 1 1)
					(thickness 0.15)
				)
			)
		)
		(property "Dielectric" ""
			(at 0 0 0)
			(layer "F.Fab")
			(hide yes)
			(effects
				(font
					(size 1 1)
					(thickness 0.15)
				)
			)
		)
		(property "License" "Apache-2.0"
			(at 0 0 0)
			(layer "F.Fab")
			(hide yes)
			(effects
				(font
					(size 1 1)
					(thickness 0.15)
				)
			)
		)
		(property "MPN" "GRM188R60J226MEA0D"
			(at 0 0 0)
			(layer "F.Fab")
			(hide yes)
			(effects
				(font
					(size 1 1)
					(thickness 0.15)
				)
			)
		)
		(property "Manufacturer" "Murata"
			(at 0 0 0)
			(layer "F.Fab")
			(hide yes)
			(effects
				(font
					(size 1 1)
					(thickness 0.15)
				)
			)
		)
		(property "Val" "22u"
			(at 0 0 0)
			(layer "F.Fab")
			(hide yes)
			(effects
				(font
					(size 1 1)
					(thickness 0.15)
				)
			)
		)
		(property "Voltage" ""
			(at 0 0 0)
			(layer "F.Fab")
			(hide yes)
			(effects
				(font
					(size 1 1)
					(thickness 0.15)
				)
			)
		)
		(sheetname "DC-DC Converters")
		(sheetfile "dc-dc.kicad_sch")
		(attr smd)
		(fp_line
			(start -0.15 -0.4)
			(end 0.15 -0.4)
			(stroke
				(width 0.15)
				(type solid)
			)
			(layer "F.SilkS")
		)
		(fp_line
			(start -0.15 0.4)
			(end 0.15 0.4)
			(stroke
				(width 0.15)
				(type solid)
			)
			(layer "F.SilkS")
		)
		(fp_rect
			(start -1.25 -0.65)
			(end 1.25 0.65)
			(stroke
				(width 0.05)
				(type solid)
			)
			(fill no)
			(layer "F.CrtYd")
		)
		(fp_rect
			(start -0.8 -0.4)
			(end 0.8 0.4)
			(stroke
				(width 0.15)
				(type solid)
			)
			(fill no)
			(layer "F.Fab")
		)
		(pad "1" smd roundrect
			(at -0.7 0)
			(size 0.8 1)
			(layers "F.Cu" "F.Mask" "F.Paste")
			(roundrect_rratio 0.2)
			(net 1 "GND")
			(pintype "passive")
		)
		(pad "2" smd roundrect
			(at 0.7 0)
			(size 0.8 1)
			(layers "F.Cu" "F.Mask" "F.Paste")
			(roundrect_rratio 0.2)
			(net 751 "/DC-DC Converters/1V0_REG")
			(pintype "passive")
		)
	)
	(footprint "antmicro-footprints:QSOP-16_3.9x4.9mm_P0.635mm"
		(layer "F.Cu")
		(at 219.8 162.3 180)
		(descr "16-Lead Plastic Shrink Small Outline Narrow Body (QR)-.150\" Body [QSOP] (see Microchip Packaging Specification 00000049BS.pdf)")
		(tags "SSOP 0.635")
		(property "Reference" "U3"
			(at -1.97 2.93 180)
			(layer "F.SilkS")
			(effects
				(font
					(size 0.7 0.7)
					(thickness 0.15)
				)
				(justify left bottom)
			)
		)
		(property "Value" "MAX1617AMEE+T"
			(at -8.22 3.67 180)
			(layer "F.Fab")
			(effects
				(font
					(size 0.7 0.7)
					(thickness 0.15)
				)
				(justify left bottom)
			)
		)
		(property "Description" "Temperature sensor"
			(at 0 0 180)
			(layer "F.Fab")
			(hide yes)
			(effects
				(font
					(size 1.27 1.27)
					(thickness 0.15)
				)
			)
		)
		(property "Author" "Antmicro"
			(at 439.6 324.6 0)
			(layer "F.Fab")
			(hide yes)
			(effects
				(font
					(size 1 1)
					(thickness 0.15)
				)
			)
		)
		(property "License" "Apache-2.0"
			(at 439.6 324.6 0)
			(layer "F.Fab")
			(hide yes)
			(effects
				(font
					(size 1 1)
					(thickness 0.15)
				)
			)
		)
		(property "MPN" "MAX1617AMEE+T"
			(at 439.6 324.6 0)
			(layer "F.Fab")
			(hide yes)
			(effects
				(font
					(size 1 1)
					(thickness 0.15)
				)
			)
		)
		(property "Manufacturer" "Maxim Integrated Products"
			(at 439.6 324.6 0)
			(layer "F.Fab")
			(hide yes)
			(effects
				(font
					(size 1 1)
					(thickness 0.15)
				)
			)
		)
		(sheetname "FPGA Config")
		(sheetfile "fpga-config.kicad_sch")
		(attr smd)
		(fp_line
			(start -1.835 -2.73)
			(end 1.874 -2.73)
			(stroke
				(width 0.15)
				(type solid)
			)
			(layer "F.SilkS")
		)
		(fp_line
			(start -1.855 2.672)
			(end 1.854 2.672)
			(stroke
				(width 0.15)
				(type solid)
			)
			(layer "F.SilkS")
		)
		(fp_circle
			(center -2.657 -2.73)
			(end -2.606 -2.73)
			(stroke
				(width 0.15)
				(type solid)
			)
			(fill yes)
			(layer "F.SilkS")
		)
		(fp_rect
			(start -3.5 -2.952)
			(end 3.499 2.95)
			(stroke
				(width 0.05)
				(type solid)
			)
			(fill no)
			(layer "F.CrtYd")
		)
		(fp_line
			(start 1.949 2.45)
			(end -1.95 2.45)
			(stroke
				(width 0.15)
				(type solid)
			)
			(layer "F.Fab")
		)
		(fp_line
			(start 1.949 -2.452)
			(end 1.949 2.45)
			(stroke
				(width 0.15)
				(type solid)
			)
			(layer "F.Fab")
		)
		(fp_line
			(start -0.951 -2.452)
			(end 1.949 -2.452)
			(stroke
				(width 0.15)
				(type solid)
			)
			(layer "F.Fab")
		)
		(fp_line
			(start -1.95 2.45)
			(end -1.95 -1.45)
			(stroke
				(width 0.15)
				(type solid)
			)
			(layer "F.Fab")
		)
		(fp_line
			(start -1.95 -1.45)
			(end -0.951 -2.452)
			(stroke
				(width 0.15)
				(type solid)
			)
			(layer "F.Fab")
		)
		(pad "1" smd rect
			(at -2.656 -2.223 180)
			(size 1.6 0.41)
			(layers "F.Cu" "F.Mask" "F.Paste")
			(net 1058 "unconnected-(U3-NC-Pad1)")
			(pinfunction "NC")
			(pintype "no_connect")
		)
		(pad "2" smd rect
			(at -2.656 -1.589 180)
			(size 1.6 0.41)
			(layers "F.Cu" "F.Mask" "F.Paste")
			(net 24 "+3V3")
			(pinfunction "VCC")
			(pintype "power_in")
		)
		(pad "3" smd rect
			(at -2.656 -0.954 180)
			(size 1.6 0.41)
			(layers "F.Cu" "F.Mask" "F.Paste")
			(net 10 "/FPGA Config/FPGA_CFG_DXP")
			(pinfunction "DXP")
			(pintype "input")
		)
		(pad "4" smd rect
			(at -2.656 -0.318 180)
			(size 1.6 0.41)
			(layers "F.Cu" "F.Mask" "F.Paste")
			(net 9 "/FPGA Config/FPGA_CFG_DXN")
			(pinfunction "DXN")
			(pintype "input")
		)
		(pad "5" smd rect
			(at -2.656 0.315 180)
			(size 1.6 0.41)
			(layers "F.Cu" "F.Mask" "F.Paste")
			(net 1059 "unconnected-(U3-NC-Pad5)")
			(pinfunction "NC")
			(pintype "no_connect")
		)
		(pad "6" smd rect
			(at -2.656 0.951 180)
			(size 1.6 0.41)
			(layers "F.Cu" "F.Mask" "F.Paste")
			(net 1 "GND")
			(pinfunction "ADD1")
			(pintype "input")
		)
		(pad "7" smd rect
			(at -2.656 1.586 180)
			(size 1.6 0.41)
			(layers "F.Cu" "F.Mask" "F.Paste")
			(net 1 "GND")
			(pinfunction "GND")
			(pintype "power_in")
		)
		(pad "8" smd rect
			(at -2.656 2.221 180)
			(size 1.6 0.41)
			(layers "F.Cu" "F.Mask" "F.Paste")
			(net 1 "GND")
			(pinfunction "GND")
			(pintype "passive")
		)
		(pad "9" smd rect
			(at 2.652 2.221 180)
			(size 1.6 0.41)
			(layers "F.Cu" "F.Mask" "F.Paste")
			(net 1119 "unconnected-(U3-NC-Pad9)")
			(pinfunction "NC")
			(pintype "no_connect")
		)
		(pad "10" smd rect
			(at 2.652 1.586 180)
			(size 1.6 0.41)
			(layers "F.Cu" "F.Mask" "F.Paste")
			(net 1 "GND")
			(pinfunction "ADD0")
			(pintype "input")
		)
		(pad "11" smd rect
			(at 2.652 0.951 180)
			(size 1.6 0.41)
			(layers "F.Cu" "F.Mask" "F.Paste")
			(net 113 "/FPGA Config/TEMP_~{ALERT}")
			(pinfunction "~{ALERT}")
			(pintype "output")
		)
		(pad "12" smd rect
			(at 2.652 0.315 180)
			(size 1.6 0.41)
			(layers "F.Cu" "F.Mask" "F.Paste")
			(net 1336 "/I2C.SDA")
			(pinfunction "SMBDATA")
			(pintype "bidirectional")
		)
		(pad "13" smd rect
			(at 2.652 -0.318 180)
			(size 1.6 0.41)
			(layers "F.Cu" "F.Mask" "F.Paste")
			(net 1120 "unconnected-(U3-NC-Pad13)")
			(pinfunction "NC")
			(pintype "no_connect")
		)
		(pad "14" smd rect
			(at 2.652 -0.954 180)
			(size 1.6 0.41)
			(layers "F.Cu" "F.Mask" "F.Paste")
			(net 1338 "/I2C.SCL")
			(pinfunction "SMBCLK")
			(pintype "input")
		)
		(pad "15" smd rect
			(at 2.652 -1.589 180)
			(size 1.6 0.41)
			(layers "F.Cu" "F.Mask" "F.Paste")
			(net 345 "Net-(U3-STBY)")
			(pinfunction "STBY")
			(pintype "input")
		)
		(pad "16" smd rect
			(at 2.652 -2.223 180)
			(size 1.6 0.41)
			(layers "F.Cu" "F.Mask" "F.Paste")
			(net 1121 "unconnected-(U3-NC-Pad16)")
			(pinfunction "NC")
			(pintype "no_connect")
		)
	)
	(footprint "antmicro-footprints:C_0402_1005Metric"
		(layer "F.Cu")
		(at 254.445 134.935 180)
		(descr "Capacitor SMD 0402")
		(tags "capacitor SMD 0402")
		(property "Reference" "C232"
			(at 1.4 3.985 180)
			(layer "F.SilkS")
			(effects
				(font
					(size 0.7 0.7)
					(thickness 0.15)
				)
				(justify left bottom)
			)
		)
		(property "Value" "C_100n_0402"
			(at 0 1.169 180)
			(layer "F.Fab")
			(effects
				(font
					(size 0.7 0.7)
					(thickness 0.15)
				)
				(justify left bottom)
			)
		)
		(property "Description" "SMD Multilayer Ceramic Capacitor, 0.1 µF, 50 V, 0402 [1005 Metric], ± 10%, X5R, GRM Series"
			(at 0 0 180)
			(layer "F.Fab")
			(hide yes)
			(effects
				(font
					(size 1.27 1.27)
					(thickness 0.15)
				)
			)
		)
		(property "Author" "Antmicro"
			(at 508.89 269.87 0)
			(layer "F.Fab")
			(hide yes)
			(effects
				(font
					(size 1 1)
					(thickness 0.15)
				)
			)
		)
		(property "Dielectric" "X5R"
			(at 508.89 269.87 0)
			(layer "F.Fab")
			(hide yes)
			(effects
				(font
					(size 1 1)
					(thickness 0.15)
				)
			)
		)
		(property "License" "Apache-2.0"
			(at 508.89 269.87 0)
			(layer "F.Fab")
			(hide yes)
			(effects
				(font
					(size 1 1)
					(thickness 0.15)
				)
			)
		)
		(property "MPN" "GRM155R61H104KE14D"
			(at 508.89 269.87 0)
			(layer "F.Fab")
			(hide yes)
			(effects
				(font
					(size 1 1)
					(thickness 0.15)
				)
			)
		)
		(property "Manufacturer" "Murata"
			(at 508.89 269.87 0)
			(layer "F.Fab")
			(hide yes)
			(effects
				(font
					(size 1 1)
					(thickness 0.15)
				)
			)
		)
		(property "Val" "100n"
			(at 508.89 269.87 0)
			(layer "F.Fab")
			(hide yes)
			(effects
				(font
					(size 1 1)
					(thickness 0.15)
				)
			)
		)
		(property "Voltage" "50V"
			(at 508.89 269.87 0)
			(layer "F.Fab")
			(hide yes)
			(effects
				(font
					(size 1 1)
					(thickness 0.15)
				)
			)
		)
		(sheetname "USB PHY")
		(sheetfile "usb-phy.kicad_sch")
		(attr smd)
		(fp_rect
			(start -0.925 -0.47)
			(end 0.925 0.47)
			(stroke
				(width 0.05)
				(type default)
			)
			(fill no)
			(layer "F.CrtYd")
		)
		(fp_line
			(start 0.504 0.248)
			(end -0.494 0.248)
			(stroke
				(width 0.15)
				(type solid)
			)
			(layer "F.Fab")
		)
		(fp_line
			(start 0.504 -0.25)
			(end 0.504 0.248)
			(stroke
				(width 0.15)
				(type solid)
			)
			(layer "F.Fab")
		)
		(fp_line
			(start -0.494 0.248)
			(end -0.494 -0.25)
			(stroke
				(width 0.15)
				(type solid)
			)
			(layer "F.Fab")
		)
		(fp_line
			(start -0.494 -0.25)
			(end 0.504 -0.25)
			(stroke
				(width 0.15)
				(type solid)
			)
			(layer "F.Fab")
		)
		(pad "1" smd roundrect
			(at -0.48 0 180)
			(size 0.59 0.64)
			(layers "F.Cu" "F.Mask" "F.Paste")
			(roundrect_rratio 0.25)
			(net 1 "GND")
			(pintype "passive")
		)
		(pad "2" smd roundrect
			(at 0.48 0 180)
			(size 0.59 0.64)
			(layers "F.Cu" "F.Mask" "F.Paste")
			(roundrect_rratio 0.25)
			(net 711 "/USB PHY/FTDI_VPLL")
			(pintype "passive")
		)
	)
	(footprint "antmicro-footprints:R_Array_4x0201_Panasonic_EXB18V"
		(layer "F.Cu")
		(at 253.9 144.302)
		(property "Reference" "R282"
			(at -19.35 -38.052 0)
			(layer "F.SilkS")
			(effects
				(font
					(size 0.7 0.7)
					(thickness 0.15)
				)
				(justify right bottom)
			)
		)
		(property "Value" "R_4x33R_0201_array"
			(at -1.1 1.8 0)
			(layer "F.Fab")
			(effects
				(font
					(size 0.7 0.7)
					(thickness 0.15)
				)
				(justify left bottom)
			)
		)
		(property "Description" "Fixed Network Resistor, 33 ohm, Isolated, 4 Resistors, 0502 [1406 Metric], Flat, ± 5%"
			(at 0 0 0)
			(layer "F.Fab")
			(hide yes)
			(effects
				(font
					(size 1.27 1.27)
					(thickness 0.15)
				)
			)
		)
		(property "Author" "Antmicro"
			(at 0 0 0)
			(layer "F.Fab")
			(hide yes)
			(effects
				(font
					(size 1 1)
					(thickness 0.15)
				)
			)
		)
		(property "License" "Apache-2.0"
			(at 0 0 0)
			(layer "F.Fab")
			(hide yes)
			(effects
				(font
					(size 1 1)
					(thickness 0.15)
				)
			)
		)
		(property "MPN" "EXB-18V330JX"
			(at 0 0 0)
			(layer "F.Fab")
			(hide yes)
			(effects
				(font
					(size 1 1)
					(thickness 0.15)
				)
			)
		)
		(property "Manufacturer" "Panasonic"
			(at 0 0 0)
			(layer "F.Fab")
			(hide yes)
			(effects
				(font
					(size 1 1)
					(thickness 0.15)
				)
			)
		)
		(property "Val" "R_4x33R_0201"
			(at 0 0 0)
			(layer "F.Fab")
			(hide yes)
			(effects
				(font
					(size 1 1)
					(thickness 0.15)
				)
			)
		)
		(sheetname "Supervisior MCU")
		(sheetfile "supervisor-mcu.kicad_sch")
		(attr smd)
		(fp_line
			(start -0.8 -0.45)
			(end -0.8 0.45)
			(stroke
				(width 0.12)
				(type solid)
			)
			(layer "F.SilkS")
		)
		(fp_line
			(start 0.8 -0.45)
			(end 0.8 0.45)
			(stroke
				(width 0.12)
				(type solid)
			)
			(layer "F.SilkS")
		)
		(fp_rect
			(start -0.898 -0.66)
			(end 0.898 0.65)
			(stroke
				(width 0.05)
				(type solid)
			)
			(fill no)
			(layer "F.CrtYd")
		)
		(pad "1" smd roundrect
			(at -0.6 0.298)
			(size 0.2 0.4)
			(layers "F.Cu" "F.Mask" "F.Paste")
			(roundrect_rratio 0.25)
			(net 1093 "/Supervisior MCU/USB_ALE")
			(pinfunction "R1.1")
			(pintype "passive")
		)
		(pad "2" smd roundrect
			(at -0.202 0.298)
			(size 0.2 0.4)
			(layers "F.Cu" "F.Mask" "F.Paste")
			(roundrect_rratio 0.25)
			(net 1086 "/Supervisior MCU/PGOOD_3V3")
			(pinfunction "R2.1")
			(pintype "passive")
		)
		(pad "3" smd roundrect
			(at 0.2 0.298)
			(size 0.2 0.4)
			(layers "F.Cu" "F.Mask" "F.Paste")
			(roundrect_rratio 0.25)
			(net 1070 "/Supervisior MCU/USB_A9")
			(pinfunction "R3.1")
			(pintype "passive")
		)
		(pad "4" smd roundrect
			(at 0.598 0.298)
			(size 0.2 0.4)
			(layers "F.Cu" "F.Mask" "F.Paste")
			(roundrect_rratio 0.25)
			(net 1094 "/Supervisior MCU/USB_RD")
			(pinfunction "R4.1")
			(pintype "passive")
		)
		(pad "5" smd roundrect
			(at 0.598 -0.3)
			(size 0.2 0.4)
			(layers "F.Cu" "F.Mask" "F.Paste")
			(roundrect_rratio 0.25)
			(net 1390 "/SUP_MCU.RD")
			(pinfunction "R4.2")
			(pintype "passive")
		)
		(pad "6" smd roundrect
			(at 0.2 -0.3)
			(size 0.2 0.4)
			(layers "F.Cu" "F.Mask" "F.Paste")
			(roundrect_rratio 0.25)
			(net 1391 "/SUP_MCU.A9")
			(pinfunction "R3.2")
			(pintype "passive")
		)
		(pad "7" smd roundrect
			(at -0.202 -0.3)
			(size 0.2 0.4)
			(layers "F.Cu" "F.Mask" "F.Paste")
			(roundrect_rratio 0.25)
			(net 1387 "/SUP_MCU.PG_3V3")
			(pinfunction "R2.2")
			(pintype "passive")
		)
		(pad "8" smd roundrect
			(at -0.6 -0.3)
			(size 0.2 0.4)
			(layers "F.Cu" "F.Mask" "F.Paste")
			(roundrect_rratio 0.25)
			(net 1392 "/SUP_MCU.ALE")
			(pinfunction "R1.2")
			(pintype "passive")
		)
	)
	(footprint "antmicro-footprints:NetTie-2_SMD_Pad0.127mm"
		(layer "F.Cu")
		(at 197.760197 131.239803 -135)
		(descr "Net tie, 2 pin, 0.127mm  SMD pads")
		(tags "net tie")
		(property "Reference" "NT24"
			(at -0.128 -1.345 225)
			(layer "F.SilkS")
			(hide yes)
			(effects
				(font
					(size 0.7 0.7)
					(thickness 0.15)
				)
				(justify left bottom)
			)
		)
		(property "Value" "Net-Tie_2"
			(at 0 1.199 225)
			(layer "F.Fab")
			(effects
				(font
					(size 0.7 0.7)
					(thickness 0.15)
				)
				(justify left bottom)
			)
		)
		(property "Description" "Net tie, 2 pins"
			(at 0 0 225)
			(layer "F.Fab")
			(hide yes)
			(effects
				(font
					(size 1.27 1.27)
					(thickness 0.15)
				)
			)
		)
		(property "Author" "Antmicro"
			(at 244.797219 363.877934 0)
			(layer "F.Fab")
			(hide yes)
			(effects
				(font
					(size 1 1)
					(thickness 0.15)
				)
			)
		)
		(property "License" "Apache-2.0"
			(at 244.797219 363.877934 0)
			(layer "F.Fab")
			(hide yes)
			(effects
				(font
					(size 1 1)
					(thickness 0.15)
				)
			)
		)
		(property "MPN" ""
			(at 244.797219 363.877934 0)
			(layer "F.Fab")
			(hide yes)
			(effects
				(font
					(size 1 1)
					(thickness 0.15)
				)
			)
		)
		(property "Manufacturer" ""
			(at 244.797219 363.877934 0)
			(layer "F.Fab")
			(hide yes)
			(effects
				(font
					(size 1 1)
					(thickness 0.15)
				)
			)
		)
		(sheetname "FPGA Config")
		(sheetfile "fpga-config.kicad_sch")
		(attr exclude_from_pos_files)
		(net_tie_pad_groups "1, 2")
		(fp_poly
			(pts
				(xy -0.0635 -0.0635) (xy 0.0625 -0.0635) (xy 0.0625 0.0635) (xy -0.0635 0.0635)
			)
			(stroke
				(width 0)
				(type solid)
			)
			(fill yes)
			(layer "F.Cu")
		)
		(pad "1" smd roundrect
			(at -0.127001 0 45)
			(size 0.127 0.127)
			(layers "F.Cu")
			(roundrect_rratio 0.5)
			(chamfer_ratio 0)
			(chamfer top_left bottom_left)
			(net 870 "VREFN")
			(pinfunction "1")
			(pintype "passive")
		)
		(pad "2" smd roundrect
			(at 0.125999 0 225)
			(size 0.127 0.127)
			(layers "F.Cu")
			(roundrect_rratio 0.5)
			(chamfer_ratio 0)
			(chamfer top_left bottom_left)
			(net 1 "GND")
			(pinfunction "2")
			(pintype "passive")
		)
	)
	(footprint "antmicro-footprints:R_0402_1005Metric"
		(layer "F.Cu")
		(at 190.515001 148.785001)
		(descr "Resistor SMD 0402")
		(tags "resistor SMD 0402")
		(property "Reference" "R334"
			(at -0.965001 -0.485001 0)
			(layer "F.SilkS")
			(effects
				(font
					(size 0.7 0.7)
					(thickness 0.15)
				)
				(justify left bottom)
			)
		)
		(property "Value" "R_100R_0402"
			(at 0 1.4 0)
			(layer "F.Fab")
			(effects
				(font
					(size 0.7 0.7)
					(thickness 0.15)
				)
				(justify left bottom)
			)
		)
		(property "Description" "SMD Chip Resistor, 100 ohm, ± 1%, 62.5 mW, 0402 [1005 Metric], Thick Film, General Purpose"
			(at 0 0 0)
			(layer "F.Fab")
			(hide yes)
			(effects
				(font
					(size 1.27 1.27)
					(thickness 0.15)
				)
			)
		)
		(property "Author" "Antmicro"
			(at 0 0 0)
			(layer "F.Fab")
			(hide yes)
			(effects
				(font
					(size 1 1)
					(thickness 0.15)
				)
			)
		)
		(property "License" "Apache-2.0"
			(at 0 0 0)
			(layer "F.Fab")
			(hide yes)
			(effects
				(font
					(size 1 1)
					(thickness 0.15)
				)
			)
		)
		(property "MPN" "CR0402-FX-1000GLF"
			(at 0 0 0)
			(layer "F.Fab")
			(hide yes)
			(effects
				(font
					(size 1 1)
					(thickness 0.15)
				)
			)
		)
		(property "Manufacturer" "Bourns"
			(at 0 0 0)
			(layer "F.Fab")
			(hide yes)
			(effects
				(font
					(size 1 1)
					(thickness 0.15)
				)
			)
		)
		(property "Tolerance" "1%"
			(at 0 0 0)
			(layer "F.Fab")
			(hide yes)
			(effects
				(font
					(size 1 1)
					(thickness 0.15)
				)
			)
		)
		(property "Val" "100R"
			(at 0 0 0)
			(layer "F.Fab")
			(hide yes)
			(effects
				(font
					(size 1 1)
					(thickness 0.15)
				)
			)
		)
		(sheetname "Clocks")
		(sheetfile "clocks.kicad_sch")
		(attr smd)
		(fp_rect
			(start -0.925 -0.47)
			(end 0.925 0.47)
			(stroke
				(width 0.05)
				(type default)
			)
			(fill no)
			(layer "F.CrtYd")
		)
		(fp_rect
			(start -0.5 -0.25)
			(end 0.5 0.25)
			(stroke
				(width 0.15)
				(type solid)
			)
			(fill no)
			(layer "F.Fab")
		)
		(pad "1" smd roundrect
			(at -0.48 0)
			(size 0.59 0.64)
			(layers "F.Cu" "F.Mask" "F.Paste")
			(roundrect_rratio 0.25)
			(net 623 "/Clocks/SYS.CLK_N")
			(pintype "passive")
		)
		(pad "2" smd roundrect
			(at 0.48 0)
			(size 0.59 0.64)
			(layers "F.Cu" "F.Mask" "F.Paste")
			(roundrect_rratio 0.25)
			(net 624 "/Clocks/SYS.CLK_P")
			(pintype "passive")
		)
	)
	(footprint "antmicro-footprints:R_0402_1005Metric"
		(layer "F.Cu")
		(at 259.6 127.5 180)
		(descr "Resistor SMD 0402")
		(tags "resistor SMD 0402")
		(property "Reference" "R174"
			(at 1.05 5.75 180)
			(layer "F.SilkS")
			(effects
				(font
					(size 0.7 0.7)
					(thickness 0.15)
				)
				(justify left bottom)
			)
		)
		(property "Value" "R_33R_0402"
			(at 0 1.4 180)
			(layer "F.Fab")
			(effects
				(font
					(size 0.7 0.7)
					(thickness 0.15)
				)
				(justify left bottom)
			)
		)
		(property "Description" "SMD Chip Resistor, 33 ohm, ± 1%, 62.5 mW, 0402 [1005 Metric], Thick Film, General Purpose"
			(at 0 0 180)
			(layer "F.Fab")
			(hide yes)
			(effects
				(font
					(size 1.27 1.27)
					(thickness 0.15)
				)
			)
		)
		(property "Author" "Antmicro"
			(at 519.2 255 0)
			(layer "F.Fab")
			(hide yes)
			(effects
				(font
					(size 1 1)
					(thickness 0.15)
				)
			)
		)
		(property "License" "Apache-2.0"
			(at 519.2 255 0)
			(layer "F.Fab")
			(hide yes)
			(effects
				(font
					(size 1 1)
					(thickness 0.15)
				)
			)
		)
		(property "MPN" "CR0402-FX-33R0GLF"
			(at 519.2 255 0)
			(layer "F.Fab")
			(hide yes)
			(effects
				(font
					(size 1 1)
					(thickness 0.15)
				)
			)
		)
		(property "Manufacturer" "Bourns"
			(at 519.2 255 0)
			(layer "F.Fab")
			(hide yes)
			(effects
				(font
					(size 1 1)
					(thickness 0.15)
				)
			)
		)
		(property "Tolerance" "1%"
			(at 519.2 255 0)
			(layer "F.Fab")
			(hide yes)
			(effects
				(font
					(size 1 1)
					(thickness 0.15)
				)
			)
		)
		(property "Val" "33R"
			(at 519.2 255 0)
			(layer "F.Fab")
			(hide yes)
			(effects
				(font
					(size 1 1)
					(thickness 0.15)
				)
			)
		)
		(sheetname "USB PHY")
		(sheetfile "usb-phy.kicad_sch")
		(attr smd)
		(fp_rect
			(start -0.925 -0.47)
			(end 0.925 0.47)
			(stroke
				(width 0.05)
				(type default)
			)
			(fill no)
			(layer "F.CrtYd")
		)
		(fp_rect
			(start -0.5 -0.25)
			(end 0.5 0.25)
			(stroke
				(width 0.15)
				(type solid)
			)
			(fill no)
			(layer "F.Fab")
		)
		(pad "1" smd roundrect
			(at -0.48 0 180)
			(size 0.59 0.64)
			(layers "F.Cu" "F.Mask" "F.Paste")
			(roundrect_rratio 0.25)
			(net 842 "/USB PHY/USB_USR_CONN_D+")
			(pintype "passive")
		)
		(pad "2" smd roundrect
			(at 0.48 0 180)
			(size 0.59 0.64)
			(layers "F.Cu" "F.Mask" "F.Paste")
			(roundrect_rratio 0.25)
			(net 928 "/USB PHY/USB_USR_D+")
			(pintype "passive")
		)
	)
	(footprint "antmicro-footprints:LED_0603_1608Metric_G"
		(layer "F.Cu")
		(at 261.5 83.8)
		(descr "LED SMD 0603 Green")
		(tags "LED SMD 0603 Green")
		(property "Reference" "D18"
			(at -1.1 1.5 0)
			(layer "F.SilkS")
			(effects
				(font
					(size 0.7 0.7)
					(thickness 0.15)
				)
				(justify left bottom)
			)
		)
		(property "Value" "LED_G_0603_KP-1608CGCK"
			(at 0 1.6 0)
			(layer "F.Fab")
			(effects
				(font
					(size 0.7 0.7)
					(thickness 0.15)
				)
				(justify left bottom)
			)
		)
		(property "Description" "LED, Green, SMD, 0603, 20 mA, 2.1 V, 570 nm"
			(at 0 0 0)
			(layer "F.Fab")
			(hide yes)
			(effects
				(font
					(size 1.27 1.27)
					(thickness 0.15)
				)
			)
		)
		(property "Author" "Antmicro"
			(at 0 0 0)
			(layer "F.Fab")
			(hide yes)
			(effects
				(font
					(size 1 1)
					(thickness 0.15)
				)
			)
		)
		(property "Color" "Green"
			(at 0 0 0)
			(layer "F.Fab")
			(hide yes)
			(effects
				(font
					(size 1 1)
					(thickness 0.15)
				)
			)
		)
		(property "License" "Apache-2.0"
			(at 0 0 0)
			(layer "F.Fab")
			(hide yes)
			(effects
				(font
					(size 1 1)
					(thickness 0.15)
				)
			)
		)
		(property "MPN" "KP-1608CGCK"
			(at 0 0 0)
			(layer "F.Fab")
			(hide yes)
			(effects
				(font
					(size 1 1)
					(thickness 0.15)
				)
			)
		)
		(property "Manufacturer" "Kingbright"
			(at 0 0 0)
			(layer "F.Fab")
			(hide yes)
			(effects
				(font
					(size 1 1)
					(thickness 0.15)
				)
			)
		)
		(sheetname "User GPIO + LED + button + DIP switch")
		(sheetfile "user-gpio.kicad_sch")
		(attr smd)
		(fp_line
			(start -1.18 -0.319)
			(end -1.18 0.321)
			(stroke
				(width 0.15)
				(type solid)
			)
			(layer "F.SilkS")
		)
		(fp_line
			(start -0.094672 0.001008)
			(end -0.24 0.001008)
			(stroke
				(width 0.1)
				(type solid)
			)
			(layer "F.SilkS")
		)
		(fp_line
			(start -0.094672 0.001008)
			(end 0.105328 -0.198992)
			(stroke
				(width 0.1)
				(type solid)
			)
			(layer "F.SilkS")
		)
		(fp_line
			(start -0.094672 0.201008)
			(end -0.094672 -0.198992)
			(stroke
				(width 0.1)
				(type solid)
			)
			(layer "F.SilkS")
		)
		(fp_line
			(start 0.105328 0.001008)
			(end 0.24 0.001)
			(stroke
				(width 0.1)
				(type solid)
			)
			(layer "F.SilkS")
		)
		(fp_line
			(start 0.105328 0.201008)
			(end -0.094672 0.001008)
			(stroke
				(width 0.1)
				(type solid)
			)
			(layer "F.SilkS")
		)
		(fp_line
			(start 0.105328 0.201008)
			(end 0.105328 -0.198992)
			(stroke
				(width 0.1)
				(type solid)
			)
			(layer "F.SilkS")
		)
		(fp_line
			(start 0.22 -0.35)
			(end -0.22 -0.35)
			(stroke
				(width 0.15)
				(type solid)
			)
			(layer "F.SilkS")
		)
		(fp_line
			(start 0.22 0.35)
			(end -0.22 0.35)
			(stroke
				(width 0.15)
				(type solid)
			)
			(layer "F.SilkS")
		)
		(fp_rect
			(start 1.25 0.65)
			(end -1.25 -0.65)
			(stroke
				(width 0.05)
				(type solid)
			)
			(fill no)
			(layer "F.CrtYd")
		)
		(fp_line
			(start -0.199 -0.202)
			(end -0.199 0.1)
			(stroke
				(width 0.15)
				(type solid)
			)
			(layer "F.Fab")
		)
		(fp_line
			(start -0.199 0)
			(end -0.597 0)
			(stroke
				(width 0.15)
				(type solid)
			)
			(layer "F.Fab")
		)
		(fp_line
			(start -0.199 0.2)
			(end -0.199 0.1)
			(stroke
				(width 0.15)
				(type solid)
			)
			(layer "F.Fab")
		)
		(fp_line
			(start -0.101 0)
			(end 0.201 0.2)
			(stroke
				(width 0.15)
				(type solid)
			)
			(layer "F.Fab")
		)
		(fp_line
			(start 0.201 -0.202)
			(end -0.101 0)
			(stroke
				(width 0.15)
				(type solid)
			)
			(layer "F.Fab")
		)
		(fp_line
			(start 0.201 0)
			(end 0.201 -0.202)
			(stroke
				(width 0.15)
				(type solid)
			)
			(layer "F.Fab")
		)
		(fp_line
			(start 0.201 0.2)
			(end 0.201 0)
			(stroke
				(width 0.15)
				(type solid)
			)
			(layer "F.Fab")
		)
		(fp_line
			(start 0.599 0)
			(end 0.201 0)
			(stroke
				(width 0.15)
				(type solid)
			)
			(layer "F.Fab")
		)
		(fp_rect
			(start 0.848 0.4)
			(end -0.85 -0.402)
			(stroke
				(width 0.15)
				(type solid)
			)
			(fill no)
			(layer "F.Fab")
		)
		(pad "1" smd roundrect
			(at -0.7 0 180)
			(size 0.8 1)
			(layers "F.Cu" "F.Mask" "F.Paste")
			(roundrect_rratio 0.2)
			(net 772 "Net-(D18-C)")
			(pinfunction "C")
			(pintype "passive")
		)
		(pad "2" smd roundrect
			(at 0.7 0 180)
			(size 0.8 1)
			(layers "F.Cu" "F.Mask" "F.Paste")
			(roundrect_rratio 0.2)
			(net 775 "Net-(D18-A)")
			(pinfunction "A")
			(pintype "passive")
		)
	)
	(footprint "antmicro-footprints:PinHeader_2x20_P1.27mm_SMD_Shrouded"
		(layer "F.Cu")
		(at 233.002 96.576)
		(property "Reference" "J9"
			(at 14.748 -3.026 0)
			(layer "F.SilkS")
			(effects
				(font
					(size 0.7 0.7)
					(thickness 0.15)
				)
				(justify left bottom)
			)
		)
		(property "Value" "PinHeader_2x20_P1.27mm_SMD_Shrouded"
			(at -3.67 0.35 0)
			(layer "F.Fab")
			(effects
				(font
					(size 0.7 0.7)
					(thickness 0.15)
				)
				(justify left bottom)
			)
		)
		(property "Description" "Pin Header, Wire-to-Board, 1.27 mm, 2 Rows, 40 Contacts, Surface Mount Straight, WR-BHD Series"
			(at 0 0 0)
			(layer "F.Fab")
			(hide yes)
			(effects
				(font
					(size 1.27 1.27)
					(thickness 0.15)
				)
			)
		)
		(property "Author" "Antmicro"
			(at 0 0 0)
			(layer "F.Fab")
			(hide yes)
			(effects
				(font
					(size 1 1)
					(thickness 0.15)
				)
			)
		)
		(property "License" "Apache-2.0"
			(at 0 0 0)
			(layer "F.Fab")
			(hide yes)
			(effects
				(font
					(size 1 1)
					(thickness 0.15)
				)
			)
		)
		(property "MPN" "62704020621"
			(at 0 0 0)
			(layer "F.Fab")
			(hide yes)
			(effects
				(font
					(size 1 1)
					(thickness 0.15)
				)
			)
		)
		(property "Manufacturer" "Würth Elektronik"
			(at 0 0 0)
			(layer "F.Fab")
			(hide yes)
			(effects
				(font
					(size 1 1)
					(thickness 0.15)
				)
			)
		)
		(sheetname "User GPIO + LED + button + DIP switch")
		(sheetfile "user-gpio.kicad_sch")
		(attr smd)
		(fp_line
			(start -16 -2.6)
			(end -16 2.6)
			(stroke
				(width 0.15)
				(type solid)
			)
			(layer "F.SilkS")
		)
		(fp_line
			(start -16 -2.6)
			(end -12.7 -2.6)
			(stroke
				(width 0.15)
				(type solid)
			)
			(layer "F.SilkS")
		)
		(fp_line
			(start -16 2.6)
			(end -12.7 2.6)
			(stroke
				(width 0.15)
				(type solid)
			)
			(layer "F.SilkS")
		)
		(fp_line
			(start 12.7 -2.6)
			(end 16 -2.6)
			(stroke
				(width 0.15)
				(type solid)
			)
			(layer "F.SilkS")
		)
		(fp_line
			(start 12.7 2.6)
			(end 16 2.6)
			(stroke
				(width 0.15)
				(type solid)
			)
			(layer "F.SilkS")
		)
		(fp_line
			(start 16 -2.6)
			(end 16 2.6)
			(stroke
				(width 0.15)
				(type solid)
			)
			(layer "F.SilkS")
		)
		(fp_circle
			(center -12.77 3.1)
			(end -12.719 3.1)
			(stroke
				(width 0.15)
				(type solid)
			)
			(fill yes)
			(layer "F.SilkS")
		)
		(fp_rect
			(start -16.3 -3.5)
			(end 16.3 3.5)
			(stroke
				(width 0.05)
				(type solid)
			)
			(fill no)
			(layer "F.CrtYd")
		)
		(fp_line
			(start -15.87 2.59)
			(end -15.67 2.79)
			(stroke
				(width 0.15)
				(type solid)
			)
			(layer "F.Fab")
		)
		(fp_rect
			(start -15.875 -2.801)
			(end 15.874 2.798)
			(stroke
				(width 0.15)
				(type solid)
			)
			(fill no)
			(layer "F.Fab")
		)
		(pad "1" smd rect
			(at -12.065 1.999)
			(size 0.74 2.8)
			(layers "F.Cu" "F.Mask" "F.Paste")
			(net 1234 "/USER_IO.A1")
			(pintype "passive")
		)
		(pad "2" smd rect
			(at -12.065 -2)
			(size 0.74 2.8)
			(layers "F.Cu" "F.Mask" "F.Paste")
			(net 1 "GND")
			(pintype "passive")
		)
		(pad "3" smd rect
			(at -10.795 1.999)
			(size 0.74 2.8)
			(layers "F.Cu" "F.Mask" "F.Paste")
			(net 1235 "/USER_IO.A3")
			(pintype "passive")
		)
		(pad "4" smd rect
			(at -10.795 -2)
			(size 0.74 2.8)
			(layers "F.Cu" "F.Mask" "F.Paste")
			(net 1 "GND")
			(pintype "passive")
		)
		(pad "5" smd rect
			(at -9.526 1.999)
			(size 0.74 2.8)
			(layers "F.Cu" "F.Mask" "F.Paste")
			(net 1236 "/USER_IO.A5")
			(pintype "passive")
		)
		(pad "6" smd rect
			(at -9.526 -2)
			(size 0.74 2.8)
			(layers "F.Cu" "F.Mask" "F.Paste")
			(net 1 "GND")
			(pintype "passive")
		)
		(pad "7" smd rect
			(at -8.257 1.999)
			(size 0.74 2.8)
			(layers "F.Cu" "F.Mask" "F.Paste")
			(net 1237 "/USER_IO.A7")
			(pintype "passive")
		)
		(pad "8" smd rect
			(at -8.257 -2)
			(size 0.74 2.8)
			(layers "F.Cu" "F.Mask" "F.Paste")
			(net 1 "GND")
			(pintype "passive")
		)
		(pad "9" smd rect
			(at -6.986 1.999)
			(size 0.74 2.8)
			(layers "F.Cu" "F.Mask" "F.Paste")
			(net 1238 "/USER_IO.A9")
			(pintype "passive")
		)
		(pad "10" smd rect
			(at -6.986 -2)
			(size 0.74 2.8)
			(layers "F.Cu" "F.Mask" "F.Paste")
			(net 1 "GND")
			(pintype "passive")
		)
		(pad "11" smd rect
			(at -5.715 1.999)
			(size 0.74 2.8)
			(layers "F.Cu" "F.Mask" "F.Paste")
			(net 1239 "/USER_IO.A11")
			(pintype "passive")
		)
		(pad "12" smd rect
			(at -5.715 -2)
			(size 0.74 2.8)
			(layers "F.Cu" "F.Mask" "F.Paste")
			(net 1240 "/USER_IO.A12")
			(pintype "passive")
		)
		(pad "13" smd rect
			(at -4.446 1.999)
			(size 0.74 2.8)
			(layers "F.Cu" "F.Mask" "F.Paste")
			(net 1241 "/USER_IO.A13")
			(pintype "passive")
		)
		(pad "14" smd rect
			(at -4.446 -2)
			(size 0.74 2.8)
			(layers "F.Cu" "F.Mask" "F.Paste")
			(net 1242 "/USER_IO.A14")
			(pintype "passive")
		)
		(pad "15" smd rect
			(at -3.176 1.999)
			(size 0.74 2.8)
			(layers "F.Cu" "F.Mask" "F.Paste")
			(net 1243 "/USER_IO.A15")
			(pintype "passive")
		)
		(pad "16" smd rect
			(at -3.176 -2)
			(size 0.74 2.8)
			(layers "F.Cu" "F.Mask" "F.Paste")
			(net 1245 "/USER_IO.A16")
			(pintype "passive")
		)
		(pad "17" smd rect
			(at -1.905 1.999)
			(size 0.74 2.8)
			(layers "F.Cu" "F.Mask" "F.Paste")
			(net 1246 "/USER_IO.A17")
			(pintype "passive")
		)
		(pad "18" smd rect
			(at -1.905 -2)
			(size 0.74 2.8)
			(layers "F.Cu" "F.Mask" "F.Paste")
			(net 1247 "/USER_IO.A18")
			(pintype "passive")
		)
		(pad "19" smd rect
			(at -0.635 1.999)
			(size 0.74 2.8)
			(layers "F.Cu" "F.Mask" "F.Paste")
			(net 2 "VCC_USR_A")
			(pintype "passive")
		)
		(pad "20" smd rect
			(at -0.635 -2)
			(size 0.74 2.8)
			(layers "F.Cu" "F.Mask" "F.Paste")
			(net 1 "GND")
			(pintype "passive")
		)
		(pad "21" smd rect
			(at 0.633 1.999)
			(size 0.74 2.8)
			(layers "F.Cu" "F.Mask" "F.Paste")
			(net 1248 "/USER_IO.A21")
			(pintype "passive")
		)
		(pad "22" smd rect
			(at 0.633 -2)
			(size 0.74 2.8)
			(layers "F.Cu" "F.Mask" "F.Paste")
			(net 24 "+3V3")
			(pintype "passive")
		)
		(pad "23" smd rect
			(at 1.904 1.999)
			(size 0.74 2.8)
			(layers "F.Cu" "F.Mask" "F.Paste")
			(net 1249 "/USER_IO.A23")
			(pintype "passive")
		)
		(pad "24" smd rect
			(at 1.904 -2)
			(size 0.74 2.8)
			(layers "F.Cu" "F.Mask" "F.Paste")
			(net 1250 "/USER_IO.A24")
			(pintype "passive")
		)
		(pad "25" smd rect
			(at 3.173 1.999)
			(size 0.74 2.8)
			(layers "F.Cu" "F.Mask" "F.Paste")
			(net 1251 "/USER_IO.A25")
			(pintype "passive")
		)
		(pad "26" smd rect
			(at 3.173 -2)
			(size 0.74 2.8)
			(layers "F.Cu" "F.Mask" "F.Paste")
			(net 1252 "/USER_IO.A26")
			(pintype "passive")
		)
		(pad "27" smd rect
			(at 4.445 1.999)
			(size 0.74 2.8)
			(layers "F.Cu" "F.Mask" "F.Paste")
			(net 1253 "/USER_IO.A27")
			(pintype "passive")
		)
		(pad "28" smd rect
			(at 4.445 -2)
			(size 0.74 2.8)
			(layers "F.Cu" "F.Mask" "F.Paste")
			(net 1254 "/USER_IO.A28")
			(pintype "passive")
		)
		(pad "29" smd rect
			(at 5.714 1.999)
			(size 0.74 2.8)
			(layers "F.Cu" "F.Mask" "F.Paste")
			(net 1255 "/USER_IO.A29")
			(pintype "passive")
		)
		(pad "30" smd rect
			(at 5.714 -2)
			(size 0.74 2.8)
			(layers "F.Cu" "F.Mask" "F.Paste")
			(net 1256 "/USER_IO.A30")
			(pintype "passive")
		)
		(pad "31" smd rect
			(at 6.985 1.999)
			(size 0.74 2.8)
			(layers "F.Cu" "F.Mask" "F.Paste")
			(net 1257 "/USER_IO.A31")
			(pintype "passive")
		)
		(pad "32" smd rect
			(at 6.985 -2)
			(size 0.74 2.8)
			(layers "F.Cu" "F.Mask" "F.Paste")
			(net 1258 "/USER_IO.A32")
			(pintype "passive")
		)
		(pad "33" smd rect
			(at 8.255 1.999)
			(size 0.74 2.8)
			(layers "F.Cu" "F.Mask" "F.Paste")
			(net 1259 "/USER_IO.A33")
			(pintype "passive")
		)
		(pad "34" smd rect
			(at 8.255 -2)
			(size 0.74 2.8)
			(layers "F.Cu" "F.Mask" "F.Paste")
			(net 1 "GND")
			(pintype "passive")
		)
		(pad "35" smd rect
			(at 9.525 1.999)
			(size 0.74 2.8)
			(layers "F.Cu" "F.Mask" "F.Paste")
			(net 1260 "/USER_IO.A35")
			(pintype "passive")
		)
		(pad "36" smd rect
			(at 9.525 -2)
			(size 0.74 2.8)
			(layers "F.Cu" "F.Mask" "F.Paste")
			(net 1261 "/USER_IO.A36")
			(pintype "passive")
		)
		(pad "37" smd rect
			(at 10.794 1.999)
			(size 0.74 2.8)
			(layers "F.Cu" "F.Mask" "F.Paste")
			(net 1262 "/USER_IO.A37")
			(pintype "passive")
		)
		(pad "38" smd rect
			(at 10.794 -2)
			(size 0.74 2.8)
			(layers "F.Cu" "F.Mask" "F.Paste")
			(net 1263 "/USER_IO.A38")
			(pintype "passive")
		)
		(pad "39" smd rect
			(at 12.063 1.999)
			(size 0.74 2.8)
			(layers "F.Cu" "F.Mask" "F.Paste")
			(net 1264 "/USER_IO.A39")
			(pintype "passive")
		)
		(pad "40" smd rect
			(at 12.063 -2)
			(size 0.74 2.8)
			(layers "F.Cu" "F.Mask" "F.Paste")
			(net 1265 "/USER_IO.A40")
			(pintype "passive")
		)
	)
	(footprint "antmicro-footprints:Conn_Socket_Samtec_ERF5_2x20_ERF5-020-05.0-L-DV-K-TR"
		(locked yes)
		(layer "F.Cu")
		(at 249.9 125.8)
		(property "Reference" "J21"
			(at 6.46 -2.66 0)
			(layer "F.SilkS")
			(effects
				(font
					(size 0.7 0.7)
					(thickness 0.15)
				)
				(justify left bottom)
			)
		)
		(property "Value" "Socket_Samtec_ERF5_2x20_ERF5-020-05.0-L-DV-K-TR"
			(at 0 3.9 0)
			(layer "F.Fab")
			(effects
				(font
					(size 0.7 0.7)
					(thickness 0.15)
				)
				(justify left bottom)
			)
		)
		(property "Description" "Board to Board & Mezzanine Connectors 0.50 mm Edge Rate Rugged High Speed Socket"
			(at 0 0 0)
			(layer "F.Fab")
			(hide yes)
			(effects
				(font
					(size 1.27 1.27)
					(thickness 0.15)
				)
			)
		)
		(property "Author" "Antmicro"
			(at 0 0 0)
			(layer "F.Fab")
			(hide yes)
			(effects
				(font
					(size 1 1)
					(thickness 0.15)
				)
			)
		)
		(property "License" "Apache-2.0"
			(at 0 0 0)
			(layer "F.Fab")
			(hide yes)
			(effects
				(font
					(size 1 1)
					(thickness 0.15)
				)
			)
		)
		(property "MPN" "ERF5-020-05.0-L-DV-K-TR"
			(at 0 0 0)
			(layer "F.Fab")
			(hide yes)
			(effects
				(font
					(size 1 1)
					(thickness 0.15)
				)
			)
		)
		(property "Manufacturer" "Samtec"
			(at 0 0 0)
			(layer "F.Fab")
			(hide yes)
			(effects
				(font
					(size 1 1)
					(thickness 0.15)
				)
			)
		)
		(property "Pitch" "0.5 mm"
			(at 0 0 0)
			(layer "F.Fab")
			(hide yes)
			(effects
				(font
					(size 1 1)
					(thickness 0.15)
				)
			)
		)
		(sheetname "Supervisior MCU")
		(sheetfile "supervisor-mcu.kicad_sch")
		(attr smd)
		(fp_line
			(start -8.4 -2.475)
			(end -5.349 -2.475)
			(stroke
				(width 0.15)
				(type solid)
			)
			(layer "F.SilkS")
		)
		(fp_line
			(start -8.4 2.476)
			(end -8.4 -2.475)
			(stroke
				(width 0.15)
				(type solid)
			)
			(layer "F.SilkS")
		)
		(fp_line
			(start -5.349 2.476)
			(end -8.4 2.476)
			(stroke
				(width 0.15)
				(type solid)
			)
			(layer "F.SilkS")
		)
		(fp_line
			(start 5.351 -2.475)
			(end 8.401 -2.475)
			(stroke
				(width 0.15)
				(type solid)
			)
			(layer "F.SilkS")
		)
		(fp_line
			(start 8.401 -2.475)
			(end 8.401 2.476)
			(stroke
				(width 0.15)
				(type solid)
			)
			(layer "F.SilkS")
		)
		(fp_line
			(start 8.401 2.476)
			(end 5.351 2.476)
			(stroke
				(width 0.15)
				(type solid)
			)
			(layer "F.SilkS")
		)
		(fp_circle
			(center -5.2 2.9)
			(end -5.25 2.9)
			(stroke
				(width 0.15)
				(type solid)
			)
			(fill no)
			(layer "F.SilkS")
		)
		(fp_poly
			(pts
				(xy -4.623 -1.225) (xy -4.876 -1.225) (xy -4.876 -2.725) (xy -4.623 -2.725)
			)
			(stroke
				(width 0.01)
				(type solid)
			)
			(fill yes)
			(layer "F.Paste")
		)
		(fp_poly
			(pts
				(xy -4.623 2.726) (xy -4.876 2.726) (xy -4.876 1.226) (xy -4.623 1.226)
			)
			(stroke
				(width 0.01)
				(type solid)
			)
			(fill yes)
			(layer "F.Paste")
		)
		(fp_poly
			(pts
				(xy -4.123 -1.225) (xy -4.376 -1.225) (xy -4.376 -2.725) (xy -4.123 -2.725)
			)
			(stroke
				(width 0.01)
				(type solid)
			)
			(fill yes)
			(layer "F.Paste")
		)
		(fp_poly
			(pts
				(xy -4.123 2.726) (xy -4.376 2.726) (xy -4.376 1.226) (xy -4.123 1.226)
			)
			(stroke
				(width 0.01)
				(type solid)
			)
			(fill yes)
			(layer "F.Paste")
		)
		(fp_poly
			(pts
				(xy -3.623 -1.225) (xy -3.875 -1.225) (xy -3.875 -2.725) (xy -3.623 -2.725)
			)
			(stroke
				(width 0.01)
				(type solid)
			)
			(fill yes)
			(layer "F.Paste")
		)
		(fp_poly
			(pts
				(xy -3.623 2.726) (xy -3.875 2.726) (xy -3.875 1.226) (xy -3.623 1.226)
			)
			(stroke
				(width 0.01)
				(type solid)
			)
			(fill yes)
			(layer "F.Paste")
		)
		(fp_poly
			(pts
				(xy -3.123 -1.225) (xy -3.375 -1.225) (xy -3.375 -2.725) (xy -3.123 -2.725)
			)
			(stroke
				(width 0.01)
				(type solid)
			)
			(fill yes)
			(layer "F.Paste")
		)
		(fp_poly
			(pts
				(xy -3.123 2.726) (xy -3.375 2.726) (xy -3.375 1.226) (xy -3.123 1.226)
			)
			(stroke
				(width 0.01)
				(type solid)
			)
			(fill yes)
			(layer "F.Paste")
		)
		(fp_poly
			(pts
				(xy -2.623 -1.225) (xy -2.875 -1.225) (xy -2.875 -2.725) (xy -2.623 -2.725)
			)
			(stroke
				(width 0.01)
				(type solid)
			)
			(fill yes)
			(layer "F.Paste")
		)
		(fp_poly
			(pts
				(xy -2.623 2.726) (xy -2.875 2.726) (xy -2.875 1.226) (xy -2.623 1.226)
			)
			(stroke
				(width 0.01)
				(type solid)
			)
			(fill yes)
			(layer "F.Paste")
		)
		(fp_poly
			(pts
				(xy -2.123 -1.225) (xy -2.375 -1.225) (xy -2.375 -2.725) (xy -2.123 -2.725)
			)
			(stroke
				(width 0.01)
				(type solid)
			)
			(fill yes)
			(layer "F.Paste")
		)
		(fp_poly
			(pts
				(xy -2.123 2.726) (xy -2.375 2.726) (xy -2.375 1.226) (xy -2.123 1.226)
			)
			(stroke
				(width 0.01)
				(type solid)
			)
			(fill yes)
			(layer "F.Paste")
		)
		(fp_poly
			(pts
				(xy -1.622 -1.225) (xy -1.876 -1.225) (xy -1.876 -2.725) (xy -1.622 -2.725)
			)
			(stroke
				(width 0.01)
				(type solid)
			)
			(fill yes)
			(layer "F.Paste")
		)
		(fp_poly
			(pts
				(xy -1.622 2.726) (xy -1.876 2.726) (xy -1.876 1.226) (xy -1.622 1.226)
			)
			(stroke
				(width 0.01)
				(type solid)
			)
			(fill yes)
			(layer "F.Paste")
		)
		(fp_poly
			(pts
				(xy -1.122 -1.225) (xy -1.376 -1.225) (xy -1.376 -2.725) (xy -1.122 -2.725)
			)
			(stroke
				(width 0.01)
				(type solid)
			)
			(fill yes)
			(layer "F.Paste")
		)
		(fp_poly
			(pts
				(xy -1.122 2.726) (xy -1.376 2.726) (xy -1.376 1.226) (xy -1.122 1.226)
			)
			(stroke
				(width 0.01)
				(type solid)
			)
			(fill yes)
			(layer "F.Paste")
		)
		(fp_poly
			(pts
				(xy -0.621 -1.225) (xy -0.875 -1.225) (xy -0.875 -2.725) (xy -0.621 -2.725)
			)
			(stroke
				(width 0.01)
				(type solid)
			)
			(fill yes)
			(layer "F.Paste")
		)
		(fp_poly
			(pts
				(xy -0.621 2.726) (xy -0.875 2.726) (xy -0.875 1.226) (xy -0.621 1.226)
			)
			(stroke
				(width 0.01)
				(type solid)
			)
			(fill yes)
			(layer "F.Paste")
		)
		(fp_poly
			(pts
				(xy -0.121 -1.225) (xy -0.375 -1.225) (xy -0.375 -2.725) (xy -0.121 -2.725)
			)
			(stroke
				(width 0.01)
				(type solid)
			)
			(fill yes)
			(layer "F.Paste")
		)
		(fp_poly
			(pts
				(xy -0.121 2.726) (xy -0.375 2.726) (xy -0.375 1.226) (xy -0.121 1.226)
			)
			(stroke
				(width 0.01)
				(type solid)
			)
			(fill yes)
			(layer "F.Paste")
		)
		(fp_poly
			(pts
				(xy 0.377 -1.225) (xy 0.123 -1.225) (xy 0.123 -2.725) (xy 0.377 -2.725)
			)
			(stroke
				(width 0.01)
				(type solid)
			)
			(fill yes)
			(layer "F.Paste")
		)
		(fp_poly
			(pts
				(xy 0.377 2.726) (xy 0.123 2.726) (xy 0.123 1.226) (xy 0.377 1.226)
			)
			(stroke
				(width 0.01)
				(type solid)
			)
			(fill yes)
			(layer "F.Paste")
		)
		(fp_poly
			(pts
				(xy 0.877 -1.225) (xy 0.623 -1.225) (xy 0.623 -2.725) (xy 0.877 -2.725)
			)
			(stroke
				(width 0.01)
				(type solid)
			)
			(fill yes)
			(layer "F.Paste")
		)
		(fp_poly
			(pts
				(xy 0.877 2.726) (xy 0.623 2.726) (xy 0.623 1.226) (xy 0.877 1.226)
			)
			(stroke
				(width 0.01)
				(type solid)
			)
			(fill yes)
			(layer "F.Paste")
		)
		(fp_poly
			(pts
				(xy 1.377 -1.225) (xy 1.123 -1.225) (xy 1.123 -2.725) (xy 1.377 -2.725)
			)
			(stroke
				(width 0.01)
				(type solid)
			)
			(fill yes)
			(layer "F.Paste")
		)
		(fp_poly
			(pts
				(xy 1.377 2.726) (xy 1.123 2.726) (xy 1.123 1.226) (xy 1.377 1.226)
			)
			(stroke
				(width 0.01)
				(type solid)
			)
			(fill yes)
			(layer "F.Paste")
		)
		(fp_poly
			(pts
				(xy 1.877 -1.225) (xy 1.623 -1.225) (xy 1.623 -2.725) (xy 1.877 -2.725)
			)
			(stroke
				(width 0.01)
				(type solid)
			)
			(fill yes)
			(layer "F.Paste")
		)
		(fp_poly
			(pts
				(xy 1.877 2.726) (xy 1.623 2.726) (xy 1.623 1.226) (xy 1.877 1.226)
			)
			(stroke
				(width 0.01)
				(type solid)
			)
			(fill yes)
			(layer "F.Paste")
		)
		(fp_poly
			(pts
				(xy 2.378 -1.225) (xy 2.125 -1.225) (xy 2.125 -2.725) (xy 2.378 -2.725)
			)
			(stroke
				(width 0.01)
				(type solid)
			)
			(fill yes)
			(layer "F.Paste")
		)
		(fp_poly
			(pts
				(xy 2.378 2.726) (xy 2.125 2.726) (xy 2.125 1.226) (xy 2.378 1.226)
			)
			(stroke
				(width 0.01)
				(type solid)
			)
			(fill yes)
			(layer "F.Paste")
		)
		(fp_poly
			(pts
				(xy 2.878 -1.225) (xy 2.625 -1.225) (xy 2.625 -2.725) (xy 2.878 -2.725)
			)
			(stroke
				(width 0.01)
				(type solid)
			)
			(fill yes)
			(layer "F.Paste")
		)
		(fp_poly
			(pts
				(xy 2.878 2.726) (xy 2.625 2.726) (xy 2.625 1.226) (xy 2.878 1.226)
			)
			(stroke
				(width 0.01)
				(type solid)
			)
			(fill yes)
			(layer "F.Paste")
		)
		(fp_poly
			(pts
				(xy 3.378 -1.225) (xy 3.125 -1.225) (xy 3.125 -2.725) (xy 3.378 -2.725)
			)
			(stroke
				(width 0.01)
				(type solid)
			)
			(fill yes)
			(layer "F.Paste")
		)
		(fp_poly
			(pts
				(xy 3.378 2.726) (xy 3.125 2.726) (xy 3.125 1.226) (xy 3.378 1.226)
			)
			(stroke
				(width 0.01)
				(type solid)
			)
			(fill yes)
			(layer "F.Paste")
		)
		(fp_poly
			(pts
				(xy 3.878 -1.225) (xy 3.625 -1.225) (xy 3.625 -2.725) (xy 3.878 -2.725)
			)
			(stroke
				(width 0.01)
				(type solid)
			)
			(fill yes)
			(layer "F.Paste")
		)
		(fp_poly
			(pts
				(xy 3.878 2.726) (xy 3.625 2.726) (xy 3.625 1.226) (xy 3.878 1.226)
			)
			(stroke
				(width 0.01)
				(type solid)
			)
			(fill yes)
			(layer "F.Paste")
		)
		(fp_poly
			(pts
				(xy 4.377 -1.225) (xy 4.124 -1.225) (xy 4.124 -2.725) (xy 4.377 -2.725)
			)
			(stroke
				(width 0.01)
				(type solid)
			)
			(fill yes)
			(layer "F.Paste")
		)
		(fp_poly
			(pts
				(xy 4.377 2.726) (xy 4.124 2.726) (xy 4.124 1.226) (xy 4.377 1.226)
			)
			(stroke
				(width 0.01)
				(type solid)
			)
			(fill yes)
			(layer "F.Paste")
		)
		(fp_poly
			(pts
				(xy 4.877 -1.225) (xy 4.624 -1.225) (xy 4.624 -2.725) (xy 4.877 -2.725)
			)
			(stroke
				(width 0.01)
				(type solid)
			)
			(fill yes)
			(layer "F.Paste")
		)
		(fp_poly
			(pts
				(xy 4.877 2.726) (xy 4.624 2.726) (xy 4.624 1.226) (xy 4.877 1.226)
			)
			(stroke
				(width 0.01)
				(type solid)
			)
			(fill yes)
			(layer "F.Paste")
		)
		(fp_rect
			(start 8.651 2.926)
			(end -8.65 -2.925)
			(stroke
				(width 0.05)
				(type solid)
			)
			(fill no)
			(layer "F.CrtYd")
		)
		(fp_line
			(start -8.39 1.35)
			(end -7.27 2.47)
			(stroke
				(width 0.15)
				(type solid)
			)
			(layer "F.Fab")
		)
		(fp_rect
			(start 8.401 2.476)
			(end -8.4 -2.475)
			(stroke
				(width 0.15)
				(type solid)
			)
			(fill no)
			(layer "F.Fab")
		)
		(pad "" np_thru_hole circle
			(at -6.9 1.401 180)
			(size 1.45 1.45)
			(drill 1.45)
			(layers "*.Cu" "*.Mask")
		)
		(pad "" np_thru_hole circle
			(at 6.901 1.401 180)
			(size 1.45 1.45)
			(drill 1.45)
			(layers "*.Cu" "*.Mask")
		)
		(pad "1" smd rect
			(at -4.748 1.976 270)
			(size 1.5 0.3)
			(layers "F.Cu" "F.Mask")
			(net 1 "GND")
			(pintype "passive")
		)
		(pad "2" smd rect
			(at -4.748 -1.975 270)
			(size 1.5 0.3)
			(layers "F.Cu" "F.Mask")
			(net 1076 "/Supervisior MCU/USB_A15")
			(pintype "passive")
		)
		(pad "3" smd rect
			(at -4.248 1.976 270)
			(size 1.5 0.3)
			(layers "F.Cu" "F.Mask")
			(net 1 "GND")
			(pintype "passive")
		)
		(pad "4" smd rect
			(at -4.248 -1.975 270)
			(size 1.5 0.3)
			(layers "F.Cu" "F.Mask")
			(net 1078 "/Supervisior MCU/USB_A17")
			(pintype "passive")
		)
		(pad "5" smd rect
			(at -3.749 1.976 270)
			(size 1.5 0.3)
			(layers "F.Cu" "F.Mask")
			(net 1 "GND")
			(pintype "passive")
		)
		(pad "6" smd rect
			(at -3.749 -1.975 270)
			(size 1.5 0.3)
			(layers "F.Cu" "F.Mask")
			(net 1067 "/Supervisior MCU/USB_A6")
			(pintype "passive")
		)
		(pad "7" smd rect
			(at -3.249 1.976 270)
			(size 1.5 0.3)
			(layers "F.Cu" "F.Mask")
			(net 1 "GND")
			(pintype "passive")
		)
		(pad "8" smd rect
			(at -3.249 -1.975 270)
			(size 1.5 0.3)
			(layers "F.Cu" "F.Mask")
			(net 265 "/Supervisior MCU/PWR_ON")
			(pintype "passive")
		)
		(pad "9" smd rect
			(at -2.749 1.976 270)
			(size 1.5 0.3)
			(layers "F.Cu" "F.Mask")
			(net 1 "GND")
			(pintype "passive")
		)
		(pad "10" smd rect
			(at -2.749 -1.975 270)
			(size 1.5 0.3)
			(layers "F.Cu" "F.Mask")
			(net 1080 "/Supervisior MCU/USB_A19")
			(pintype "passive")
		)
		(pad "11" smd rect
			(at -2.249 1.976 270)
			(size 1.5 0.3)
			(layers "F.Cu" "F.Mask")
			(net 1061 "/Supervisior MCU/USB_A0")
			(pintype "passive")
		)
		(pad "12" smd rect
			(at -2.249 -1.975 270)
			(size 1.5 0.3)
			(layers "F.Cu" "F.Mask")
			(net 1075 "/Supervisior MCU/USB_A14")
			(pintype "passive")
		)
		(pad "13" smd rect
			(at -1.749 1.976 270)
			(size 1.5 0.3)
			(layers "F.Cu" "F.Mask")
			(net 1083 "/Supervisior MCU/RXD1")
			(pintype "passive")
		)
		(pad "14" smd rect
			(at -1.749 -1.975 270)
			(size 1.5 0.3)
			(layers "F.Cu" "F.Mask")
			(net 1118 "/Supervisior MCU/USB_CLK0")
			(pintype "passive")
		)
		(pad "15" smd rect
			(at -1.249 1.976 270)
			(size 1.5 0.3)
			(layers "F.Cu" "F.Mask")
			(net 1074 "/Supervisior MCU/USB_A13")
			(pintype "passive")
		)
		(pad "16" smd rect
			(at -1.249 -1.975 270)
			(size 1.5 0.3)
			(layers "F.Cu" "F.Mask")
			(net 111 "/Supervisior MCU/FAN_PWM")
			(pintype "passive")
		)
		(pad "17" smd rect
			(at -0.748 1.976 270)
			(size 1.5 0.3)
			(layers "F.Cu" "F.Mask")
			(net 1062 "/Supervisior MCU/USB_A1")
			(pintype "passive")
		)
		(pad "18" smd rect
			(at -0.748 -1.975 270)
			(size 1.5 0.3)
			(layers "F.Cu" "F.Mask")
			(net 1073 "/Supervisior MCU/USB_A12")
			(pintype "passive")
		)
		(pad "19" smd rect
			(at -0.248 1.976 270)
			(size 1.5 0.3)
			(layers "F.Cu" "F.Mask")
			(net 1068 "/Supervisior MCU/USB_A7")
			(pintype "passive")
		)
		(pad "20" smd rect
			(at -0.248 -1.975 270)
			(size 1.5 0.3)
			(layers "F.Cu" "F.Mask")
			(net 1072 "/Supervisior MCU/USB_A11")
			(pintype "passive")
		)
		(pad "21" smd rect
			(at 0.25 1.976 270)
			(size 1.5 0.3)
			(layers "F.Cu" "F.Mask")
			(net 1077 "/Supervisior MCU/USB_A16")
			(pintype "passive")
		)
		(pad "22" smd rect
			(at 0.25 -1.975 270)
			(size 1.5 0.3)
			(layers "F.Cu" "F.Mask")
			(net 1071 "/Supervisior MCU/USB_A10")
			(pintype "passive")
		)
		(pad "23" smd rect
			(at 0.75 1.976 270)
			(size 1.5 0.3)
			(layers "F.Cu" "F.Mask")
			(net 1079 "/Supervisior MCU/USB_A18")
			(pintype "passive")
		)
		(pad "24" smd rect
			(at 0.75 -1.975 270)
			(size 1.5 0.3)
			(layers "F.Cu" "F.Mask")
			(net 1082 "/Supervisior MCU/TXD0")
			(pintype "passive")
		)
		(pad "25" smd rect
			(at 1.25 1.976 270)
			(size 1.5 0.3)
			(layers "F.Cu" "F.Mask")
			(net 276 "/Supervisior MCU/SW_STATE")
			(pintype "passive")
		)
		(pad "26" smd rect
			(at 1.25 -1.975 270)
			(size 1.5 0.3)
			(layers "F.Cu" "F.Mask")
			(net 1081 "/Supervisior MCU/TXD1")
			(pintype "passive")
		)
		(pad "27" smd rect
			(at 1.75 1.976 270)
			(size 1.5 0.3)
			(layers "F.Cu" "F.Mask")
			(net 112 "/Supervisior MCU/SAM_FPGA_CCLK")
			(pintype "passive")
		)
		(pad "28" smd rect
			(at 1.75 -1.975 270)
			(size 1.5 0.3)
			(layers "F.Cu" "F.Mask")
			(net 1084 "/Supervisior MCU/RXD0")
			(pintype "passive")
		)
		(pad "29" smd rect
			(at 2.25 1.976 270)
			(size 1.5 0.3)
			(layers "F.Cu" "F.Mask")
			(net 1108 "/Supervisior MCU/PWR_RST")
			(pintype "passive")
		)
		(pad "30" smd rect
			(at 2.25 -1.975 270)
			(size 1.5 0.3)
			(layers "F.Cu" "F.Mask")
			(net 1087 "/Supervisior MCU/PGOOD_1V8")
			(pintype "passive")
		)
		(pad "31" smd rect
			(at 2.75 1.976 270)
			(size 1.5 0.3)
			(layers "F.Cu" "F.Mask")
			(net 1063 "/Supervisior MCU/USB_A2")
			(pintype "passive")
		)
		(pad "32" smd rect
			(at 2.75 -1.975 270)
			(size 1.5 0.3)
			(layers "F.Cu" "F.Mask")
			(net 703 "+5V")
			(pintype "passive")
		)
		(pad "33" smd rect
			(at 3.25 1.976 270)
			(size 1.5 0.3)
			(layers "F.Cu" "F.Mask")
			(net 1066 "/Supervisior MCU/USB_A5")
			(pintype "passive")
		)
		(pad "34" smd rect
			(at 3.25 -1.975 270)
			(size 1.5 0.3)
			(layers "F.Cu" "F.Mask")
			(net 703 "+5V")
			(pintype "passive")
		)
		(pad "35" smd rect
			(at 3.75 1.976 270)
			(size 1.5 0.3)
			(layers "F.Cu" "F.Mask")
			(net 1064 "/Supervisior MCU/USB_A3")
			(pintype "passive")
		)
		(pad "36" smd rect
			(at 3.75 -1.975 270)
			(size 1.5 0.3)
			(layers "F.Cu" "F.Mask")
			(net 703 "+5V")
			(pintype "passive")
		)
		(pad "37" smd rect
			(at 4.25 1.976 270)
			(size 1.5 0.3)
			(layers "F.Cu" "F.Mask")
			(net 1101 "/Supervisior MCU/SDA0")
			(pintype "passive")
		)
		(pad "38" smd rect
			(at 4.25 -1.975 270)
			(size 1.5 0.3)
			(layers "F.Cu" "F.Mask")
			(net 703 "+5V")
			(pintype "passive")
		)
		(pad "39" smd rect
			(at 4.75 1.976 270)
			(size 1.5 0.3)
			(layers "F.Cu" "F.Mask")
			(net 1065 "/Supervisior MCU/USB_A4")
			(pintype "passive")
		)
		(pad "40" smd rect
			(at 4.75 -1.975 270)
			(size 1.5 0.3)
			(layers "F.Cu" "F.Mask")
			(net 703 "+5V")
			(pintype "passive")
		)
	)
	(footprint "antmicro-footprints:C_0402_1005Metric"
		(layer "F.Cu")
		(at 201.695004 99.9115)
		(descr "Capacitor SMD 0402")
		(tags "capacitor SMD 0402")
		(property "Reference" "C282"
			(at 4.304996 7.9885 0)
			(layer "F.SilkS")
			(effects
				(font
					(size 0.7 0.7)
					(thickness 0.15)
				)
				(justify left bottom)
			)
		)
		(property "Value" "C_100n_0402"
			(at 0 1.169 0)
			(layer "F.Fab")
			(effects
				(font
					(size 0.7 0.7)
					(thickness 0.15)
				)
				(justify left bottom)
			)
		)
		(property "Description" "SMD Multilayer Ceramic Capacitor, 0.1 µF, 50 V, 0402 [1005 Metric], ± 10%, X5R, GRM Series"
			(at 0 0 0)
			(layer "F.Fab")
			(hide yes)
			(effects
				(font
					(size 1.27 1.27)
					(thickness 0.15)
				)
			)
		)
		(property "Author" "Antmicro"
			(at 0 0 0)
			(layer "F.Fab")
			(hide yes)
			(effects
				(font
					(size 1 1)
					(thickness 0.15)
				)
			)
		)
		(property "Dielectric" "X5R"
			(at 0 0 0)
			(layer "F.Fab")
			(hide yes)
			(effects
				(font
					(size 1 1)
					(thickness 0.15)
				)
			)
		)
		(property "License" "Apache-2.0"
			(at 0 0 0)
			(layer "F.Fab")
			(hide yes)
			(effects
				(font
					(size 1 1)
					(thickness 0.15)
				)
			)
		)
		(property "MPN" "GRM155R61H104KE14D"
			(at 0 0 0)
			(layer "F.Fab")
			(hide yes)
			(effects
				(font
					(size 1 1)
					(thickness 0.15)
				)
			)
		)
		(property "Manufacturer" "Murata"
			(at 0 0 0)
			(layer "F.Fab")
			(hide yes)
			(effects
				(font
					(size 1 1)
					(thickness 0.15)
				)
			)
		)
		(property "Val" "100n"
			(at 0 0 0)
			(layer "F.Fab")
			(hide yes)
			(effects
				(font
					(size 1 1)
					(thickness 0.15)
				)
			)
		)
		(property "Voltage" "50V"
			(at 0 0 0)
			(layer "F.Fab")
			(hide yes)
			(effects
				(font
					(size 1 1)
					(thickness 0.15)
				)
			)
		)
		(sheetname "HDMI + Ethernet")
		(sheetfile "hdmi-ethernet.kicad_sch")
		(attr smd)
		(fp_rect
			(start -0.925 -0.47)
			(end 0.925 0.47)
			(stroke
				(width 0.05)
				(type default)
			)
			(fill no)
			(layer "F.CrtYd")
		)
		(fp_line
			(start -0.494 -0.25)
			(end 0.504 -0.25)
			(stroke
				(width 0.15)
				(type solid)
			)
			(layer "F.Fab")
		)
		(fp_line
			(start -0.494 0.248)
			(end -0.494 -0.25)
			(stroke
				(width 0.15)
				(type solid)
			)
			(layer "F.Fab")
		)
		(fp_line
			(start 0.504 -0.25)
			(end 0.504 0.248)
			(stroke
				(width 0.15)
				(type solid)
			)
			(layer "F.Fab")
		)
		(fp_line
			(start 0.504 0.248)
			(end -0.494 0.248)
			(stroke
				(width 0.15)
				(type solid)
			)
			(layer "F.Fab")
		)
		(pad "1" smd roundrect
			(at -0.48 0)
			(size 0.59 0.64)
			(layers "F.Cu" "F.Mask" "F.Paste")
			(roundrect_rratio 0.25)
			(net 1 "GND")
			(pintype "passive")
		)
		(pad "2" smd roundrect
			(at 0.48 0)
			(size 0.59 0.64)
			(layers "F.Cu" "F.Mask" "F.Paste")
			(roundrect_rratio 0.25)
			(net 728 "/HDMI + Ethernet/GBE_AVDDL{slash}PLL")
			(pintype "passive")
		)
	)
	(footprint "antmicro-footprints:C_0603_1608Metric"
		(layer "F.Cu")
		(at 259.45 146.35 -90)
		(descr "Capacitor SMD 0603")
		(tags "capacitor 0603")
		(property "Reference" "C218"
			(at 1 -0.35 90)
			(layer "F.SilkS")
			(effects
				(font
					(size 0.7 0.7)
					(thickness 0.15)
				)
				(justify right bottom)
			)
		)
		(property "Value" "C_10u_25V_0603"
			(at 0 1.6 90)
			(layer "F.Fab")
			(effects
				(font
					(size 0.7 0.7)
					(thickness 0.15)
				)
				(justify right bottom)
			)
		)
		(property "Description" "SMD Multilayer Ceramic Capacitor, 10 µF, 25 V, 0603 [1608 Metric], ± 20%, X5R, C"
			(at 0 0 270)
			(layer "F.Fab")
			(hide yes)
			(effects
				(font
					(size 1.27 1.27)
					(thickness 0.15)
				)
			)
		)
		(property "Author" "Antmicro"
			(at 113.1 405.8 0)
			(layer "F.Fab")
			(hide yes)
			(effects
				(font
					(size 1 1)
					(thickness 0.15)
				)
			)
		)
		(property "Dielectric" ""
			(at 113.1 405.8 0)
			(layer "F.Fab")
			(hide yes)
			(effects
				(font
					(size 1 1)
					(thickness 0.15)
				)
			)
		)
		(property "License" "Apache-2.0"
			(at 113.1 405.8 0)
			(layer "F.Fab")
			(hide yes)
			(effects
				(font
					(size 1 1)
					(thickness 0.15)
				)
			)
		)
		(property "MPN" "C1608X5R1E106M080AC"
			(at 113.1 405.8 0)
			(layer "F.Fab")
			(hide yes)
			(effects
				(font
					(size 1 1)
					(thickness 0.15)
				)
			)
		)
		(property "Manufacturer" "TDK"
			(at 113.1 405.8 0)
			(layer "F.Fab")
			(hide yes)
			(effects
				(font
					(size 1 1)
					(thickness 0.15)
				)
			)
		)
		(property "Val" "10u"
			(at 113.1 405.8 0)
			(layer "F.Fab")
			(hide yes)
			(effects
				(font
					(size 1 1)
					(thickness 0.15)
				)
			)
		)
		(property "Voltage" "25V"
			(at 113.1 405.8 0)
			(layer "F.Fab")
			(hide yes)
			(effects
				(font
					(size 1 1)
					(thickness 0.15)
				)
			)
		)
		(sheetname "USB PHY")
		(sheetfile "usb-phy.kicad_sch")
		(attr smd)
		(fp_line
			(start -0.15 0.4)
			(end 0.15 0.4)
			(stroke
				(width 0.15)
				(type solid)
			)
			(layer "F.SilkS")
		)
		(fp_line
			(start -0.15 -0.4)
			(end 0.15 -0.4)
			(stroke
				(width 0.15)
				(type solid)
			)
			(layer "F.SilkS")
		)
		(fp_rect
			(start -1.25 -0.65)
			(end 1.25 0.65)
			(stroke
				(width 0.05)
				(type solid)
			)
			(fill no)
			(layer "F.CrtYd")
		)
		(fp_rect
			(start -0.8 -0.4)
			(end 0.8 0.4)
			(stroke
				(width 0.15)
				(type solid)
			)
			(fill no)
			(layer "F.Fab")
		)
		(pad "1" smd roundrect
			(at -0.7 0 270)
			(size 0.8 1)
			(layers "F.Cu" "F.Mask" "F.Paste")
			(roundrect_rratio 0.2)
			(net 1 "GND")
			(pintype "passive")
		)
		(pad "2" smd roundrect
			(at 0.7 0 270)
			(size 0.8 1)
			(layers "F.Cu" "F.Mask" "F.Paste")
			(roundrect_rratio 0.2)
			(net 704 "/Power supply/USB_DBG_PD.VBUS")
			(pintype "passive")
		)
	)
	(footprint "antmicro-footprints:R_Array_4x0201_Panasonic_EXB18V"
		(layer "F.Cu")
		(at 247.4 122)
		(property "Reference" "R25"
			(at 1 -0.8 0)
			(layer "F.SilkS")
			(effects
				(font
					(size 0.7 0.7)
					(thickness 0.15)
				)
				(justify right bottom)
			)
		)
		(property "Value" "R_4x33R_0201_array"
			(at -1.1 1.8 0)
			(layer "F.Fab")
			(effects
				(font
					(size 0.7 0.7)
					(thickness 0.15)
				)
				(justify left bottom)
			)
		)
		(property "Description" "Fixed Network Resistor, 33 ohm, Isolated, 4 Resistors, 0502 [1406 Metric], Flat, ± 5%"
			(at 0 0 0)
			(layer "F.Fab")
			(hide yes)
			(effects
				(font
					(size 1.27 1.27)
					(thickness 0.15)
				)
			)
		)
		(property "Author" "Antmicro"
			(at 0 0 0)
			(layer "F.Fab")
			(hide yes)
			(effects
				(font
					(size 1 1)
					(thickness 0.15)
				)
			)
		)
		(property "License" "Apache-2.0"
			(at 0 0 0)
			(layer "F.Fab")
			(hide yes)
			(effects
				(font
					(size 1 1)
					(thickness 0.15)
				)
			)
		)
		(property "MPN" "EXB-18V330JX"
			(at 0 0 0)
			(layer "F.Fab")
			(hide yes)
			(effects
				(font
					(size 1 1)
					(thickness 0.15)
				)
			)
		)
		(property "Manufacturer" "Panasonic"
			(at 0 0 0)
			(layer "F.Fab")
			(hide yes)
			(effects
				(font
					(size 1 1)
					(thickness 0.15)
				)
			)
		)
		(property "Val" "R_4x33R_0201"
			(at 0 0 0)
			(layer "F.Fab")
			(hide yes)
			(effects
				(font
					(size 1 1)
					(thickness 0.15)
				)
			)
		)
		(sheetname "Supervisior MCU")
		(sheetfile "supervisor-mcu.kicad_sch")
		(attr smd)
		(fp_line
			(start -0.8 -0.45)
			(end -0.8 0.45)
			(stroke
				(width 0.12)
				(type solid)
			)
			(layer "F.SilkS")
		)
		(fp_line
			(start 0.8 -0.45)
			(end 0.8 0.45)
			(stroke
				(width 0.12)
				(type solid)
			)
			(layer "F.SilkS")
		)
		(fp_rect
			(start -0.898 -0.66)
			(end 0.898 0.65)
			(stroke
				(width 0.05)
				(type solid)
			)
			(fill no)
			(layer "F.CrtYd")
		)
		(pad "1" smd roundrect
			(at -0.6 0.298)
			(size 0.2 0.4)
			(layers "F.Cu" "F.Mask" "F.Paste")
			(roundrect_rratio 0.25)
			(net 265 "/Supervisior MCU/PWR_ON")
			(pinfunction "R1.1")
			(pintype "passive")
		)
		(pad "2" smd roundrect
			(at -0.202 0.298)
			(size 0.2 0.4)
			(layers "F.Cu" "F.Mask" "F.Paste")
			(roundrect_rratio 0.25)
			(net 1080 "/Supervisior MCU/USB_A19")
			(pinfunction "R2.1")
			(pintype "passive")
		)
		(pad "3" smd roundrect
			(at 0.2 0.298)
			(size 0.2 0.4)
			(layers "F.Cu" "F.Mask" "F.Paste")
			(roundrect_rratio 0.25)
			(net 1075 "/Supervisior MCU/USB_A14")
			(pinfunction "R3.1")
			(pintype "passive")
		)
		(pad "4" smd roundrect
			(at 0.598 0.298)
			(size 0.2 0.4)
			(layers "F.Cu" "F.Mask" "F.Paste")
			(roundrect_rratio 0.25)
			(net 1118 "/Supervisior MCU/USB_CLK0")
			(pinfunction "R4.1")
			(pintype "passive")
		)
		(pad "5" smd roundrect
			(at 0.598 -0.3)
			(size 0.2 0.4)
			(layers "F.Cu" "F.Mask" "F.Paste")
			(roundrect_rratio 0.25)
			(net 1365 "/SUP_MCU.CLKO")
			(pinfunction "R4.2")
			(pintype "passive")
		)
		(pad "6" smd roundrect
			(at 0.2 -0.3)
			(size 0.2 0.4)
			(layers "F.Cu" "F.Mask" "F.Paste")
			(roundrect_rratio 0.25)
			(net 1366 "/SUP_MCU.A14")
			(pinfunction "R3.2")
			(pintype "passive")
		)
		(pad "7" smd roundrect
			(at -0.202 -0.3)
			(size 0.2 0.4)
			(layers "F.Cu" "F.Mask" "F.Paste")
			(roundrect_rratio 0.25)
			(net 1367 "/SUP_MCU.A19")
			(pinfunction "R2.2")
			(pintype "passive")
		)
		(pad "8" smd roundrect
			(at -0.6 -0.3)
			(size 0.2 0.4)
			(layers "F.Cu" "F.Mask" "F.Paste")
			(roundrect_rratio 0.25)
			(net 357 "unconnected-(R25-R1.2-Pad8)")
			(pinfunction "R1.2")
			(pintype "passive+no_connect")
		)
	)
	(footprint "antmicro-footprints:C_1206_3216Metric"
		(layer "F.Cu")
		(at 196.08 177.039 -90)
		(descr "Capacitor SMD 1206")
		(tags "capacitor SMD 1206")
		(property "Reference" "C202"
			(at -4.589 -1.37 45)
			(layer "F.SilkS")
			(effects
				(font
					(size 0.7 0.7)
					(thickness 0.15)
				)
				(justify right bottom)
			)
		)
		(property "Value" "C_47u_16V_1206"
			(at 0 2.1 90)
			(layer "F.Fab")
			(effects
				(font
					(size 0.7 0.7)
					(thickness 0.15)
				)
				(justify right bottom)
			)
		)
		(property "Description" "SMD Multilayer Ceramic Capacitor, 47 µF, 16 V, 1206 [3216 Metric], ± 20%, X5R, C"
			(at 0 0 270)
			(layer "F.Fab")
			(hide yes)
			(effects
				(font
					(size 1.27 1.27)
					(thickness 0.15)
				)
			)
		)
		(property "Author" "Antmicro"
			(at 19.041 373.119 0)
			(layer "F.Fab")
			(hide yes)
			(effects
				(font
					(size 1 1)
					(thickness 0.15)
				)
			)
		)
		(property "Dielectric" "X5R"
			(at 19.041 373.119 0)
			(layer "F.Fab")
			(hide yes)
			(effects
				(font
					(size 1 1)
					(thickness 0.15)
				)
			)
		)
		(property "License" "Apache-2.0"
			(at 19.041 373.119 0)
			(layer "F.Fab")
			(hide yes)
			(effects
				(font
					(size 1 1)
					(thickness 0.15)
				)
			)
		)
		(property "MPN" "C3216X5R1C476M160AB"
			(at 19.041 373.119 0)
			(layer "F.Fab")
			(hide yes)
			(effects
				(font
					(size 1 1)
					(thickness 0.15)
				)
			)
		)
		(property "Manufacturer" "TDK"
			(at 19.041 373.119 0)
			(layer "F.Fab")
			(hide yes)
			(effects
				(font
					(size 1 1)
					(thickness 0.15)
				)
			)
		)
		(property "Val" "47u"
			(at 19.041 373.119 0)
			(layer "F.Fab")
			(hide yes)
			(effects
				(font
					(size 1 1)
					(thickness 0.15)
				)
			)
		)
		(property "Voltage" "16V"
			(at 19.041 373.119 0)
			(layer "F.Fab")
			(hide yes)
			(effects
				(font
					(size 1 1)
					(thickness 0.15)
				)
			)
		)
		(sheetname "Power supply")
		(sheetfile "power-supply.kicad_sch")
		(attr smd)
		(fp_line
			(start 0.8 0.901)
			(end -0.8 0.901)
			(stroke
				(width 0.15)
				(type solid)
			)
			(layer "F.SilkS")
		)
		(fp_line
			(start 0.8 -0.899)
			(end -0.8 -0.899)
			(stroke
				(width 0.15)
				(type solid)
			)
			(layer "F.SilkS")
		)
		(fp_rect
			(start -2.325 -1.15)
			(end 2.325 1.15)
			(stroke
				(width 0.05)
				(type default)
			)
			(fill no)
			(layer "F.CrtYd")
		)
		(fp_rect
			(start -1.6 -0.799)
			(end 1.6 0.801)
			(stroke
				(width 0.15)
				(type solid)
			)
			(fill no)
			(layer "F.Fab")
		)
		(pad "1" smd roundrect
			(at -1.5 0.001 270)
			(size 1.15 1.8)
			(layers "F.Cu" "F.Mask" "F.Paste")
			(roundrect_rratio 0.25)
			(net 1 "GND")
			(pintype "passive")
		)
		(pad "2" smd roundrect
			(at 1.5 0.001 270)
			(size 1.15 1.8)
			(layers "F.Cu" "F.Mask" "F.Paste")
			(roundrect_rratio 0.25)
			(net 956 "/DC-DC Converters/POE_DC")
			(pintype "passive")
		)
	)
	(footprint "antmicro-footprints:R_0402_1005Metric"
		(layer "F.Cu")
		(at 236.35 144.45 180)
		(descr "Resistor SMD 0402")
		(tags "resistor SMD 0402")
		(property "Reference" "R184"
			(at 1.05 -4.45 180)
			(layer "F.SilkS")
			(effects
				(font
					(size 0.7 0.7)
					(thickness 0.15)
				)
				(justify left bottom)
			)
		)
		(property "Value" "R_33R_0402"
			(at 0 1.4 180)
			(layer "F.Fab")
			(effects
				(font
					(size 0.7 0.7)
					(thickness 0.15)
				)
				(justify left bottom)
			)
		)
		(property "Description" "SMD Chip Resistor, 33 ohm, ± 1%, 62.5 mW, 0402 [1005 Metric], Thick Film, General Purpose"
			(at 0 0 180)
			(layer "F.Fab")
			(hide yes)
			(effects
				(font
					(size 1.27 1.27)
					(thickness 0.15)
				)
			)
		)
		(property "Author" "Antmicro"
			(at 472.7 288.9 0)
			(layer "F.Fab")
			(hide yes)
			(effects
				(font
					(size 1 1)
					(thickness 0.15)
				)
			)
		)
		(property "License" "Apache-2.0"
			(at 472.7 288.9 0)
			(layer "F.Fab")
			(hide yes)
			(effects
				(font
					(size 1 1)
					(thickness 0.15)
				)
			)
		)
		(property "MPN" "CR0402-FX-33R0GLF"
			(at 472.7 288.9 0)
			(layer "F.Fab")
			(hide yes)
			(effects
				(font
					(size 1 1)
					(thickness 0.15)
				)
			)
		)
		(property "Manufacturer" "Bourns"
			(at 472.7 288.9 0)
			(layer "F.Fab")
			(hide yes)
			(effects
				(font
					(size 1 1)
					(thickness 0.15)
				)
			)
		)
		(property "Tolerance" "1%"
			(at 472.7 288.9 0)
			(layer "F.Fab")
			(hide yes)
			(effects
				(font
					(size 1 1)
					(thickness 0.15)
				)
			)
		)
		(property "Val" "33R"
			(at 472.7 288.9 0)
			(layer "F.Fab")
			(hide yes)
			(effects
				(font
					(size 1 1)
					(thickness 0.15)
				)
			)
		)
		(sheetname "USB PHY")
		(sheetfile "usb-phy.kicad_sch")
		(attr smd)
		(fp_rect
			(start -0.925 -0.47)
			(end 0.925 0.47)
			(stroke
				(width 0.05)
				(type default)
			)
			(fill no)
			(layer "F.CrtYd")
		)
		(fp_rect
			(start -0.5 -0.25)
			(end 0.5 0.25)
			(stroke
				(width 0.15)
				(type solid)
			)
			(fill no)
			(layer "F.Fab")
		)
		(pad "1" smd roundrect
			(at -0.48 0 180)
			(size 0.59 0.64)
			(layers "F.Cu" "F.Mask" "F.Paste")
			(roundrect_rratio 0.25)
			(net 376 "Net-(U23-B3Y)")
			(pintype "passive")
		)
		(pad "2" smd roundrect
			(at 0.48 0 180)
			(size 0.59 0.64)
			(layers "F.Cu" "F.Mask" "F.Paste")
			(roundrect_rratio 0.25)
			(net 1297 "/USB_SPI.~{CS}")
			(pintype "passive")
		)
	)
	(footprint "antmicro-footprints:C_0805_2012Metric"
		(layer "F.Cu")
		(at 159.0125 178.2)
		(descr "Capacitor SMD 0805")
		(tags "capacitor SMD 0805")
		(property "Reference" "C319"
			(at 2.4875 0.8 0)
			(layer "F.SilkS")
			(effects
				(font
					(size 0.7 0.7)
					(thickness 0.15)
				)
				(justify left bottom)
			)
		)
		(property "Value" "C_22u_25V_0805"
			(at 0 1.947 0)
			(layer "F.Fab")
			(effects
				(font
					(size 0.7 0.7)
					(thickness 0.15)
				)
				(justify left bottom)
			)
		)
		(property "Description" "SMT Multilayer Ceramic Capacitor, 22uF, +/-20%, 25V, X5R, 0805 [2012 Metric]"
			(at 0 0 0)
			(layer "F.Fab")
			(hide yes)
			(effects
				(font
					(size 1.27 1.27)
					(thickness 0.15)
				)
			)
		)
		(property "Author" "Antmicro"
			(at 0 0 0)
			(layer "F.Fab")
			(hide yes)
			(effects
				(font
					(size 1 1)
					(thickness 0.15)
				)
			)
		)
		(property "Dielectric" "X5R"
			(at 0 0 0)
			(layer "F.Fab")
			(hide yes)
			(effects
				(font
					(size 1 1)
					(thickness 0.15)
				)
			)
		)
		(property "License" "Apache-2.0"
			(at 0 0 0)
			(layer "F.Fab")
			(hide yes)
			(effects
				(font
					(size 1 1)
					(thickness 0.15)
				)
			)
		)
		(property "MPN" "CL21A226MAYNNNE"
			(at 0 0 0)
			(layer "F.Fab")
			(hide yes)
			(effects
				(font
					(size 1 1)
					(thickness 0.15)
				)
			)
		)
		(property "Manufacturer" "Samsung Electro-Mechanics"
			(at 0 0 0)
			(layer "F.Fab")
			(hide yes)
			(effects
				(font
					(size 1 1)
					(thickness 0.15)
				)
			)
		)
		(property "Val" "22u"
			(at 0 0 0)
			(layer "F.Fab")
			(hide yes)
			(effects
				(font
					(size 1 1)
					(thickness 0.15)
				)
			)
		)
		(property "Voltage" "25V"
			(at 0 0 0)
			(layer "F.Fab")
			(hide yes)
			(effects
				(font
					(size 1 1)
					(thickness 0.15)
				)
			)
		)
		(sheetname "DC-DC Converters")
		(sheetfile "dc-dc.kicad_sch")
		(attr smd)
		(fp_line
			(start -0.3 -0.7)
			(end 0.3 -0.7)
			(stroke
				(width 0.15)
				(type solid)
			)
			(layer "F.SilkS")
		)
		(fp_line
			(start -0.3 0.7)
			(end 0.3 0.7)
			(stroke
				(width 0.15)
				(type solid)
			)
			(layer "F.SilkS")
		)
		(fp_rect
			(start 1.95 -0.9)
			(end -1.95 0.9)
			(stroke
				(width 0.05)
				(type default)
			)
			(fill no)
			(layer "F.CrtYd")
		)
		(fp_rect
			(start -0.95 -0.675)
			(end 0.95 0.675)
			(stroke
				(width 0.15)
				(type solid)
			)
			(fill no)
			(layer "F.Fab")
		)
		(pad "1" smd roundrect
			(at -1.1 0)
			(size 1.2 1.3)
			(layers "F.Cu" "F.Mask" "F.Paste")
			(roundrect_rratio 0.25)
			(net 1 "GND")
			(pintype "passive")
		)
		(pad "2" smd roundrect
			(at 1.1 0)
			(size 1.2 1.3)
			(layers "F.Cu" "F.Mask" "F.Paste")
			(roundrect_rratio 0.25)
			(net 702 "VDC")
			(pintype "passive")
		)
	)
	(footprint "antmicro-footprints:SC70-3"
		(layer "F.Cu")
		(at 258.4 93.4)
		(property "Reference" "Q13"
			(at -1.6 1.1 90)
			(layer "F.SilkS")
			(effects
				(font
					(size 0.7 0.7)
					(thickness 0.15)
				)
				(justify left bottom)
			)
		)
		(property "Value" "BSS138PW"
			(at 0 2.3 0)
			(layer "F.Fab")
			(effects
				(font
					(size 0.7 0.7)
					(thickness 0.15)
				)
				(justify left bottom)
			)
		)
		(property "Description" "Power MOSFET, N Channel, 60 V, 320 mA, 0.9 ohm, SOT-323, Surface Mount"
			(at 0 0 0)
			(layer "F.Fab")
			(hide yes)
			(effects
				(font
					(size 1.27 1.27)
					(thickness 0.15)
				)
			)
		)
		(property "Author" "Antmicro"
			(at 0 0 0)
			(layer "F.Fab")
			(hide yes)
			(effects
				(font
					(size 1 1)
					(thickness 0.15)
				)
			)
		)
		(property "License" "Apache-2.0"
			(at 0 0 0)
			(layer "F.Fab")
			(hide yes)
			(effects
				(font
					(size 1 1)
					(thickness 0.15)
				)
			)
		)
		(property "MPN" "BSS138PW"
			(at 0 0 0)
			(layer "F.Fab")
			(hide yes)
			(effects
				(font
					(size 1 1)
					(thickness 0.15)
				)
			)
		)
		(property "Manufacturer" "Nexperia"
			(at 0 0 0)
			(layer "F.Fab")
			(hide yes)
			(effects
				(font
					(size 1 1)
					(thickness 0.15)
				)
			)
		)
		(sheetname "User GPIO + LED + button + DIP switch")
		(sheetfile "user-gpio.kicad_sch")
		(attr smd)
		(fp_line
			(start -0.3 -1)
			(end 0.627 -0.999)
			(stroke
				(width 0.15)
				(type solid)
			)
			(layer "F.SilkS")
		)
		(fp_line
			(start -0.3 1)
			(end 0.627 1.001)
			(stroke
				(width 0.15)
				(type solid)
			)
			(layer "F.SilkS")
		)
		(fp_line
			(start 0.627 -0.6)
			(end 0.627 -0.999)
			(stroke
				(width 0.15)
				(type solid)
			)
			(layer "F.SilkS")
		)
		(fp_line
			(start 0.627 0.6)
			(end 0.627 1.001)
			(stroke
				(width 0.15)
				(type solid)
			)
			(layer "F.SilkS")
		)
		(fp_line
			(start -1.4 1)
			(end -1.4 -1)
			(stroke
				(width 0.05)
				(type solid)
			)
			(layer "F.CrtYd")
		)
		(fp_line
			(start -0.9 -1.3)
			(end -0.9 -1)
			(stroke
				(width 0.05)
				(type solid)
			)
			(layer "F.CrtYd")
		)
		(fp_line
			(start -0.9 -1.3)
			(end 0.9 -1.3)
			(stroke
				(width 0.05)
				(type solid)
			)
			(layer "F.CrtYd")
		)
		(fp_line
			(start -0.9 -1)
			(end -1.4 -1)
			(stroke
				(width 0.05)
				(type solid)
			)
			(layer "F.CrtYd")
		)
		(fp_line
			(start -0.9 1)
			(end -1.4 1)
			(stroke
				(width 0.05)
				(type solid)
			)
			(layer "F.CrtYd")
		)
		(fp_line
			(start -0.9 1.3)
			(end -0.9 1)
			(stroke
				(width 0.05)
				(type solid)
			)
			(layer "F.CrtYd")
		)
		(fp_line
			(start 0.9 -1.3)
			(end 0.9 -0.4)
			(stroke
				(width 0.05)
				(type solid)
			)
			(layer "F.CrtYd")
		)
		(fp_line
			(start 0.9 -0.4)
			(end 1.4 -0.4)
			(stroke
				(width 0.05)
				(type solid)
			)
			(layer "F.CrtYd")
		)
		(fp_line
			(start 0.9 0.4)
			(end 0.9 1.3)
			(stroke
				(width 0.05)
				(type solid)
			)
			(layer "F.CrtYd")
		)
		(fp_line
			(start 0.9 1.3)
			(end -0.9 1.3)
			(stroke
				(width 0.05)
				(type solid)
			)
			(layer "F.CrtYd")
		)
		(fp_line
			(start 1.4 -0.4)
			(end 1.4 0.4)
			(stroke
				(width 0.05)
				(type solid)
			)
			(layer "F.CrtYd")
		)
		(fp_line
			(start 1.4 0.4)
			(end 0.9 0.4)
			(stroke
				(width 0.05)
				(type solid)
			)
			(layer "F.CrtYd")
		)
		(fp_rect
			(start -0.623 -0.999)
			(end 0.627 1.001)
			(stroke
				(width 0.15)
				(type solid)
			)
			(fill no)
			(layer "F.Fab")
		)
		(pad "1" smd rect
			(at -1.051 -0.65 90)
			(size 0.6 0.6)
			(layers "F.Cu" "F.Mask" "F.Paste")
			(net 1303 "/USER_IO.LED_GREEN4")
			(pinfunction "G")
			(pintype "passive")
		)
		(pad "2" smd rect
			(at -1.051 0.65 90)
			(size 0.6 0.6)
			(layers "F.Cu" "F.Mask" "F.Paste")
			(net 1 "GND")
			(pinfunction "S")
			(pintype "passive")
		)
		(pad "3" smd rect
			(at 1.05 0 90)
			(size 0.6 0.6)
			(layers "F.Cu" "F.Mask" "F.Paste")
			(net 27 "Net-(D22-C)")
			(pinfunction "D")
			(pintype "passive")
		)
	)
	(footprint "antmicro-footprints:C_0402_1005Metric"
		(layer "F.Cu")
		(at 262.145 139.3 90)
		(descr "Capacitor SMD 0402")
		(tags "capacitor SMD 0402")
		(property "Reference" "C235"
			(at -3.6 0.355 90)
			(layer "F.SilkS")
			(effects
				(font
					(size 0.7 0.7)
					(thickness 0.15)
				)
				(justify left bottom)
			)
		)
		(property "Value" "C_22p_0402"
			(at 0 1.4 90)
			(layer "F.Fab")
			(effects
				(font
					(size 0.7 0.7)
					(thickness 0.15)
				)
				(justify left bottom)
			)
		)
		(property "Description" "SMD Multilayer Ceramic Capacitor, 22 pF, 50 V, 0402 [1005 Metric], ± 5%, C0G / NP0, CC Series"
			(at 0 0 90)
			(layer "F.Fab")
			(hide yes)
			(effects
				(font
					(size 1.27 1.27)
					(thickness 0.15)
				)
			)
		)
		(property "Author" "Antmicro"
			(at 401.445 -122.845 0)
			(layer "F.Fab")
			(hide yes)
			(effects
				(font
					(size 1 1)
					(thickness 0.15)
				)
			)
		)
		(property "Dielectric" ""
			(at 401.445 -122.845 0)
			(layer "F.Fab")
			(hide yes)
			(effects
				(font
					(size 1 1)
					(thickness 0.15)
				)
			)
		)
		(property "License" "Apache-2.0"
			(at 401.445 -122.845 0)
			(layer "F.Fab")
			(hide yes)
			(effects
				(font
					(size 1 1)
					(thickness 0.15)
				)
			)
		)
		(property "MPN" "CC0402JRNPO9BN220"
			(at 401.445 -122.845 0)
			(layer "F.Fab")
			(hide yes)
			(effects
				(font
					(size 1 1)
					(thickness 0.15)
				)
			)
		)
		(property "Manufacturer" "YAGEO"
			(at 401.445 -122.845 0)
			(layer "F.Fab")
			(hide yes)
			(effects
				(font
					(size 1 1)
					(thickness 0.15)
				)
			)
		)
		(property "Val" "22p"
			(at 401.445 -122.845 0)
			(layer "F.Fab")
			(hide yes)
			(effects
				(font
					(size 1 1)
					(thickness 0.15)
				)
			)
		)
		(property "Voltage" ""
			(at 401.445 -122.845 0)
			(layer "F.Fab")
			(hide yes)
			(effects
				(font
					(size 1 1)
					(thickness 0.15)
				)
			)
		)
		(sheetname "USB PHY")
		(sheetfile "usb-phy.kicad_sch")
		(attr smd)
		(fp_rect
			(start -0.925 -0.47)
			(end 0.925 0.47)
			(stroke
				(width 0.05)
				(type default)
			)
			(fill no)
			(layer "F.CrtYd")
		)
		(fp_line
			(start 0.504 -0.25)
			(end 0.504 0.248)
			(stroke
				(width 0.15)
				(type solid)
			)
			(layer "F.Fab")
		)
		(fp_line
			(start -0.494 -0.25)
			(end 0.504 -0.25)
			(stroke
				(width 0.15)
				(type solid)
			)
			(layer "F.Fab")
		)
		(fp_line
			(start 0.504 0.248)
			(end -0.494 0.248)
			(stroke
				(width 0.15)
				(type solid)
			)
			(layer "F.Fab")
		)
		(fp_line
			(start -0.494 0.248)
			(end -0.494 -0.25)
			(stroke
				(width 0.15)
				(type solid)
			)
			(layer "F.Fab")
		)
		(pad "1" smd roundrect
			(at -0.48 0 90)
			(size 0.59 0.64)
			(layers "F.Cu" "F.Mask" "F.Paste")
			(roundrect_rratio 0.25)
			(net 1 "GND")
			(pintype "passive")
		)
		(pad "2" smd roundrect
			(at 0.48 0 90)
			(size 0.59 0.64)
			(layers "F.Cu" "F.Mask" "F.Paste")
			(roundrect_rratio 0.25)
			(net 713 "/USB PHY/FTDI_XO")
			(pintype "passive")
		)
	)
	(footprint "antmicro-footprints:C_0402_1005Metric"
		(layer "F.Cu")
		(at 219.2 140.975)
		(descr "Capacitor SMD 0402")
		(tags "capacitor SMD 0402")
		(property "Reference" "C371"
			(at -3.65 0.425 0)
			(layer "F.SilkS")
			(effects
				(font
					(size 0.7 0.7)
					(thickness 0.15)
				)
				(justify left bottom)
			)
		)
		(property "Value" "C_100n_0402"
			(at 0 1.4 0)
			(layer "F.Fab")
			(effects
				(font
					(size 0.7 0.7)
					(thickness 0.15)
				)
				(justify left bottom)
			)
		)
		(property "Description" "SMD Multilayer Ceramic Capacitor, 0.1 µF, 50 V, 0402 [1005 Metric], ± 10%, X5R, GRM Series"
			(at 0 0 0)
			(layer "F.Fab")
			(hide yes)
			(effects
				(font
					(size 1.27 1.27)
					(thickness 0.15)
				)
			)
		)
		(property "Author" "Antmicro"
			(at 0 0 0)
			(layer "F.Fab")
			(hide yes)
			(effects
				(font
					(size 1 1)
					(thickness 0.15)
				)
			)
		)
		(property "Dielectric" "X5R"
			(at 0 0 0)
			(layer "F.Fab")
			(hide yes)
			(effects
				(font
					(size 1 1)
					(thickness 0.15)
				)
			)
		)
		(property "License" "Apache-2.0"
			(at 0 0 0)
			(layer "F.Fab")
			(hide yes)
			(effects
				(font
					(size 1 1)
					(thickness 0.15)
				)
			)
		)
		(property "MPN" "GRM155R61H104KE14D"
			(at 0 0 0)
			(layer "F.Fab")
			(hide yes)
			(effects
				(font
					(size 1 1)
					(thickness 0.15)
				)
			)
		)
		(property "Manufacturer" "Murata"
			(at 0 0 0)
			(layer "F.Fab")
			(hide yes)
			(effects
				(font
					(size 1 1)
					(thickness 0.15)
				)
			)
		)
		(property "Val" "100n"
			(at 0 0 0)
			(layer "F.Fab")
			(hide yes)
			(effects
				(font
					(size 1 1)
					(thickness 0.15)
				)
			)
		)
		(property "Voltage" "50V"
			(at 0 0 0)
			(layer "F.Fab")
			(hide yes)
			(effects
				(font
					(size 1 1)
					(thickness 0.15)
				)
			)
		)
		(sheetname "Clocks")
		(sheetfile "clocks.kicad_sch")
		(attr smd)
		(fp_rect
			(start -0.925 -0.47)
			(end 0.925 0.47)
			(stroke
				(width 0.05)
				(type default)
			)
			(fill no)
			(layer "F.CrtYd")
		)
		(fp_line
			(start -0.494 -0.25)
			(end 0.504 -0.25)
			(stroke
				(width 0.15)
				(type solid)
			)
			(layer "F.Fab")
		)
		(fp_line
			(start -0.494 0.248)
			(end -0.494 -0.25)
			(stroke
				(width 0.15)
				(type solid)
			)
			(layer "F.Fab")
		)
		(fp_line
			(start 0.504 -0.25)
			(end 0.504 0.248)
			(stroke
				(width 0.15)
				(type solid)
			)
			(layer "F.Fab")
		)
		(fp_line
			(start 0.504 0.248)
			(end -0.494 0.248)
			(stroke
				(width 0.15)
				(type solid)
			)
			(layer "F.Fab")
		)
		(pad "1" smd roundrect
			(at -0.48 0)
			(size 0.59 0.64)
			(layers "F.Cu" "F.Mask" "F.Paste")
			(roundrect_rratio 0.25)
			(net 24 "+3V3")
			(pintype "passive")
		)
		(pad "2" smd roundrect
			(at 0.48 0)
			(size 0.59 0.64)
			(layers "F.Cu" "F.Mask" "F.Paste")
			(roundrect_rratio 0.25)
			(net 1 "GND")
			(pintype "passive")
		)
	)
	(footprint "antmicro-footprints:R_0402_1005Metric"
		(layer "F.Cu")
		(at 189.915 152.885001 180)
		(descr "Resistor SMD 0402")
		(tags "resistor SMD 0402")
		(property "Reference" "R352"
			(at 1.415 -1.264999 180)
			(layer "F.SilkS")
			(effects
				(font
					(size 0.7 0.7)
					(thickness 0.15)
				)
				(justify left bottom)
			)
		)
		(property "Value" "R_10k_0402"
			(at 0 1.4 180)
			(layer "F.Fab")
			(effects
				(font
					(size 0.7 0.7)
					(thickness 0.15)
				)
				(justify left bottom)
			)
		)
		(property "Description" "SMD Chip Resistor, 10 kohm, ± 1%, 62.5 mW, 0402 [1005 Metric], Thick Film, General Purpose"
			(at 0 0 180)
			(layer "F.Fab")
			(hide yes)
			(effects
				(font
					(size 1.27 1.27)
					(thickness 0.15)
				)
			)
		)
		(property "Author" "Antmicro"
			(at 379.83 305.770002 0)
			(layer "F.Fab")
			(hide yes)
			(effects
				(font
					(size 1 1)
					(thickness 0.15)
				)
			)
		)
		(property "License" "Apache-2.0"
			(at 379.83 305.770002 0)
			(layer "F.Fab")
			(hide yes)
			(effects
				(font
					(size 1 1)
					(thickness 0.15)
				)
			)
		)
		(property "MPN" "CR0402-FX-1002GLF"
			(at 379.83 305.770002 0)
			(layer "F.Fab")
			(hide yes)
			(effects
				(font
					(size 1 1)
					(thickness 0.15)
				)
			)
		)
		(property "Manufacturer" "Bourns"
			(at 379.83 305.770002 0)
			(layer "F.Fab")
			(hide yes)
			(effects
				(font
					(size 1 1)
					(thickness 0.15)
				)
			)
		)
		(property "Tolerance" "1%"
			(at 379.83 305.770002 0)
			(layer "F.Fab")
			(hide yes)
			(effects
				(font
					(size 1 1)
					(thickness 0.15)
				)
			)
		)
		(property "Val" "10k"
			(at 379.83 305.770002 0)
			(layer "F.Fab")
			(hide yes)
			(effects
				(font
					(size 1 1)
					(thickness 0.15)
				)
			)
		)
		(sheetname "Clocks")
		(sheetfile "clocks.kicad_sch")
		(attr smd)
		(fp_rect
			(start -0.925 -0.47)
			(end 0.925 0.47)
			(stroke
				(width 0.05)
				(type default)
			)
			(fill no)
			(layer "F.CrtYd")
		)
		(fp_rect
			(start -0.5 -0.25)
			(end 0.5 0.25)
			(stroke
				(width 0.15)
				(type solid)
			)
			(fill no)
			(layer "F.Fab")
		)
		(pad "1" smd roundrect
			(at -0.48 0 180)
			(size 0.59 0.64)
			(layers "F.Cu" "F.Mask" "F.Paste")
			(roundrect_rratio 0.25)
			(net 1 "GND")
			(pintype "passive")
		)
		(pad "2" smd roundrect
			(at 0.48 0 180)
			(size 0.59 0.64)
			(layers "F.Cu" "F.Mask" "F.Paste")
			(roundrect_rratio 0.25)
			(net 640 "/Clocks/LVDS_XO_200M_ENA")
			(pintype "passive")
		)
	)
	(footprint "antmicro-footprints:SC70-3"
		(layer "F.Cu")
		(at 258.4 95.8)
		(property "Reference" "Q14"
			(at -1.6 1.1 90)
			(layer "F.SilkS")
			(effects
				(font
					(size 0.7 0.7)
					(thickness 0.15)
				)
				(justify left bottom)
			)
		)
		(property "Value" "BSS138PW"
			(at 0 2.3 0)
			(layer "F.Fab")
			(effects
				(font
					(size 0.7 0.7)
					(thickness 0.15)
				)
				(justify left bottom)
			)
		)
		(property "Description" "Power MOSFET, N Channel, 60 V, 320 mA, 0.9 ohm, SOT-323, Surface Mount"
			(at 0 0 0)
			(layer "F.Fab")
			(hide yes)
			(effects
				(font
					(size 1.27 1.27)
					(thickness 0.15)
				)
			)
		)
		(property "Author" "Antmicro"
			(at 0 0 0)
			(layer "F.Fab")
			(hide yes)
			(effects
				(font
					(size 1 1)
					(thickness 0.15)
				)
			)
		)
		(property "License" "Apache-2.0"
			(at 0 0 0)
			(layer "F.Fab")
			(hide yes)
			(effects
				(font
					(size 1 1)
					(thickness 0.15)
				)
			)
		)
		(property "MPN" "BSS138PW"
			(at 0 0 0)
			(layer "F.Fab")
			(hide yes)
			(effects
				(font
					(size 1 1)
					(thickness 0.15)
				)
			)
		)
		(property "Manufacturer" "Nexperia"
			(at 0 0 0)
			(layer "F.Fab")
			(hide yes)
			(effects
				(font
					(size 1 1)
					(thickness 0.15)
				)
			)
		)
		(sheetname "User GPIO + LED + button + DIP switch")
		(sheetfile "user-gpio.kicad_sch")
		(attr smd)
		(fp_line
			(start -0.3 -1)
			(end 0.627 -0.999)
			(stroke
				(width 0.15)
				(type solid)
			)
			(layer "F.SilkS")
		)
		(fp_line
			(start -0.3 1)
			(end 0.627 1.001)
			(stroke
				(width 0.15)
				(type solid)
			)
			(layer "F.SilkS")
		)
		(fp_line
			(start 0.627 -0.6)
			(end 0.627 -0.999)
			(stroke
				(width 0.15)
				(type solid)
			)
			(layer "F.SilkS")
		)
		(fp_line
			(start 0.627 0.6)
			(end 0.627 1.001)
			(stroke
				(width 0.15)
				(type solid)
			)
			(layer "F.SilkS")
		)
		(fp_line
			(start -1.4 1)
			(end -1.4 -1)
			(stroke
				(width 0.05)
				(type solid)
			)
			(layer "F.CrtYd")
		)
		(fp_line
			(start -0.9 -1.3)
			(end -0.9 -1)
			(stroke
				(width 0.05)
				(type solid)
			)
			(layer "F.CrtYd")
		)
		(fp_line
			(start -0.9 -1.3)
			(end 0.9 -1.3)
			(stroke
				(width 0.05)
				(type solid)
			)
			(layer "F.CrtYd")
		)
		(fp_line
			(start -0.9 -1)
			(end -1.4 -1)
			(stroke
				(width 0.05)
				(type solid)
			)
			(layer "F.CrtYd")
		)
		(fp_line
			(start -0.9 1)
			(end -1.4 1)
			(stroke
				(width 0.05)
				(type solid)
			)
			(layer "F.CrtYd")
		)
		(fp_line
			(start -0.9 1.3)
			(end -0.9 1)
			(stroke
				(width 0.05)
				(type solid)
			)
			(layer "F.CrtYd")
		)
		(fp_line
			(start 0.9 -1.3)
			(end 0.9 -0.4)
			(stroke
				(width 0.05)
				(type solid)
			)
			(layer "F.CrtYd")
		)
		(fp_line
			(start 0.9 -0.4)
			(end 1.4 -0.4)
			(stroke
				(width 0.05)
				(type solid)
			)
			(layer "F.CrtYd")
		)
		(fp_line
			(start 0.9 0.4)
			(end 0.9 1.3)
			(stroke
				(width 0.05)
				(type solid)
			)
			(layer "F.CrtYd")
		)
		(fp_line
			(start 0.9 1.3)
			(end -0.9 1.3)
			(stroke
				(width 0.05)
				(type solid)
			)
			(layer "F.CrtYd")
		)
		(fp_line
			(start 1.4 -0.4)
			(end 1.4 0.4)
			(stroke
				(width 0.05)
				(type solid)
			)
			(layer "F.CrtYd")
		)
		(fp_line
			(start 1.4 0.4)
			(end 0.9 0.4)
			(stroke
				(width 0.05)
				(type solid)
			)
			(layer "F.CrtYd")
		)
		(fp_rect
			(start -0.623 -0.999)
			(end 0.627 1.001)
			(stroke
				(width 0.15)
				(type solid)
			)
			(fill no)
			(layer "F.Fab")
		)
		(pad "1" smd rect
			(at -1.051 -0.65 90)
			(size 0.6 0.6)
			(layers "F.Cu" "F.Mask" "F.Paste")
			(net 1304 "/USER_IO.LED_GREEN5")
			(pinfunction "G")
			(pintype "passive")
		)
		(pad "2" smd rect
			(at -1.051 0.65 90)
			(size 0.6 0.6)
			(layers "F.Cu" "F.Mask" "F.Paste")
			(net 1 "GND")
			(pinfunction "S")
			(pintype "passive")
		)
		(pad "3" smd rect
			(at 1.05 0 90)
			(size 0.6 0.6)
			(layers "F.Cu" "F.Mask" "F.Paste")
			(net 768 "Net-(D23-C)")
			(pinfunction "D")
			(pintype "passive")
		)
	)
	(footprint "antmicro-footprints:R_0402_1005Metric"
		(layer "F.Cu")
		(at 242.599 115.404 90)
		(descr "Resistor SMD 0402")
		(tags "resistor SMD 0402")
		(property "Reference" "R349"
			(at -1.496 -0.549 90)
			(unlocked yes)
			(layer "F.SilkS")
			(effects
				(font
					(size 0.7 0.7)
					(thickness 0.15)
				)
				(justify left bottom)
			)
		)
		(property "Value" "R_0R_0402"
			(at 0 1.4 90)
			(layer "F.Fab")
			(effects
				(font
					(size 0.7 0.7)
					(thickness 0.15)
				)
				(justify left bottom)
			)
		)
		(property "Description" "SMD Chip Resistor, Jumper, 0 ohm, 100 mW, 0402 [1005 Metric], Thick Film, General Purpose"
			(at 0 0 90)
			(layer "F.Fab")
			(hide yes)
			(effects
				(font
					(size 1.27 1.27)
					(thickness 0.15)
				)
			)
		)
		(property "Author" "Antmicro"
			(at 358.003 -127.195 0)
			(layer "F.Fab")
			(hide yes)
			(effects
				(font
					(size 1 1)
					(thickness 0.15)
				)
			)
		)
		(property "Current" "1A"
			(at 358.003 -127.195 0)
			(layer "F.Fab")
			(hide yes)
			(effects
				(font
					(size 1 1)
					(thickness 0.15)
				)
			)
		)
		(property "License" "Apache-2.0"
			(at 358.003 -127.195 0)
			(layer "F.Fab")
			(hide yes)
			(effects
				(font
					(size 1 1)
					(thickness 0.15)
				)
			)
		)
		(property "MPN" "ERJ2GE0R00X"
			(at 358.003 -127.195 0)
			(layer "F.Fab")
			(hide yes)
			(effects
				(font
					(size 1 1)
					(thickness 0.15)
				)
			)
		)
		(property "Manufacturer" "Panasonic"
			(at 358.003 -127.195 0)
			(layer "F.Fab")
			(hide yes)
			(effects
				(font
					(size 1 1)
					(thickness 0.15)
				)
			)
		)
		(property "Tolerance" ""
			(at 358.003 -127.195 0)
			(layer "F.Fab")
			(hide yes)
			(effects
				(font
					(size 1 1)
					(thickness 0.15)
				)
			)
		)
		(property "Val" "0R"
			(at 358.003 -127.195 0)
			(layer "F.Fab")
			(hide yes)
			(effects
				(font
					(size 1 1)
					(thickness 0.15)
				)
			)
		)
		(sheetname "USB PHY")
		(sheetfile "usb-phy.kicad_sch")
		(attr smd)
		(fp_rect
			(start -0.925 -0.47)
			(end 0.925 0.47)
			(stroke
				(width 0.05)
				(type default)
			)
			(fill no)
			(layer "F.CrtYd")
		)
		(fp_rect
			(start -0.5 -0.25)
			(end 0.5 0.25)
			(stroke
				(width 0.15)
				(type solid)
			)
			(fill no)
			(layer "F.Fab")
		)
		(pad "1" smd roundrect
			(at -0.48 0 90)
			(size 0.59 0.64)
			(layers "F.Cu" "F.Mask" "F.Paste")
			(roundrect_rratio 0.25)
			(net 570 "/FPGA Bank 12 & 13/USB_USER.VBUS_PEN")
			(pintype "passive")
		)
		(pad "2" smd roundrect
			(at 0.48 0 90)
			(size 0.59 0.64)
			(layers "F.Cu" "F.Mask" "F.Paste")
			(roundrect_rratio 0.25)
			(net 385 "Net-(U43-EN)")
			(pintype "passive")
		)
	)
	(footprint "antmicro-footprints:TP_1206_SMD_RCW-0C"
		(layer "F.Cu")
		(at 167.78 164.65)
		(property "Reference" "TP9"
			(at 2.77 0.95 90)
			(layer "F.SilkS")
			(effects
				(font
					(size 0.7 0.7)
					(thickness 0.15)
				)
				(justify left bottom)
			)
		)
		(property "Value" "TP_1206_SMD_RCW-0C"
			(at -4.68 2.25 0)
			(layer "F.Fab")
			(effects
				(font
					(size 0.7 0.7)
					(thickness 0.15)
				)
				(justify left bottom)
			)
		)
		(property "Description" "Circuit Probe Pad, SMD, Test Point, 1206"
			(at 0 0 0)
			(layer "F.Fab")
			(hide yes)
			(effects
				(font
					(size 1.27 1.27)
					(thickness 0.15)
				)
			)
		)
		(property "Author" "Antmicro"
			(at 0 0 0)
			(layer "F.Fab")
			(hide yes)
			(effects
				(font
					(size 1 1)
					(thickness 0.15)
				)
			)
		)
		(property "License" "Apache-2.0"
			(at 0 0 0)
			(layer "F.Fab")
			(hide yes)
			(effects
				(font
					(size 1 1)
					(thickness 0.15)
				)
			)
		)
		(property "MPN" "RCW-0C"
			(at 0 0 0)
			(layer "F.Fab")
			(hide yes)
			(effects
				(font
					(size 1 1)
					(thickness 0.15)
				)
			)
		)
		(property "Manufacturer" "TE Connectivity"
			(at 0 0 0)
			(layer "F.Fab")
			(hide yes)
			(effects
				(font
					(size 1 1)
					(thickness 0.15)
				)
			)
		)
		(sheetfile "k410t-devboard.kicad_sch")
		(attr smd)
		(fp_line
			(start -1.779 -0.981)
			(end -1.779 -0.479)
			(stroke
				(width 0.15)
				(type solid)
			)
			(layer "F.SilkS")
		)
		(fp_line
			(start -1.779 -0.981)
			(end -1.279 -0.981)
			(stroke
				(width 0.15)
				(type solid)
			)
			(layer "F.SilkS")
		)
		(fp_line
			(start -1.779 0.482)
			(end -1.779 0.98)
			(stroke
				(width 0.15)
				(type solid)
			)
			(layer "F.SilkS")
		)
		(fp_line
			(start -1.779 0.98)
			(end -1.279 0.98)
			(stroke
				(width 0.15)
				(type solid)
			)
			(layer "F.SilkS")
		)
		(fp_line
			(start 1.78 -0.981)
			(end 1.281 -0.981)
			(stroke
				(width 0.15)
				(type solid)
			)
			(layer "F.SilkS")
		)
		(fp_line
			(start 1.78 -0.981)
			(end 1.78 -0.479)
			(stroke
				(width 0.15)
				(type solid)
			)
			(layer "F.SilkS")
		)
		(fp_line
			(start 1.78 0.982)
			(end 1.281 0.982)
			(stroke
				(width 0.15)
				(type solid)
			)
			(layer "F.SilkS")
		)
		(fp_line
			(start 1.78 0.982)
			(end 1.78 0.482)
			(stroke
				(width 0.15)
				(type solid)
			)
			(layer "F.SilkS")
		)
		(fp_rect
			(start -2.101 -1.314)
			(end 2.1 1.312)
			(stroke
				(width 0.05)
				(type solid)
			)
			(fill no)
			(layer "F.CrtYd")
		)
		(fp_rect
			(start -1.601 -0.814)
			(end 1.6 0.812)
			(stroke
				(width 0.15)
				(type solid)
			)
			(fill no)
			(layer "F.Fab")
		)
		(pad "1" smd rect
			(at 0 0)
			(size 3.4 1.8)
			(layers "F.Cu" "F.Mask" "F.Paste")
			(net 1 "GND")
			(pinfunction "1")
			(pintype "passive")
		)
	)
	(footprint "antmicro-footprints:NetTie-2_SMD_Pad0.127mm"
		(layer "F.Cu")
		(at 258.36 120.04 -90)
		(descr "Net tie, 2 pin, 0.127mm  SMD pads")
		(tags "net tie")
		(property "Reference" "NT25"
			(at -0.128 -1.345 90)
			(layer "F.SilkS")
			(hide yes)
			(effects
				(font
					(size 0.7 0.7)
					(thickness 0.15)
				)
				(justify right bottom)
			)
		)
		(property "Value" "Net-Tie_2"
			(at 0 1.199 90)
			(layer "F.Fab")
			(effects
				(font
					(size 0.7 0.7)
					(thickness 0.15)
				)
				(justify right bottom)
			)
		)
		(property "Description" "Net tie, 2 pins"
			(at 0 0 270)
			(layer "F.Fab")
			(hide yes)
			(effects
				(font
					(size 1.27 1.27)
					(thickness 0.15)
				)
			)
		)
		(property "Author" "Antmicro"
			(at 138.32 378.4 0)
			(layer "F.Fab")
			(hide yes)
			(effects
				(font
					(size 1 1)
					(thickness 0.15)
				)
			)
		)
		(property "License" "Apache-2.0"
			(at 138.32 378.4 0)
			(layer "F.Fab")
			(hide yes)
			(effects
				(font
					(size 1 1)
					(thickness 0.15)
				)
			)
		)
		(property "MPN" ""
			(at 138.32 378.4 0)
			(layer "F.Fab")
			(hide yes)
			(effects
				(font
					(size 1 1)
					(thickness 0.15)
				)
			)
		)
		(property "Manufacturer" ""
			(at 138.32 378.4 0)
			(layer "F.Fab")
			(hide yes)
			(effects
				(font
					(size 1 1)
					(thickness 0.15)
				)
			)
		)
		(sheetname "DC-DC Converters")
		(sheetfile "dc-dc.kicad_sch")
		(attr exclude_from_pos_files)
		(net_tie_pad_groups "1, 2")
		(fp_poly
			(pts
				(xy -0.0635 -0.0635) (xy 0.0625 -0.0635) (xy 0.0625 0.0635) (xy -0.0635 0.0635)
			)
			(stroke
				(width 0)
				(type solid)
			)
			(fill yes)
			(layer "F.Cu")
		)
		(pad "1" smd roundrect
			(at -0.127 0 90)
			(size 0.127 0.127)
			(layers "F.Cu")
			(roundrect_rratio 0.5)
			(chamfer_ratio 0)
			(chamfer top_left bottom_left)
			(net 1 "GND")
			(pinfunction "1")
			(pintype "passive")
		)
		(pad "2" smd roundrect
			(at 0.126 0 270)
			(size 0.127 0.127)
			(layers "F.Cu")
			(roundrect_rratio 0.5)
			(chamfer_ratio 0)
			(chamfer top_left bottom_left)
			(net 1213 "/DC-DC Converters/SENSE_5V_N")
			(pinfunction "2")
			(pintype "passive")
		)
	)
	(footprint "antmicro-footprints:C_0402_1005Metric"
		(layer "F.Cu")
		(at 198.3625 88.3365 -90)
		(descr "Capacitor SMD 0402")
		(tags "capacitor SMD 0402")
		(property "Reference" "C292"
			(at -1.8865 0.4625 90)
			(layer "F.SilkS")
			(effects
				(font
					(size 0.7 0.7)
					(thickness 0.15)
				)
				(justify right bottom)
			)
		)
		(property "Value" "C_10u_0402"
			(at 0 1.4 90)
			(layer "F.Fab")
			(effects
				(font
					(size 0.7 0.7)
					(thickness 0.15)
				)
				(justify right bottom)
			)
		)
		(property "Description" "SMD Multilayer Ceramic Capacitor, 10 µF, 6.3 V, 0402 [1005 Metric], ± 20%, X5R, CC Series"
			(at 0 0 270)
			(layer "F.Fab")
			(hide yes)
			(effects
				(font
					(size 1.27 1.27)
					(thickness 0.15)
				)
			)
		)
		(property "Author" "Antmicro"
			(at 110.026 286.699 0)
			(layer "F.Fab")
			(hide yes)
			(effects
				(font
					(size 1 1)
					(thickness 0.15)
				)
			)
		)
		(property "Dielectric" ""
			(at 110.026 286.699 0)
			(layer "F.Fab")
			(hide yes)
			(effects
				(font
					(size 1 1)
					(thickness 0.15)
				)
			)
		)
		(property "License" "Apache-2.0"
			(at 110.026 286.699 0)
			(layer "F.Fab")
			(hide yes)
			(effects
				(font
					(size 1 1)
					(thickness 0.15)
				)
			)
		)
		(property "MPN" "CC0402MRX5R5BB106"
			(at 110.026 286.699 0)
			(layer "F.Fab")
			(hide yes)
			(effects
				(font
					(size 1 1)
					(thickness 0.15)
				)
			)
		)
		(property "Manufacturer" "YAGEO"
			(at 110.026 286.699 0)
			(layer "F.Fab")
			(hide yes)
			(effects
				(font
					(size 1 1)
					(thickness 0.15)
				)
			)
		)
		(property "Val" "10u"
			(at 110.026 286.699 0)
			(layer "F.Fab")
			(hide yes)
			(effects
				(font
					(size 1 1)
					(thickness 0.15)
				)
			)
		)
		(property "Voltage" ""
			(at 110.026 286.699 0)
			(layer "F.Fab")
			(hide yes)
			(effects
				(font
					(size 1 1)
					(thickness 0.15)
				)
			)
		)
		(sheetname "HDMI + Ethernet")
		(sheetfile "hdmi-ethernet.kicad_sch")
		(attr smd)
		(fp_rect
			(start -0.925 -0.47)
			(end 0.925 0.47)
			(stroke
				(width 0.05)
				(type default)
			)
			(fill no)
			(layer "F.CrtYd")
		)
		(fp_line
			(start -0.494 0.248)
			(end -0.494 -0.25)
			(stroke
				(width 0.15)
				(type solid)
			)
			(layer "F.Fab")
		)
		(fp_line
			(start 0.504 0.248)
			(end -0.494 0.248)
			(stroke
				(width 0.15)
				(type solid)
			)
			(layer "F.Fab")
		)
		(fp_line
			(start -0.494 -0.25)
			(end 0.504 -0.25)
			(stroke
				(width 0.15)
				(type solid)
			)
			(layer "F.Fab")
		)
		(fp_line
			(start 0.504 -0.25)
			(end 0.504 0.248)
			(stroke
				(width 0.15)
				(type solid)
			)
			(layer "F.Fab")
		)
		(pad "1" smd roundrect
			(at -0.48 0 270)
			(size 0.59 0.64)
			(layers "F.Cu" "F.Mask" "F.Paste")
			(roundrect_rratio 0.25)
			(net 1 "GND")
			(pintype "passive")
		)
		(pad "2" smd roundrect
			(at 0.48 0 270)
			(size 0.59 0.64)
			(layers "F.Cu" "F.Mask" "F.Paste")
			(roundrect_rratio 0.25)
			(net 727 "+1V2")
			(pintype "passive")
		)
	)
	(footprint "antmicro-footprints:R_0402_1005Metric"
		(layer "F.Cu")
		(at 218.4 148.8)
		(descr "Resistor SMD 0402")
		(tags "resistor SMD 0402")
		(property "Reference" "R234"
			(at -3.6 0.35 0)
			(layer "F.SilkS")
			(effects
				(font
					(size 0.7 0.7)
					(thickness 0.15)
				)
				(justify left bottom)
			)
		)
		(property "Value" "R_10R_0402"
			(at 0 1.4 0)
			(layer "F.Fab")
			(effects
				(font
					(size 0.7 0.7)
					(thickness 0.15)
				)
				(justify left bottom)
			)
		)
		(property "Description" "SMD Chip Resistor, 10 ohm, ± 1%, 62.5 mW, 0402 [1005 Metric], Thick Film, General Purpose"
			(at 0 0 0)
			(layer "F.Fab")
			(hide yes)
			(effects
				(font
					(size 1.27 1.27)
					(thickness 0.15)
				)
			)
		)
		(property "Author" "Antmicro"
			(at 0 0 0)
			(layer "F.Fab")
			(hide yes)
			(effects
				(font
					(size 1 1)
					(thickness 0.15)
				)
			)
		)
		(property "License" "Apache-2.0"
			(at 0 0 0)
			(layer "F.Fab")
			(hide yes)
			(effects
				(font
					(size 1 1)
					(thickness 0.15)
				)
			)
		)
		(property "MPN" "CR0402-FX-10R0GLF"
			(at 0 0 0)
			(layer "F.Fab")
			(hide yes)
			(effects
				(font
					(size 1 1)
					(thickness 0.15)
				)
			)
		)
		(property "Manufacturer" "Bourns"
			(at 0 0 0)
			(layer "F.Fab")
			(hide yes)
			(effects
				(font
					(size 1 1)
					(thickness 0.15)
				)
			)
		)
		(property "Tolerance" "1%"
			(at 0 0 0)
			(layer "F.Fab")
			(hide yes)
			(effects
				(font
					(size 1 1)
					(thickness 0.15)
				)
			)
		)
		(property "Val" "10R"
			(at 0 0 0)
			(layer "F.Fab")
			(hide yes)
			(effects
				(font
					(size 1 1)
					(thickness 0.15)
				)
			)
		)
		(sheetname "HDMI + Ethernet")
		(sheetfile "hdmi-ethernet.kicad_sch")
		(attr smd)
		(fp_rect
			(start -0.925 -0.47)
			(end 0.925 0.47)
			(stroke
				(width 0.05)
				(type default)
			)
			(fill no)
			(layer "F.CrtYd")
		)
		(fp_rect
			(start -0.5 -0.25)
			(end 0.5 0.25)
			(stroke
				(width 0.15)
				(type solid)
			)
			(fill no)
			(layer "F.Fab")
		)
		(pad "1" smd roundrect
			(at -0.48 0)
			(size 0.59 0.64)
			(layers "F.Cu" "F.Mask" "F.Paste")
			(roundrect_rratio 0.25)
			(net 516 "/FPGA Bank 18 & 32/ETH_RMII.REFCLK")
			(pintype "passive")
		)
		(pad "2" smd roundrect
			(at 0.48 0)
			(size 0.59 0.64)
			(layers "F.Cu" "F.Mask" "F.Paste")
			(roundrect_rratio 0.25)
			(net 951 "/HDMI + Ethernet/ETH_PHY_REFCLK")
			(pintype "passive")
		)
	)
	(footprint "antmicro-footprints:C_0402_1005Metric"
		(layer "F.Cu")
		(at 158.8 155.7 -90)
		(descr "Capacitor SMD 0402")
		(tags "capacitor SMD 0402")
		(property "Reference" "C400"
			(at 0.75 -0.4 90)
			(layer "F.SilkS")
			(effects
				(font
					(size 0.7 0.7)
					(thickness 0.15)
				)
				(justify right bottom)
			)
		)
		(property "Value" "C_100n_0402"
			(at 0 1.4 90)
			(layer "F.Fab")
			(effects
				(font
					(size 0.7 0.7)
					(thickness 0.15)
				)
				(justify right bottom)
			)
		)
		(property "Description" "SMD Multilayer Ceramic Capacitor, 0.1 µF, 50 V, 0402 [1005 Metric], ± 10%, X5R, GRM Series"
			(at 0 0 270)
			(layer "F.Fab")
			(hide yes)
			(effects
				(font
					(size 1.27 1.27)
					(thickness 0.15)
				)
			)
		)
		(property "Author" "Antmicro"
			(at 3.1 314.5 0)
			(layer "F.Fab")
			(hide yes)
			(effects
				(font
					(size 1 1)
					(thickness 0.15)
				)
			)
		)
		(property "Dielectric" "X5R"
			(at 3.1 314.5 0)
			(layer "F.Fab")
			(hide yes)
			(effects
				(font
					(size 1 1)
					(thickness 0.15)
				)
			)
		)
		(property "License" "Apache-2.0"
			(at 3.1 314.5 0)
			(layer "F.Fab")
			(hide yes)
			(effects
				(font
					(size 1 1)
					(thickness 0.15)
				)
			)
		)
		(property "MPN" "GRM155R61H104KE14D"
			(at 3.1 314.5 0)
			(layer "F.Fab")
			(hide yes)
			(effects
				(font
					(size 1 1)
					(thickness 0.15)
				)
			)
		)
		(property "Manufacturer" "Murata"
			(at 3.1 314.5 0)
			(layer "F.Fab")
			(hide yes)
			(effects
				(font
					(size 1 1)
					(thickness 0.15)
				)
			)
		)
		(property "Val" "100n"
			(at 3.1 314.5 0)
			(layer "F.Fab")
			(hide yes)
			(effects
				(font
					(size 1 1)
					(thickness 0.15)
				)
			)
		)
		(property "Voltage" "50V"
			(at 3.1 314.5 0)
			(layer "F.Fab")
			(hide yes)
			(effects
				(font
					(size 1 1)
					(thickness 0.15)
				)
			)
		)
		(sheetname "DC-DC Converters")
		(sheetfile "dc-dc.kicad_sch")
		(attr smd)
		(fp_rect
			(start -0.925 -0.47)
			(end 0.925 0.47)
			(stroke
				(width 0.05)
				(type default)
			)
			(fill no)
			(layer "F.CrtYd")
		)
		(fp_line
			(start -0.494 0.248)
			(end -0.494 -0.25)
			(stroke
				(width 0.15)
				(type solid)
			)
			(layer "F.Fab")
		)
		(fp_line
			(start 0.504 0.248)
			(end -0.494 0.248)
			(stroke
				(width 0.15)
				(type solid)
			)
			(layer "F.Fab")
		)
		(fp_line
			(start -0.494 -0.25)
			(end 0.504 -0.25)
			(stroke
				(width 0.15)
				(type solid)
			)
			(layer "F.Fab")
		)
		(fp_line
			(start 0.504 -0.25)
			(end 0.504 0.248)
			(stroke
				(width 0.15)
				(type solid)
			)
			(layer "F.Fab")
		)
		(pad "1" smd roundrect
			(at -0.48 0 270)
			(size 0.59 0.64)
			(layers "F.Cu" "F.Mask" "F.Paste")
			(roundrect_rratio 0.25)
			(net 1 "GND")
			(pintype "passive")
		)
		(pad "2" smd roundrect
			(at 0.48 0 270)
			(size 0.59 0.64)
			(layers "F.Cu" "F.Mask" "F.Paste")
			(roundrect_rratio 0.25)
			(net 25 "+1V35")
			(pintype "passive")
		)
	)
	(footprint "antmicro-footprints:C_0402_1005Metric"
		(layer "F.Cu")
		(at 255.95 141.915 90)
		(descr "Capacitor SMD 0402")
		(tags "capacitor SMD 0402")
		(property "Reference" "C221"
			(at -3.585 0.4 90)
			(layer "F.SilkS")
			(effects
				(font
					(size 0.7 0.7)
					(thickness 0.15)
				)
				(justify left bottom)
			)
		)
		(property "Value" "C_10u_0402"
			(at 0 1.4 90)
			(layer "F.Fab")
			(effects
				(font
					(size 0.7 0.7)
					(thickness 0.15)
				)
				(justify left bottom)
			)
		)
		(property "Description" "SMD Multilayer Ceramic Capacitor, 10 µF, 6.3 V, 0402 [1005 Metric], ± 20%, X5R, CC Series"
			(at 0 0 90)
			(layer "F.Fab")
			(hide yes)
			(effects
				(font
					(size 1.27 1.27)
					(thickness 0.15)
				)
			)
		)
		(property "Author" "Antmicro"
			(at 397.865 -114.035 0)
			(layer "F.Fab")
			(hide yes)
			(effects
				(font
					(size 1 1)
					(thickness 0.15)
				)
			)
		)
		(property "Dielectric" ""
			(at 397.865 -114.035 0)
			(layer "F.Fab")
			(hide yes)
			(effects
				(font
					(size 1 1)
					(thickness 0.15)
				)
			)
		)
		(property "License" "Apache-2.0"
			(at 397.865 -114.035 0)
			(layer "F.Fab")
			(hide yes)
			(effects
				(font
					(size 1 1)
					(thickness 0.15)
				)
			)
		)
		(property "MPN" "CC0402MRX5R5BB106"
			(at 397.865 -114.035 0)
			(layer "F.Fab")
			(hide yes)
			(effects
				(font
					(size 1 1)
					(thickness 0.15)
				)
			)
		)
		(property "Manufacturer" "YAGEO"
			(at 397.865 -114.035 0)
			(layer "F.Fab")
			(hide yes)
			(effects
				(font
					(size 1 1)
					(thickness 0.15)
				)
			)
		)
		(property "Val" "10u"
			(at 397.865 -114.035 0)
			(layer "F.Fab")
			(hide yes)
			(effects
				(font
					(size 1 1)
					(thickness 0.15)
				)
			)
		)
		(property "Voltage" ""
			(at 397.865 -114.035 0)
			(layer "F.Fab")
			(hide yes)
			(effects
				(font
					(size 1 1)
					(thickness 0.15)
				)
			)
		)
		(sheetname "USB PHY")
		(sheetfile "usb-phy.kicad_sch")
		(attr smd)
		(fp_rect
			(start -0.925 -0.47)
			(end 0.925 0.47)
			(stroke
				(width 0.05)
				(type default)
			)
			(fill no)
			(layer "F.CrtYd")
		)
		(fp_line
			(start 0.504 -0.25)
			(end 0.504 0.248)
			(stroke
				(width 0.15)
				(type solid)
			)
			(layer "F.Fab")
		)
		(fp_line
			(start -0.494 -0.25)
			(end 0.504 -0.25)
			(stroke
				(width 0.15)
				(type solid)
			)
			(layer "F.Fab")
		)
		(fp_line
			(start 0.504 0.248)
			(end -0.494 0.248)
			(stroke
				(width 0.15)
				(type solid)
			)
			(layer "F.Fab")
		)
		(fp_line
			(start -0.494 0.248)
			(end -0.494 -0.25)
			(stroke
				(width 0.15)
				(type solid)
			)
			(layer "F.Fab")
		)
		(pad "1" smd roundrect
			(at -0.48 0 90)
			(size 0.59 0.64)
			(layers "F.Cu" "F.Mask" "F.Paste")
			(roundrect_rratio 0.25)
			(net 1 "GND")
			(pintype "passive")
		)
		(pad "2" smd roundrect
			(at 0.48 0 90)
			(size 0.59 0.64)
			(layers "F.Cu" "F.Mask" "F.Paste")
			(roundrect_rratio 0.25)
			(net 707 "/USB PHY/FTDI_3V3")
			(pintype "passive")
		)
	)
	(footprint "antmicro-footprints:R_0402_1005Metric"
		(layer "F.Cu")
		(at 236.35 146.45 180)
		(descr "Resistor SMD 0402")
		(tags "resistor SMD 0402")
		(property "Reference" "R182"
			(at 1.05 -4.45 180)
			(layer "F.SilkS")
			(effects
				(font
					(size 0.7 0.7)
					(thickness 0.15)
				)
				(justify left bottom)
			)
		)
		(property "Value" "R_33R_0402"
			(at 0 1.4 180)
			(layer "F.Fab")
			(effects
				(font
					(size 0.7 0.7)
					(thickness 0.15)
				)
				(justify left bottom)
			)
		)
		(property "Description" "SMD Chip Resistor, 33 ohm, ± 1%, 62.5 mW, 0402 [1005 Metric], Thick Film, General Purpose"
			(at 0 0 180)
			(layer "F.Fab")
			(hide yes)
			(effects
				(font
					(size 1.27 1.27)
					(thickness 0.15)
				)
			)
		)
		(property "Author" "Antmicro"
			(at 472.7 292.9 0)
			(layer "F.Fab")
			(hide yes)
			(effects
				(font
					(size 1 1)
					(thickness 0.15)
				)
			)
		)
		(property "License" "Apache-2.0"
			(at 472.7 292.9 0)
			(layer "F.Fab")
			(hide yes)
			(effects
				(font
					(size 1 1)
					(thickness 0.15)
				)
			)
		)
		(property "MPN" "CR0402-FX-33R0GLF"
			(at 472.7 292.9 0)
			(layer "F.Fab")
			(hide yes)
			(effects
				(font
					(size 1 1)
					(thickness 0.15)
				)
			)
		)
		(property "Manufacturer" "Bourns"
			(at 472.7 292.9 0)
			(layer "F.Fab")
			(hide yes)
			(effects
				(font
					(size 1 1)
					(thickness 0.15)
				)
			)
		)
		(property "Tolerance" "1%"
			(at 472.7 292.9 0)
			(layer "F.Fab")
			(hide yes)
			(effects
				(font
					(size 1 1)
					(thickness 0.15)
				)
			)
		)
		(property "Val" "33R"
			(at 472.7 292.9 0)
			(layer "F.Fab")
			(hide yes)
			(effects
				(font
					(size 1 1)
					(thickness 0.15)
				)
			)
		)
		(sheetname "USB PHY")
		(sheetfile "usb-phy.kicad_sch")
		(attr smd)
		(fp_rect
			(start -0.925 -0.47)
			(end 0.925 0.47)
			(stroke
				(width 0.05)
				(type default)
			)
			(fill no)
			(layer "F.CrtYd")
		)
		(fp_rect
			(start -0.5 -0.25)
			(end 0.5 0.25)
			(stroke
				(width 0.15)
				(type solid)
			)
			(fill no)
			(layer "F.Fab")
		)
		(pad "1" smd roundrect
			(at -0.48 0 180)
			(size 0.59 0.64)
			(layers "F.Cu" "F.Mask" "F.Paste")
			(roundrect_rratio 0.25)
			(net 374 "Net-(U23-B1Y)")
			(pintype "passive")
		)
		(pad "2" smd roundrect
			(at 0.48 0 180)
			(size 0.59 0.64)
			(layers "F.Cu" "F.Mask" "F.Paste")
			(roundrect_rratio 0.25)
			(net 1296 "/USB_SPI.SCK")
			(pintype "passive")
		)
	)
	(footprint "antmicro-footprints:WDFN-8-1EP_6x5mm_P1.27mm_EP3.4x4mm"
		(layer "F.Cu")
		(at 230.475 113.15)
		(property "Reference" "U14"
			(at -3.7 -3.2 0)
			(layer "F.SilkS")
			(effects
				(font
					(size 0.7 0.7)
					(thickness 0.15)
				)
				(justify left bottom)
			)
		)
		(property "Value" "MT25QL256ABA1EW7-0SIT"
			(at -10.1 4 0)
			(layer "F.Fab")
			(effects
				(font
					(size 0.7 0.7)
					(thickness 0.15)
				)
				(justify left bottom)
			)
		)
		(property "Description" "Flash Memory, Serial NOR, 256 Mbit, 32M x 8bit, SPI, MLP, 8 Pins"
			(at 0 0 0)
			(layer "F.Fab")
			(hide yes)
			(effects
				(font
					(size 1.27 1.27)
					(thickness 0.15)
				)
			)
		)
		(property "Author" "Antmicro"
			(at 0 0 0)
			(layer "F.Fab")
			(hide yes)
			(effects
				(font
					(size 1 1)
					(thickness 0.15)
				)
			)
		)
		(property "DNP" "DNP"
			(at 0 0 0)
			(layer "F.Fab")
			(hide yes)
			(effects
				(font
					(size 1 1)
					(thickness 0.15)
				)
			)
		)
		(property "License" "Apache-2.0"
			(at 0 0 0)
			(layer "F.Fab")
			(hide yes)
			(effects
				(font
					(size 1 1)
					(thickness 0.15)
				)
			)
		)
		(property "MPN" "MT25QL256ABA1EW7-0SIT"
			(at 0 0 0)
			(layer "F.Fab")
			(hide yes)
			(effects
				(font
					(size 1 1)
					(thickness 0.15)
				)
			)
		)
		(property "Manufacturer" "Micron Technology"
			(at 0 0 0)
			(layer "F.Fab")
			(hide yes)
			(effects
				(font
					(size 1 1)
					(thickness 0.15)
				)
			)
		)
		(property "dnp" ""
			(at 0 0 0)
			(layer "F.Fab")
			(hide yes)
			(effects
				(font
					(size 1 1)
					(thickness 0.15)
				)
			)
		)
		(property "exclude_from_bom" ""
			(at 0 0 0)
			(layer "F.Fab")
			(hide yes)
			(effects
				(font
					(size 1 1)
					(thickness 0.15)
				)
			)
		)
		(sheetname "SPI Flash + SD Card")
		(sheetfile "spi-flash.kicad_sch")
		(attr smd exclude_from_bom)
		(fp_line
			(start -3.801 2.6)
			(end 3.7 2.6)
			(stroke
				(width 0.15)
				(type solid)
			)
			(layer "F.SilkS")
		)
		(fp_line
			(start -2.301 -2.601)
			(end 3.7 -2.601)
			(stroke
				(width 0.15)
				(type solid)
			)
			(layer "F.SilkS")
		)
		(fp_circle
			(center -3.3 -2.8)
			(end -3.25 -2.8)
			(stroke
				(width 0.15)
				(type solid)
			)
			(fill yes)
			(layer "F.SilkS")
		)
		(fp_rect
			(start -3.5 -3)
			(end 3.499 2.999)
			(stroke
				(width 0.05)
				(type solid)
			)
			(fill no)
			(layer "F.CrtYd")
		)
		(fp_line
			(start -3 -1.5)
			(end -3 2.499)
			(stroke
				(width 0.15)
				(type solid)
			)
			(layer "F.Fab")
		)
		(fp_line
			(start -3 2.499)
			(end 2.999 2.499)
			(stroke
				(width 0.15)
				(type solid)
			)
			(layer "F.Fab")
		)
		(fp_line
			(start -2 -2.5)
			(end -3 -1.5)
			(stroke
				(width 0.15)
				(type solid)
			)
			(layer "F.Fab")
		)
		(fp_line
			(start 2.999 -2.5)
			(end -2 -2.5)
			(stroke
				(width 0.15)
				(type solid)
			)
			(layer "F.Fab")
		)
		(fp_line
			(start 2.999 2.499)
			(end 2.999 -2.5)
			(stroke
				(width 0.15)
				(type solid)
			)
			(layer "F.Fab")
		)
		(pad "" smd roundrect
			(at -0.802 -1)
			(size 1.37 1.61)
			(layers "F.Paste")
			(roundrect_rratio 0.182482)
		)
		(pad "" smd roundrect
			(at -0.802 0.998)
			(size 1.37 1.61)
			(layers "F.Paste")
			(roundrect_rratio 0.182482)
		)
		(pad "" smd roundrect
			(at 0.8 -1)
			(size 1.37 1.61)
			(layers "F.Paste")
			(roundrect_rratio 0.182482)
		)
		(pad "" smd roundrect
			(at 0.8 0.998)
			(size 1.37 1.61)
			(layers "F.Paste")
			(roundrect_rratio 0.182482)
		)
		(pad "1" smd rect
			(at -3 -1.905 90)
			(size 0.5 1.5)
			(layers "F.Cu" "F.Mask" "F.Paste")
			(net 906 "/SPI Flash + SD Card/USR_FLASH_1_~{CS}")
			(pinfunction "~{CS}")
			(pintype "passive")
		)
		(pad "2" smd roundrect
			(at -3 -0.635 90)
			(size 0.5 1.5)
			(layers "F.Cu" "F.Mask" "F.Paste")
			(roundrect_rratio 0.25)
			(net 909 "/SPI Flash + SD Card/USR_FLASH_1_DQ1")
			(pinfunction "DQ1")
			(pintype "passive")
		)
		(pad "3" smd roundrect
			(at -3 0.633 90)
			(size 0.5 1.5)
			(layers "F.Cu" "F.Mask" "F.Paste")
			(roundrect_rratio 0.25)
			(net 910 "/SPI Flash + SD Card/USR_FLASH_1_DQ2")
			(pinfunction "DQ2/~{W}")
			(pintype "passive")
		)
		(pad "4" smd roundrect
			(at -3 1.904 90)
			(size 0.5 1.5)
			(layers "F.Cu" "F.Mask" "F.Paste")
			(roundrect_rratio 0.25)
			(net 1 "GND")
			(pinfunction "GND")
			(pintype "passive")
		)
		(pad "5" smd roundrect
			(at 2.999 1.904 90)
			(size 0.5 1.5)
			(layers "F.Cu" "F.Mask" "F.Paste")
			(roundrect_rratio 0.25)
			(net 908 "/SPI Flash + SD Card/USR_FLASH_1_DQ0")
			(pinfunction "DQ0")
			(pintype "passive")
		)
		(pad "6" smd roundrect
			(at 2.999 0.633 90)
			(size 0.5 1.5)
			(layers "F.Cu" "F.Mask" "F.Paste")
			(roundrect_rratio 0.25)
			(net 907 "/SPI Flash + SD Card/USR_FLASH_1_CLK")
			(pinfunction "CLK")
			(pintype "passive")
		)
		(pad "7" smd roundrect
			(at 2.999 -0.635 90)
			(size 0.5 1.5)
			(layers "F.Cu" "F.Mask" "F.Paste")
			(roundrect_rratio 0.25)
			(net 911 "/SPI Flash + SD Card/USR_FLASH_1_DQ3")
			(pinfunction "DQ3/~{HOLD}")
			(pintype "passive")
		)
		(pad "8" smd roundrect
			(at 2.999 -1.905 90)
			(size 0.5 1.5)
			(layers "F.Cu" "F.Mask" "F.Paste")
			(roundrect_rratio 0.25)
			(net 3 "VCC_USR_B")
			(pinfunction "VCC")
			(pintype "passive")
		)
		(pad "9" smd rect
			(at 0 0)
			(size 3.4 4)
			(layers "F.Cu" "F.Mask")
			(net 1 "GND")
			(pinfunction "EP")
			(pintype "passive")
			(solder_paste_margin -0.1)
		)
	)
	(footprint "antmicro-footprints:R_0402_1005Metric"
		(layer "F.Cu")
		(at 199.901 109.249 180)
		(descr "Resistor SMD 0402")
		(tags "resistor SMD 0402")
		(property "Reference" "R154"
			(at -0.899 -0.351 180)
			(layer "F.SilkS")
			(effects
				(font
					(size 0.7 0.7)
					(thickness 0.15)
				)
				(justify left bottom)
			)
		)
		(property "Value" "R_33R_0402"
			(at 0 1.4 180)
			(layer "F.Fab")
			(effects
				(font
					(size 0.7 0.7)
					(thickness 0.15)
				)
				(justify left bottom)
			)
		)
		(property "Description" "SMD Chip Resistor, 33 ohm, ± 1%, 62.5 mW, 0402 [1005 Metric], Thick Film, General Purpose"
			(at 0 0 180)
			(layer "F.Fab")
			(hide yes)
			(effects
				(font
					(size 1.27 1.27)
					(thickness 0.15)
				)
			)
		)
		(property "Author" "Antmicro"
			(at 399.802 218.498 0)
			(layer "F.Fab")
			(hide yes)
			(effects
				(font
					(size 1 1)
					(thickness 0.15)
				)
			)
		)
		(property "License" "Apache-2.0"
			(at 399.802 218.498 0)
			(layer "F.Fab")
			(hide yes)
			(effects
				(font
					(size 1 1)
					(thickness 0.15)
				)
			)
		)
		(property "MPN" "CR0402-FX-33R0GLF"
			(at 399.802 218.498 0)
			(layer "F.Fab")
			(hide yes)
			(effects
				(font
					(size 1 1)
					(thickness 0.15)
				)
			)
		)
		(property "Manufacturer" "Bourns"
			(at 399.802 218.498 0)
			(layer "F.Fab")
			(hide yes)
			(effects
				(font
					(size 1 1)
					(thickness 0.15)
				)
			)
		)
		(property "Tolerance" "1%"
			(at 399.802 218.498 0)
			(layer "F.Fab")
			(hide yes)
			(effects
				(font
					(size 1 1)
					(thickness 0.15)
				)
			)
		)
		(property "Val" "33R"
			(at 399.802 218.498 0)
			(layer "F.Fab")
			(hide yes)
			(effects
				(font
					(size 1 1)
					(thickness 0.15)
				)
			)
		)
		(sheetname "USB PHY")
		(sheetfile "usb-phy.kicad_sch")
		(attr smd)
		(fp_rect
			(start -0.925 -0.47)
			(end 0.925 0.47)
			(stroke
				(width 0.05)
				(type default)
			)
			(fill no)
			(layer "F.CrtYd")
		)
		(fp_rect
			(start -0.5 -0.25)
			(end 0.5 0.25)
			(stroke
				(width 0.15)
				(type solid)
			)
			(fill no)
			(layer "F.Fab")
		)
		(pad "1" smd roundrect
			(at -0.48 0 180)
			(size 0.59 0.64)
			(layers "F.Cu" "F.Mask" "F.Paste")
			(roundrect_rratio 0.25)
			(net 835 "/USB PHY/USB_HOST_CONN_D-")
			(pintype "passive")
		)
		(pad "2" smd roundrect
			(at 0.48 0 180)
			(size 0.59 0.64)
			(layers "F.Cu" "F.Mask" "F.Paste")
			(roundrect_rratio 0.25)
			(net 916 "/USB PHY/USB_HOST_D-")
			(pintype "passive")
		)
	)
	(footprint "antmicro-footprints:C_0402_1005Metric"
		(layer "F.Cu")
		(at 207.4125 91.1115 180)
		(descr "Capacitor SMD 0402")
		(tags "capacitor SMD 0402")
		(property "Reference" "C262"
			(at 1.8125 4.5615 180)
			(layer "F.SilkS")
			(effects
				(font
					(size 0.7 0.7)
					(thickness 0.15)
				)
				(justify left bottom)
			)
		)
		(property "Value" "C_100n_0402"
			(at 0 1.169 180)
			(layer "F.Fab")
			(effects
				(font
					(size 0.7 0.7)
					(thickness 0.15)
				)
				(justify left bottom)
			)
		)
		(property "Description" "SMD Multilayer Ceramic Capacitor, 0.1 µF, 50 V, 0402 [1005 Metric], ± 10%, X5R, GRM Series"
			(at 0 0 180)
			(layer "F.Fab")
			(hide yes)
			(effects
				(font
					(size 1.27 1.27)
					(thickness 0.15)
				)
			)
		)
		(property "Author" "Antmicro"
			(at 414.825 182.223 0)
			(layer "F.Fab")
			(hide yes)
			(effects
				(font
					(size 1 1)
					(thickness 0.15)
				)
			)
		)
		(property "Dielectric" "X5R"
			(at 414.825 182.223 0)
			(layer "F.Fab")
			(hide yes)
			(effects
				(font
					(size 1 1)
					(thickness 0.15)
				)
			)
		)
		(property "License" "Apache-2.0"
			(at 414.825 182.223 0)
			(layer "F.Fab")
			(hide yes)
			(effects
				(font
					(size 1 1)
					(thickness 0.15)
				)
			)
		)
		(property "MPN" "GRM155R61H104KE14D"
			(at 414.825 182.223 0)
			(layer "F.Fab")
			(hide yes)
			(effects
				(font
					(size 1 1)
					(thickness 0.15)
				)
			)
		)
		(property "Manufacturer" "Murata"
			(at 414.825 182.223 0)
			(layer "F.Fab")
			(hide yes)
			(effects
				(font
					(size 1 1)
					(thickness 0.15)
				)
			)
		)
		(property "Val" "100n"
			(at 414.825 182.223 0)
			(layer "F.Fab")
			(hide yes)
			(effects
				(font
					(size 1 1)
					(thickness 0.15)
				)
			)
		)
		(property "Voltage" "50V"
			(at 414.825 182.223 0)
			(layer "F.Fab")
			(hide yes)
			(effects
				(font
					(size 1 1)
					(thickness 0.15)
				)
			)
		)
		(sheetname "HDMI + Ethernet")
		(sheetfile "hdmi-ethernet.kicad_sch")
		(attr smd)
		(fp_rect
			(start -0.925 -0.47)
			(end 0.925 0.47)
			(stroke
				(width 0.05)
				(type default)
			)
			(fill no)
			(layer "F.CrtYd")
		)
		(fp_line
			(start 0.504 0.248)
			(end -0.494 0.248)
			(stroke
				(width 0.15)
				(type solid)
			)
			(layer "F.Fab")
		)
		(fp_line
			(start 0.504 -0.25)
			(end 0.504 0.248)
			(stroke
				(width 0.15)
				(type solid)
			)
			(layer "F.Fab")
		)
		(fp_line
			(start -0.494 0.248)
			(end -0.494 -0.25)
			(stroke
				(width 0.15)
				(type solid)
			)
			(layer "F.Fab")
		)
		(fp_line
			(start -0.494 -0.25)
			(end 0.504 -0.25)
			(stroke
				(width 0.15)
				(type solid)
			)
			(layer "F.Fab")
		)
		(pad "1" smd roundrect
			(at -0.48 0 180)
			(size 0.59 0.64)
			(layers "F.Cu" "F.Mask" "F.Paste")
			(roundrect_rratio 0.25)
			(net 1 "GND")
			(pintype "passive")
		)
		(pad "2" smd roundrect
			(at 0.48 0 180)
			(size 0.59 0.64)
			(layers "F.Cu" "F.Mask" "F.Paste")
			(roundrect_rratio 0.25)
			(net 717 "/HDMI + Ethernet/GBE_AVDDH")
			(pintype "passive")
		)
	)
	(footprint "antmicro-footprints:R_0402_1005Metric"
		(layer "F.Cu")
		(at 162.5275 175.75)
		(descr "Resistor SMD 0402")
		(tags "resistor SMD 0402")
		(property "Reference" "R309"
			(at -0.9275 1.25 0)
			(layer "F.SilkS")
			(effects
				(font
					(size 0.7 0.7)
					(thickness 0.15)
				)
				(justify left bottom)
			)
		)
		(property "Value" "R_0R_0402"
			(at 0 1.4 0)
			(layer "F.Fab")
			(effects
				(font
					(size 0.7 0.7)
					(thickness 0.15)
				)
				(justify left bottom)
			)
		)
		(property "Description" "SMD Chip Resistor, Jumper, 0 ohm, 100 mW, 0402 [1005 Metric], Thick Film, General Purpose"
			(at 0 0 0)
			(layer "F.Fab")
			(hide yes)
			(effects
				(font
					(size 1.27 1.27)
					(thickness 0.15)
				)
			)
		)
		(property "Author" "Antmicro"
			(at 0 0 0)
			(layer "F.Fab")
			(hide yes)
			(effects
				(font
					(size 1 1)
					(thickness 0.15)
				)
			)
		)
		(property "Current" "1A"
			(at 0 0 0)
			(layer "F.Fab")
			(hide yes)
			(effects
				(font
					(size 1 1)
					(thickness 0.15)
				)
			)
		)
		(property "License" "Apache-2.0"
			(at 0 0 0)
			(layer "F.Fab")
			(hide yes)
			(effects
				(font
					(size 1 1)
					(thickness 0.15)
				)
			)
		)
		(property "MPN" "ERJ2GE0R00X"
			(at 0 0 0)
			(layer "F.Fab")
			(hide yes)
			(effects
				(font
					(size 1 1)
					(thickness 0.15)
				)
			)
		)
		(property "Manufacturer" "Panasonic"
			(at 0 0 0)
			(layer "F.Fab")
			(hide yes)
			(effects
				(font
					(size 1 1)
					(thickness 0.15)
				)
			)
		)
		(property "Tolerance" ""
			(at 0 0 0)
			(layer "F.Fab")
			(hide yes)
			(effects
				(font
					(size 1 1)
					(thickness 0.15)
				)
			)
		)
		(property "Val" "0R"
			(at 0 0 0)
			(layer "F.Fab")
			(hide yes)
			(effects
				(font
					(size 1 1)
					(thickness 0.15)
				)
			)
		)
		(sheetname "DC-DC Converters")
		(sheetfile "dc-dc.kicad_sch")
		(attr smd)
		(fp_rect
			(start -0.925 -0.47)
			(end 0.925 0.47)
			(stroke
				(width 0.05)
				(type default)
			)
			(fill no)
			(layer "F.CrtYd")
		)
		(fp_rect
			(start -0.5 -0.25)
			(end 0.5 0.25)
			(stroke
				(width 0.15)
				(type solid)
			)
			(fill no)
			(layer "F.Fab")
		)
		(pad "1" smd roundrect
			(at -0.48 0)
			(size 0.59 0.64)
			(layers "F.Cu" "F.Mask" "F.Paste")
			(roundrect_rratio 0.25)
			(net 962 "/DC-DC Converters/FB3")
			(pintype "passive")
		)
		(pad "2" smd roundrect
			(at 0.48 0)
			(size 0.59 0.64)
			(layers "F.Cu" "F.Mask" "F.Paste")
			(roundrect_rratio 0.25)
			(net 737 "/DC-DC Converters/1V2_local")
			(pintype "passive")
		)
	)
	(footprint "antmicro-footprints:R_0402_1005Metric"
		(layer "F.Cu")
		(at 250.899 96 180)
		(descr "Resistor SMD 0402")
		(tags "resistor SMD 0402")
		(property "Reference" "R342"
			(at 1.399 1.6 0)
			(layer "F.SilkS")
			(effects
				(font
					(size 0.7 0.7)
					(thickness 0.15)
				)
				(justify left bottom)
			)
		)
		(property "Value" "R_0R_0402"
			(at 0 1.4 180)
			(layer "F.Fab")
			(effects
				(font
					(size 0.7 0.7)
					(thickness 0.15)
				)
				(justify left bottom)
			)
		)
		(property "Description" "SMD Chip Resistor, Jumper, 0 ohm, 100 mW, 0402 [1005 Metric], Thick Film, General Purpose"
			(at 0 0 180)
			(layer "F.Fab")
			(hide yes)
			(effects
				(font
					(size 1.27 1.27)
					(thickness 0.15)
				)
			)
		)
		(property "Author" "Antmicro"
			(at 501.798 192 0)
			(layer "F.Fab")
			(hide yes)
			(effects
				(font
					(size 1 1)
					(thickness 0.15)
				)
			)
		)
		(property "Current" "1A"
			(at 501.798 192 0)
			(layer "F.Fab")
			(hide yes)
			(effects
				(font
					(size 1 1)
					(thickness 0.15)
				)
			)
		)
		(property "DNP" "DNP"
			(at 501.798 192 0)
			(layer "F.Fab")
			(hide yes)
			(effects
				(font
					(size 1 1)
					(thickness 0.15)
				)
			)
		)
		(property "License" "Apache-2.0"
			(at 501.798 192 0)
			(layer "F.Fab")
			(hide yes)
			(effects
				(font
					(size 1 1)
					(thickness 0.15)
				)
			)
		)
		(property "MPN" "ERJ2GE0R00X"
			(at 501.798 192 0)
			(layer "F.Fab")
			(hide yes)
			(effects
				(font
					(size 1 1)
					(thickness 0.15)
				)
			)
		)
		(property "Manufacturer" "Panasonic"
			(at 501.798 192 0)
			(layer "F.Fab")
			(hide yes)
			(effects
				(font
					(size 1 1)
					(thickness 0.15)
				)
			)
		)
		(property "Tolerance" ""
			(at 501.798 192 0)
			(layer "F.Fab")
			(hide yes)
			(effects
				(font
					(size 1 1)
					(thickness 0.15)
				)
			)
		)
		(property "Val" "0R"
			(at 501.798 192 0)
			(layer "F.Fab")
			(hide yes)
			(effects
				(font
					(size 1 1)
					(thickness 0.15)
				)
			)
		)
		(property "dnp" ""
			(at 501.798 192 0)
			(layer "F.Fab")
			(hide yes)
			(effects
				(font
					(size 1 1)
					(thickness 0.15)
				)
			)
		)
		(property "exclude_from_bom" ""
			(at 501.798 192 0)
			(layer "F.Fab")
			(hide yes)
			(effects
				(font
					(size 1 1)
					(thickness 0.15)
				)
			)
		)
		(sheetname "USB PHY")
		(sheetfile "usb-phy.kicad_sch")
		(attr smd exclude_from_bom)
		(fp_rect
			(start -0.925 -0.47)
			(end 0.925 0.47)
			(stroke
				(width 0.05)
				(type default)
			)
			(fill no)
			(layer "F.CrtYd")
		)
		(fp_rect
			(start -0.5 -0.25)
			(end 0.5 0.25)
			(stroke
				(width 0.15)
				(type solid)
			)
			(fill no)
			(layer "F.Fab")
		)
		(pad "1" smd roundrect
			(at -0.48 0 180)
			(size 0.59 0.64)
			(layers "F.Cu" "F.Mask" "F.Paste")
			(roundrect_rratio 0.25)
			(net 703 "+5V")
			(pintype "passive")
		)
		(pad "2" smd roundrect
			(at 0.48 0 180)
			(size 0.59 0.64)
			(layers "F.Cu" "F.Mask" "F.Paste")
			(roundrect_rratio 0.25)
			(net 583 "/USB PHY/USB_HOST_VBUS_EN")
			(pintype "passive")
		)
	)
	(footprint "antmicro-footprints:Vishay_PowerPAK_1212-8_Single"
		(layer "F.Cu")
		(at 225.8 157.2 180)
		(descr "PowerPAK 1212-8 Single")
		(tags "Vishay PowerPAK 1212-8 Single")
		(property "Reference" "Q4"
			(at -0.35 1.95 180)
			(layer "F.SilkS")
			(effects
				(font
					(size 0.7 0.7)
					(thickness 0.15)
				)
				(justify left bottom)
			)
		)
		(property "Value" "SI7613DN-T1-GE3"
			(at -8 2.7 180)
			(layer "F.Fab")
			(effects
				(font
					(size 0.7 0.7)
					(thickness 0.15)
				)
				(justify left bottom)
			)
		)
		(property "Description" "Power MOSFET, P Channel, 20 V, 35 A, 0.0072 ohm, PowerPAK 1212, Surface Mount"
			(at 0 0 180)
			(layer "F.Fab")
			(hide yes)
			(effects
				(font
					(size 1.27 1.27)
					(thickness 0.15)
				)
			)
		)
		(property "Author" "Antmicro"
			(at 451.6 314.4 0)
			(layer "F.Fab")
			(hide yes)
			(effects
				(font
					(size 1 1)
					(thickness 0.15)
				)
			)
		)
		(property "License" "Apache-2.0"
			(at 451.6 314.4 0)
			(layer "F.Fab")
			(hide yes)
			(effects
				(font
					(size 1 1)
					(thickness 0.15)
				)
			)
		)
		(property "MPN" "SI7613DN-T1-GE3"
			(at 451.6 314.4 0)
			(layer "F.Fab")
			(hide yes)
			(effects
				(font
					(size 1 1)
					(thickness 0.15)
				)
			)
		)
		(property "Manufacturer" "Vishay"
			(at 451.6 314.4 0)
			(layer "F.Fab")
			(hide yes)
			(effects
				(font
					(size 1 1)
					(thickness 0.15)
				)
			)
		)
		(sheetname "Power supply")
		(sheetfile "power-supply.kicad_sch")
		(attr smd)
		(fp_line
			(start 1.648 -1.651)
			(end 1.648 -1.317)
			(stroke
				(width 0.15)
				(type solid)
			)
			(layer "F.SilkS")
		)
		(fp_line
			(start 1.634 1.3)
			(end 1.634 1.634)
			(stroke
				(width 0.15)
				(type solid)
			)
			(layer "F.SilkS")
		)
		(fp_line
			(start -1.635 1.634)
			(end 1.634 1.634)
			(stroke
				(width 0.15)
				(type solid)
			)
			(layer "F.SilkS")
		)
		(fp_line
			(start -1.635 1.3)
			(end -1.635 1.634)
			(stroke
				(width 0.15)
				(type solid)
			)
			(layer "F.SilkS")
		)
		(fp_line
			(start -1.651 -1.651)
			(end 1.648 -1.651)
			(stroke
				(width 0.15)
				(type solid)
			)
			(layer "F.SilkS")
		)
		(fp_line
			(start -1.651 -1.651)
			(end -1.651 -1.317)
			(stroke
				(width 0.15)
				(type solid)
			)
			(layer "F.SilkS")
		)
		(fp_circle
			(center -1.9 -1.4)
			(end -1.85 -1.4)
			(stroke
				(width 0.15)
				(type solid)
			)
			(fill yes)
			(layer "F.SilkS")
		)
		(fp_rect
			(start -2 -1.8)
			(end 2 1.798)
			(stroke
				(width 0.05)
				(type solid)
			)
			(fill no)
			(layer "F.CrtYd")
		)
		(fp_line
			(start -1.6425 -1.4175)
			(end -1.4175 -1.6425)
			(stroke
				(width 0.15)
				(type solid)
			)
			(layer "F.Fab")
		)
		(fp_rect
			(start -1.651 -1.651)
			(end 1.648 1.648)
			(stroke
				(width 0.15)
				(type solid)
			)
			(fill no)
			(layer "F.Fab")
		)
		(pad "1" smd rect
			(at -1.436 -0.99 180)
			(size 0.99 0.405)
			(layers "F.Cu" "F.Mask" "F.Paste")
			(net 5 "/Power supply/PD_VBUS")
			(pinfunction "S")
			(pintype "passive")
		)
		(pad "2" smd rect
			(at -1.436 -0.332 180)
			(size 0.99 0.405)
			(layers "F.Cu" "F.Mask" "F.Paste")
			(net 5 "/Power supply/PD_VBUS")
			(pinfunction "S")
			(pintype "passive")
		)
		(pad "3" smd rect
			(at -1.436 0.33 180)
			(size 0.99 0.405)
			(layers "F.Cu" "F.Mask" "F.Paste")
			(net 5 "/Power supply/PD_VBUS")
			(pinfunction "S")
			(pintype "passive")
		)
		(pad "4" smd rect
			(at -1.436 0.988 180)
			(size 0.99 0.405)
			(layers "F.Cu" "F.Mask" "F.Paste")
			(net 872 "/Power supply/SINK_EN")
			(pinfunction "G")
			(pintype "passive")
		)
		(pad "5" smd custom
			(at 0.557 0 180)
			(size 1.725 2.235)
			(layers "F.Cu" "F.Mask" "F.Paste")
			(net 700 "/Power supply/USB_PD_VBUS")
			(pinfunction "D")
			(pintype "passive")
			(zone_connect 2)
			(options
				(clearance outline)
				(anchor rect)
			)
			(primitives
				(gr_poly
					(pts
						(xy 0.8625 0.1275) (xy 0.8625 -0.1275) (xy 1.3725 -0.1275) (xy 1.3725 -0.5325) (xy 0.8625 -0.5325)
						(xy 0.8625 -0.7875) (xy 1.3725 -0.7875) (xy 1.3725 -1.195) (xy 0.6125 -1.195) (xy 0.6125 1.195)
						(xy 1.3725 1.195) (xy 1.3725 0.7875) (xy 0.8625 0.7875) (xy 0.8625 0.5325) (xy 1.3725 0.5325)
						(xy 1.3725 0.1275)
					)
					(width 0)
					(fill yes)
				)
			)
		)
	)
	(footprint "antmicro-footprints:TP_SMD_0.75mm"
		(layer "F.Cu")
		(at 172.66 81.1308 180)
		(property "Reference" "TP3"
			(at -0.34 0.3308 270)
			(layer "F.SilkS")
			(effects
				(font
					(size 0.7 0.7)
					(thickness 0.15)
				)
				(justify left bottom)
			)
		)
		(property "Value" "TP_0.75mm_SMD"
			(at 0 1.2 180)
			(layer "F.Fab")
			(effects
				(font
					(size 0.7 0.7)
					(thickness 0.15)
				)
				(justify left bottom)
			)
		)
		(property "Description" "SMT test point"
			(at 0 0 180)
			(layer "F.Fab")
			(hide yes)
			(effects
				(font
					(size 1.27 1.27)
					(thickness 0.15)
				)
			)
		)
		(property "Author" "Antmicro"
			(at 345.32 162.2616 0)
			(layer "F.Fab")
			(hide yes)
			(effects
				(font
					(size 1 1)
					(thickness 0.15)
				)
			)
		)
		(property "License" "Apache-2.0"
			(at 345.32 162.2616 0)
			(layer "F.Fab")
			(hide yes)
			(effects
				(font
					(size 1 1)
					(thickness 0.15)
				)
			)
		)
		(property "MPN" ""
			(at 345.32 162.2616 0)
			(layer "F.Fab")
			(hide yes)
			(effects
				(font
					(size 1 1)
					(thickness 0.15)
				)
			)
		)
		(property "Manufacturer" ""
			(at 345.32 162.2616 0)
			(layer "F.Fab")
			(hide yes)
			(effects
				(font
					(size 1 1)
					(thickness 0.15)
				)
			)
		)
		(sheetname "FMC+ HSPC")
		(sheetfile "fmc-hspc.kicad_sch")
		(attr exclude_from_pos_files)
		(pad "1" smd circle
			(at 0 0 180)
			(size 0.75 0.75)
			(layers "F.Cu" "F.Mask")
			(net 153 "Net-(J18B-PG_M2C)")
			(pinfunction "1")
			(pintype "passive")
		)
	)
	(footprint "antmicro-footprints:SC70-3"
		(layer "F.Cu")
		(at 258.4 86.2)
		(property "Reference" "Q9"
			(at -1.6 1.1 90)
			(layer "F.SilkS")
			(effects
				(font
					(size 0.7 0.7)
					(thickness 0.15)
				)
				(justify left bottom)
			)
		)
		(property "Value" "BSS138PW"
			(at 0 2.3 0)
			(layer "F.Fab")
			(effects
				(font
					(size 0.7 0.7)
					(thickness 0.15)
				)
				(justify left bottom)
			)
		)
		(property "Description" "Power MOSFET, N Channel, 60 V, 320 mA, 0.9 ohm, SOT-323, Surface Mount"
			(at 0 0 0)
			(layer "F.Fab")
			(hide yes)
			(effects
				(font
					(size 1.27 1.27)
					(thickness 0.15)
				)
			)
		)
		(property "Author" "Antmicro"
			(at 0 0 0)
			(layer "F.Fab")
			(hide yes)
			(effects
				(font
					(size 1 1)
					(thickness 0.15)
				)
			)
		)
		(property "License" "Apache-2.0"
			(at 0 0 0)
			(layer "F.Fab")
			(hide yes)
			(effects
				(font
					(size 1 1)
					(thickness 0.15)
				)
			)
		)
		(property "MPN" "BSS138PW"
			(at 0 0 0)
			(layer "F.Fab")
			(hide yes)
			(effects
				(font
					(size 1 1)
					(thickness 0.15)
				)
			)
		)
		(property "Manufacturer" "Nexperia"
			(at 0 0 0)
			(layer "F.Fab")
			(hide yes)
			(effects
				(font
					(size 1 1)
					(thickness 0.15)
				)
			)
		)
		(sheetname "User GPIO + LED + button + DIP switch")
		(sheetfile "user-gpio.kicad_sch")
		(attr smd)
		(fp_line
			(start -0.3 -1)
			(end 0.627 -0.999)
			(stroke
				(width 0.15)
				(type solid)
			)
			(layer "F.SilkS")
		)
		(fp_line
			(start -0.3 1)
			(end 0.627 1.001)
			(stroke
				(width 0.15)
				(type solid)
			)
			(layer "F.SilkS")
		)
		(fp_line
			(start 0.627 -0.6)
			(end 0.627 -0.999)
			(stroke
				(width 0.15)
				(type solid)
			)
			(layer "F.SilkS")
		)
		(fp_line
			(start 0.627 0.6)
			(end 0.627 1.001)
			(stroke
				(width 0.15)
				(type solid)
			)
			(layer "F.SilkS")
		)
		(fp_line
			(start -1.4 1)
			(end -1.4 -1)
			(stroke
				(width 0.05)
				(type solid)
			)
			(layer "F.CrtYd")
		)
		(fp_line
			(start -0.9 -1.3)
			(end -0.9 -1)
			(stroke
				(width 0.05)
				(type solid)
			)
			(layer "F.CrtYd")
		)
		(fp_line
			(start -0.9 -1.3)
			(end 0.9 -1.3)
			(stroke
				(width 0.05)
				(type solid)
			)
			(layer "F.CrtYd")
		)
		(fp_line
			(start -0.9 -1)
			(end -1.4 -1)
			(stroke
				(width 0.05)
				(type solid)
			)
			(layer "F.CrtYd")
		)
		(fp_line
			(start -0.9 1)
			(end -1.4 1)
			(stroke
				(width 0.05)
				(type solid)
			)
			(layer "F.CrtYd")
		)
		(fp_line
			(start -0.9 1.3)
			(end -0.9 1)
			(stroke
				(width 0.05)
				(type solid)
			)
			(layer "F.CrtYd")
		)
		(fp_line
			(start 0.9 -1.3)
			(end 0.9 -0.4)
			(stroke
				(width 0.05)
				(type solid)
			)
			(layer "F.CrtYd")
		)
		(fp_line
			(start 0.9 -0.4)
			(end 1.4 -0.4)
			(stroke
				(width 0.05)
				(type solid)
			)
			(layer "F.CrtYd")
		)
		(fp_line
			(start 0.9 0.4)
			(end 0.9 1.3)
			(stroke
				(width 0.05)
				(type solid)
			)
			(layer "F.CrtYd")
		)
		(fp_line
			(start 0.9 1.3)
			(end -0.9 1.3)
			(stroke
				(width 0.05)
				(type solid)
			)
			(layer "F.CrtYd")
		)
		(fp_line
			(start 1.4 -0.4)
			(end 1.4 0.4)
			(stroke
				(width 0.05)
				(type solid)
			)
			(layer "F.CrtYd")
		)
		(fp_line
			(start 1.4 0.4)
			(end 0.9 0.4)
			(stroke
				(width 0.05)
				(type solid)
			)
			(layer "F.CrtYd")
		)
		(fp_rect
			(start -0.623 -0.999)
			(end 0.627 1.001)
			(stroke
				(width 0.15)
				(type solid)
			)
			(fill no)
			(layer "F.Fab")
		)
		(pad "1" smd rect
			(at -1.051 -0.65 90)
			(size 0.6 0.6)
			(layers "F.Cu" "F.Mask" "F.Paste")
			(net 1300 "/USER_IO.LED_GREEN1")
			(pinfunction "G")
			(pintype "passive")
		)
		(pad "2" smd rect
			(at -1.051 0.65 90)
			(size 0.6 0.6)
			(layers "F.Cu" "F.Mask" "F.Paste")
			(net 1 "GND")
			(pinfunction "S")
			(pintype "passive")
		)
		(pad "3" smd rect
			(at 1.05 0 90)
			(size 0.6 0.6)
			(layers "F.Cu" "F.Mask" "F.Paste")
			(net 21 "Net-(D19-C)")
			(pinfunction "D")
			(pintype "passive")
		)
	)
	(footprint "antmicro-footprints:R_0402_1005Metric"
		(layer "F.Cu")
		(at 194.301 112.499 180)
		(descr "Resistor SMD 0402")
		(tags "resistor SMD 0402")
		(property "Reference" "R157"
			(at -0.799 -0.401 180)
			(layer "F.SilkS")
			(effects
				(font
					(size 0.7 0.7)
					(thickness 0.15)
				)
				(justify left bottom)
			)
		)
		(property "Value" "R_10k_0402"
			(at 0 1.4 180)
			(layer "F.Fab")
			(effects
				(font
					(size 0.7 0.7)
					(thickness 0.15)
				)
				(justify left bottom)
			)
		)
		(property "Description" "SMD Chip Resistor, 10 kohm, ± 1%, 62.5 mW, 0402 [1005 Metric], Thick Film, General Purpose"
			(at 0 0 180)
			(layer "F.Fab")
			(hide yes)
			(effects
				(font
					(size 1.27 1.27)
					(thickness 0.15)
				)
			)
		)
		(property "Author" "Antmicro"
			(at 388.602 224.998 0)
			(layer "F.Fab")
			(hide yes)
			(effects
				(font
					(size 1 1)
					(thickness 0.15)
				)
			)
		)
		(property "License" "Apache-2.0"
			(at 388.602 224.998 0)
			(layer "F.Fab")
			(hide yes)
			(effects
				(font
					(size 1 1)
					(thickness 0.15)
				)
			)
		)
		(property "MPN" "CR0402-FX-1002GLF"
			(at 388.602 224.998 0)
			(layer "F.Fab")
			(hide yes)
			(effects
				(font
					(size 1 1)
					(thickness 0.15)
				)
			)
		)
		(property "Manufacturer" "Bourns"
			(at 388.602 224.998 0)
			(layer "F.Fab")
			(hide yes)
			(effects
				(font
					(size 1 1)
					(thickness 0.15)
				)
			)
		)
		(property "Tolerance" "1%"
			(at 388.602 224.998 0)
			(layer "F.Fab")
			(hide yes)
			(effects
				(font
					(size 1 1)
					(thickness 0.15)
				)
			)
		)
		(property "Val" "10k"
			(at 388.602 224.998 0)
			(layer "F.Fab")
			(hide yes)
			(effects
				(font
					(size 1 1)
					(thickness 0.15)
				)
			)
		)
		(sheetname "USB PHY")
		(sheetfile "usb-phy.kicad_sch")
		(attr smd)
		(fp_rect
			(start -0.925 -0.47)
			(end 0.925 0.47)
			(stroke
				(width 0.05)
				(type default)
			)
			(fill no)
			(layer "F.CrtYd")
		)
		(fp_rect
			(start -0.5 -0.25)
			(end 0.5 0.25)
			(stroke
				(width 0.15)
				(type solid)
			)
			(fill no)
			(layer "F.Fab")
		)
		(pad "1" smd roundrect
			(at -0.48 0 180)
			(size 0.59 0.64)
			(layers "F.Cu" "F.Mask" "F.Paste")
			(roundrect_rratio 0.25)
			(net 496 "/FPGA Bank 12 & 13/USB_HOST.~{RESET}")
			(pintype "passive")
		)
		(pad "2" smd roundrect
			(at 0.48 0 180)
			(size 0.59 0.64)
			(layers "F.Cu" "F.Mask" "F.Paste")
			(roundrect_rratio 0.25)
			(net 24 "+3V3")
			(pintype "passive")
		)
	)
	(footprint "antmicro-footprints:C_Pol_EIA-B"
		(layer "F.Cu")
		(at 195.961 149.4)
		(property "Reference" "C130"
			(at -2.081 -1.71 0)
			(layer "F.SilkS")
			(effects
				(font
					(size 0.7 0.7)
					(thickness 0.15)
				)
				(justify left bottom)
			)
		)
		(property "Value" "C_Pol_330u_6.3V_KEMET-T520-B"
			(at -2.34 2.45 0)
			(layer "F.Fab")
			(effects
				(font
					(size 0.7 0.7)
					(thickness 0.15)
				)
				(justify left bottom)
			)
		)
		(property "Description" "Tantalum Polymer Capacitor, KO-CAP®, 330 µF, ± 20%, 6.3 V, B, 0.04 ohm, 1411 [3528 Metric]"
			(at 0 0 0)
			(layer "F.Fab")
			(hide yes)
			(effects
				(font
					(size 1.27 1.27)
					(thickness 0.15)
				)
			)
		)
		(property "Author" "Antmicro"
			(at 0 0 0)
			(layer "F.Fab")
			(hide yes)
			(effects
				(font
					(size 1 1)
					(thickness 0.15)
				)
			)
		)
		(property "Dielectric" ""
			(at 0 0 0)
			(layer "F.Fab")
			(hide yes)
			(effects
				(font
					(size 1 1)
					(thickness 0.15)
				)
			)
		)
		(property "License" "Apache-2.0"
			(at 0 0 0)
			(layer "F.Fab")
			(hide yes)
			(effects
				(font
					(size 1 1)
					(thickness 0.15)
				)
			)
		)
		(property "MPN" "T520B337M006ATE040"
			(at 0 0 0)
			(layer "F.Fab")
			(hide yes)
			(effects
				(font
					(size 1 1)
					(thickness 0.15)
				)
			)
		)
		(property "Manufacturer" "KEMET"
			(at 0 0 0)
			(layer "F.Fab")
			(hide yes)
			(effects
				(font
					(size 1 1)
					(thickness 0.15)
				)
			)
		)
		(property "Val" "330u"
			(at 0 0 0)
			(layer "F.Fab")
			(hide yes)
			(effects
				(font
					(size 1 1)
					(thickness 0.15)
				)
			)
		)
		(property "Voltage" "6.3V"
			(at 0 0 0)
			(layer "F.Fab")
			(hide yes)
			(effects
				(font
					(size 1 1)
					(thickness 0.15)
				)
			)
		)
		(sheetname "FPGA supply")
		(sheetfile "fpga-supply.kicad_sch")
		(attr smd)
		(fp_line
			(start -2.521 -1.676)
			(end -2.123 -1.676)
			(stroke
				(width 0.15)
				(type solid)
			)
			(layer "F.SilkS")
		)
		(fp_line
			(start -2.325 -1.475)
			(end -2.325 -1.878)
			(stroke
				(width 0.15)
				(type solid)
			)
			(layer "F.SilkS")
		)
		(fp_line
			(start -1.8 -1.6)
			(end 1.8 -1.6)
			(stroke
				(width 0.15)
				(type solid)
			)
			(layer "F.SilkS")
		)
		(fp_line
			(start -1.8 -1.3)
			(end -1.8 -1.6)
			(stroke
				(width 0.15)
				(type solid)
			)
			(layer "F.SilkS")
		)
		(fp_line
			(start -1.8 1.3)
			(end -1.8 1.6)
			(stroke
				(width 0.15)
				(type solid)
			)
			(layer "F.SilkS")
		)
		(fp_line
			(start 1.8 -1.3)
			(end 1.8 -1.6)
			(stroke
				(width 0.15)
				(type solid)
			)
			(layer "F.SilkS")
		)
		(fp_line
			(start 1.8 1.3)
			(end 1.8 1.6)
			(stroke
				(width 0.15)
				(type solid)
			)
			(layer "F.SilkS")
		)
		(fp_line
			(start 1.8 1.6)
			(end -1.8 1.6)
			(stroke
				(width 0.15)
				(type solid)
			)
			(layer "F.SilkS")
		)
		(fp_line
			(start -2.411 -1.35)
			(end -2.41 1.35)
			(stroke
				(width 0.05)
				(type solid)
			)
			(layer "F.CrtYd")
		)
		(fp_line
			(start -1.97 -1.75)
			(end -1.97 -1.35)
			(stroke
				(width 0.05)
				(type solid)
			)
			(layer "F.CrtYd")
		)
		(fp_line
			(start -1.97 -1.35)
			(end -2.41 -1.35)
			(stroke
				(width 0.05)
				(type solid)
			)
			(layer "F.CrtYd")
		)
		(fp_line
			(start -1.97 1.35)
			(end -2.41 1.35)
			(stroke
				(width 0.05)
				(type solid)
			)
			(layer "F.CrtYd")
		)
		(fp_line
			(start -1.97 1.35)
			(end -1.97 1.75)
			(stroke
				(width 0.05)
				(type solid)
			)
			(layer "F.CrtYd")
		)
		(fp_line
			(start 1.959 -1.75)
			(end -1.971 -1.75)
			(stroke
				(width 0.05)
				(type solid)
			)
			(layer "F.CrtYd")
		)
		(fp_line
			(start 1.959 -1.75)
			(end 1.959 -1.35)
			(stroke
				(width 0.05)
				(type solid)
			)
			(layer "F.CrtYd")
		)
		(fp_line
			(start 1.96 1.35)
			(end 1.96 1.75)
			(stroke
				(width 0.05)
				(type solid)
			)
			(layer "F.CrtYd")
		)
		(fp_line
			(start 1.96 1.75)
			(end -1.97 1.75)
			(stroke
				(width 0.05)
				(type solid)
			)
			(layer "F.CrtYd")
		)
		(fp_line
			(start 2.399 -1.35)
			(end 1.959 -1.35)
			(stroke
				(width 0.05)
				(type solid)
			)
			(layer "F.CrtYd")
		)
		(fp_line
			(start 2.399 -1.35)
			(end 2.4 1.35)
			(stroke
				(width 0.05)
				(type solid)
			)
			(layer "F.CrtYd")
		)
		(fp_line
			(start 2.4 1.35)
			(end 1.96 1.35)
			(stroke
				(width 0.05)
				(type solid)
			)
			(layer "F.CrtYd")
		)
		(fp_line
			(start -1.7 1.324)
			(end -1.551 1.475)
			(stroke
				(width 0.15)
				(type solid)
			)
			(layer "F.Fab")
		)
		(fp_rect
			(start -1.72 -1.5)
			(end 1.719 1.499)
			(stroke
				(width 0.15)
				(type solid)
			)
			(fill no)
			(layer "F.Fab")
		)
		(pad "1" smd roundrect
			(at -1.551 0)
			(size 1.2 2.2)
			(layers "F.Cu" "F.Mask" "F.Paste")
			(roundrect_rratio 0.1)
			(net 650 "+1V0")
			(pintype "passive")
		)
		(pad "2" smd roundrect
			(at 1.55 0)
			(size 1.2 2.2)
			(layers "F.Cu" "F.Mask" "F.Paste")
			(roundrect_rratio 0.1)
			(net 1 "GND")
			(pintype "passive")
		)
	)
	(footprint "antmicro-footprints:R_0402_1005Metric"
		(layer "F.Cu")
		(at 239 134.7 90)
		(descr "Resistor SMD 0402")
		(tags "resistor SMD 0402")
		(property "Reference" "R186"
			(at 1.625 3.825 270)
			(layer "F.SilkS")
			(effects
				(font
					(size 0.7 0.7)
					(thickness 0.15)
				)
				(justify left bottom)
			)
		)
		(property "Value" "R_0R_0402"
			(at 0 1.4 90)
			(layer "F.Fab")
			(effects
				(font
					(size 0.7 0.7)
					(thickness 0.15)
				)
				(justify left bottom)
			)
		)
		(property "Description" "SMD Chip Resistor, Jumper, 0 ohm, 100 mW, 0402 [1005 Metric], Thick Film, General Purpose"
			(at 0 0 90)
			(layer "F.Fab")
			(hide yes)
			(effects
				(font
					(size 1.27 1.27)
					(thickness 0.15)
				)
			)
		)
		(property "Author" "Antmicro"
			(at 373.7 -104.3 0)
			(layer "F.Fab")
			(hide yes)
			(effects
				(font
					(size 1 1)
					(thickness 0.15)
				)
			)
		)
		(property "Current" "1A"
			(at 373.7 -104.3 0)
			(layer "F.Fab")
			(hide yes)
			(effects
				(font
					(size 1 1)
					(thickness 0.15)
				)
			)
		)
		(property "License" "Apache-2.0"
			(at 373.7 -104.3 0)
			(layer "F.Fab")
			(hide yes)
			(effects
				(font
					(size 1 1)
					(thickness 0.15)
				)
			)
		)
		(property "MPN" "ERJ2GE0R00X"
			(at 373.7 -104.3 0)
			(layer "F.Fab")
			(hide yes)
			(effects
				(font
					(size 1 1)
					(thickness 0.15)
				)
			)
		)
		(property "Manufacturer" "Panasonic"
			(at 373.7 -104.3 0)
			(layer "F.Fab")
			(hide yes)
			(effects
				(font
					(size 1 1)
					(thickness 0.15)
				)
			)
		)
		(property "Tolerance" ""
			(at 373.7 -104.3 0)
			(layer "F.Fab")
			(hide yes)
			(effects
				(font
					(size 1 1)
					(thickness 0.15)
				)
			)
		)
		(property "Val" "0R"
			(at 373.7 -104.3 0)
			(layer "F.Fab")
			(hide yes)
			(effects
				(font
					(size 1 1)
					(thickness 0.15)
				)
			)
		)
		(sheetname "USB PHY")
		(sheetfile "usb-phy.kicad_sch")
		(attr smd)
		(fp_rect
			(start -0.925 -0.47)
			(end 0.925 0.47)
			(stroke
				(width 0.05)
				(type default)
			)
			(fill no)
			(layer "F.CrtYd")
		)
		(fp_rect
			(start -0.5 -0.25)
			(end 0.5 0.25)
			(stroke
				(width 0.15)
				(type solid)
			)
			(fill no)
			(layer "F.Fab")
		)
		(pad "1" smd roundrect
			(at -0.48 0 90)
			(size 0.59 0.64)
			(layers "F.Cu" "F.Mask" "F.Paste")
			(roundrect_rratio 0.25)
			(net 379 "Net-(U24-OE)")
			(pintype "passive")
		)
		(pad "2" smd roundrect
			(at 0.48 0 90)
			(size 0.59 0.64)
			(layers "F.Cu" "F.Mask" "F.Paste")
			(roundrect_rratio 0.25)
			(net 925 "/USB PHY/BDBUS3")
			(pintype "passive")
		)
	)
	(footprint "antmicro-footprints:R_0402_1005Metric"
		(layer "F.Cu")
		(at 236 140 180)
		(descr "Resistor SMD 0402")
		(tags "resistor SMD 0402")
		(property "Reference" "R193"
			(at 1.9 -2.35 180)
			(layer "F.SilkS")
			(effects
				(font
					(size 0.7 0.7)
					(thickness 0.15)
				)
				(justify left bottom)
			)
		)
		(property "Value" "R_4k7_0402"
			(at 0 1.4 180)
			(layer "F.Fab")
			(effects
				(font
					(size 0.7 0.7)
					(thickness 0.15)
				)
				(justify left bottom)
			)
		)
		(property "Description" "SMD Chip Resistor, 4.7 kohm, ± 1%, 62.5 mW, 0402 [1005 Metric], Thick Film, General Purpose"
			(at 0 0 180)
			(layer "F.Fab")
			(hide yes)
			(effects
				(font
					(size 1.27 1.27)
					(thickness 0.15)
				)
			)
		)
		(property "Author" "Antmicro"
			(at 472 280 0)
			(layer "F.Fab")
			(hide yes)
			(effects
				(font
					(size 1 1)
					(thickness 0.15)
				)
			)
		)
		(property "License" "Apache-2.0"
			(at 472 280 0)
			(layer "F.Fab")
			(hide yes)
			(effects
				(font
					(size 1 1)
					(thickness 0.15)
				)
			)
		)
		(property "MPN" "CR0402-FX-4701GLF"
			(at 472 280 0)
			(layer "F.Fab")
			(hide yes)
			(effects
				(font
					(size 1 1)
					(thickness 0.15)
				)
			)
		)
		(property "Manufacturer" "Bourns"
			(at 472 280 0)
			(layer "F.Fab")
			(hide yes)
			(effects
				(font
					(size 1 1)
					(thickness 0.15)
				)
			)
		)
		(property "Tolerance" "1%"
			(at 472 280 0)
			(layer "F.Fab")
			(hide yes)
			(effects
				(font
					(size 1 1)
					(thickness 0.15)
				)
			)
		)
		(property "Val" "4k7"
			(at 472 280 0)
			(layer "F.Fab")
			(hide yes)
			(effects
				(font
					(size 1 1)
					(thickness 0.15)
				)
			)
		)
		(sheetname "USB PHY")
		(sheetfile "usb-phy.kicad_sch")
		(attr smd)
		(fp_rect
			(start -0.925 -0.47)
			(end 0.925 0.47)
			(stroke
				(width 0.05)
				(type default)
			)
			(fill no)
			(layer "F.CrtYd")
		)
		(fp_rect
			(start -0.5 -0.25)
			(end 0.5 0.25)
			(stroke
				(width 0.15)
				(type solid)
			)
			(fill no)
			(layer "F.Fab")
		)
		(pad "1" smd roundrect
			(at -0.48 0 180)
			(size 0.59 0.64)
			(layers "F.Cu" "F.Mask" "F.Paste")
			(roundrect_rratio 0.25)
			(net 1205 "Net-(D38-Pad1)")
			(pintype "passive")
		)
		(pad "2" smd roundrect
			(at 0.48 0 180)
			(size 0.59 0.64)
			(layers "F.Cu" "F.Mask" "F.Paste")
			(roundrect_rratio 0.25)
			(net 1338 "/I2C.SCL")
			(pintype "passive")
		)
	)
	(footprint "antmicro-footprints:R_Array_4x0201_Panasonic_EXB18V"
		(layer "F.Cu")
		(at 247.9 144.302)
		(property "Reference" "R42"
			(at -13.7 -40.902 0)
			(layer "F.SilkS")
			(effects
				(font
					(size 0.7 0.7)
					(thickness 0.15)
				)
				(justify right bottom)
			)
		)
		(property "Value" "R_4x33R_0201_array"
			(at -1.1 1.8 0)
			(layer "F.Fab")
			(effects
				(font
					(size 0.7 0.7)
					(thickness 0.15)
				)
				(justify left bottom)
			)
		)
		(property "Description" "Fixed Network Resistor, 33 ohm, Isolated, 4 Resistors, 0502 [1406 Metric], Flat, ± 5%"
			(at 0 0 0)
			(layer "F.Fab")
			(hide yes)
			(effects
				(font
					(size 1.27 1.27)
					(thickness 0.15)
				)
			)
		)
		(property "Author" "Antmicro"
			(at 0 0 0)
			(layer "F.Fab")
			(hide yes)
			(effects
				(font
					(size 1 1)
					(thickness 0.15)
				)
			)
		)
		(property "License" "Apache-2.0"
			(at 0 0 0)
			(layer "F.Fab")
			(hide yes)
			(effects
				(font
					(size 1 1)
					(thickness 0.15)
				)
			)
		)
		(property "MPN" "EXB-18V330JX"
			(at 0 0 0)
			(layer "F.Fab")
			(hide yes)
			(effects
				(font
					(size 1 1)
					(thickness 0.15)
				)
			)
		)
		(property "Manufacturer" "Panasonic"
			(at 0 0 0)
			(layer "F.Fab")
			(hide yes)
			(effects
				(font
					(size 1 1)
					(thickness 0.15)
				)
			)
		)
		(property "Val" "R_4x33R_0201"
			(at 0 0 0)
			(layer "F.Fab")
			(hide yes)
			(effects
				(font
					(size 1 1)
					(thickness 0.15)
				)
			)
		)
		(sheetname "Supervisior MCU")
		(sheetfile "supervisor-mcu.kicad_sch")
		(attr smd)
		(fp_line
			(start -0.8 -0.45)
			(end -0.8 0.45)
			(stroke
				(width 0.12)
				(type solid)
			)
			(layer "F.SilkS")
		)
		(fp_line
			(start 0.8 -0.45)
			(end 0.8 0.45)
			(stroke
				(width 0.12)
				(type solid)
			)
			(layer "F.SilkS")
		)
		(fp_rect
			(start -0.898 -0.66)
			(end 0.898 0.65)
			(stroke
				(width 0.05)
				(type solid)
			)
			(fill no)
			(layer "F.CrtYd")
		)
		(pad "1" smd roundrect
			(at -0.6 0.298)
			(size 0.2 0.4)
			(layers "F.Cu" "F.Mask" "F.Paste")
			(roundrect_rratio 0.25)
			(net 1106 "/Supervisior MCU/TEMP_ALERT_N")
			(pinfunction "R1.1")
			(pintype "passive")
		)
		(pad "2" smd roundrect
			(at -0.202 0.298)
			(size 0.2 0.4)
			(layers "F.Cu" "F.Mask" "F.Paste")
			(roundrect_rratio 0.25)
			(net 1103 "/Supervisior MCU/FPGA_M0")
			(pinfunction "R2.1")
			(pintype "passive")
		)
		(pad "3" smd roundrect
			(at 0.2 0.298)
			(size 0.2 0.4)
			(layers "F.Cu" "F.Mask" "F.Paste")
			(roundrect_rratio 0.25)
			(net 1116 "/Supervisior MCU/USB_SPARE2")
			(pinfunction "R3.1")
			(pintype "passive")
		)
		(pad "4" smd roundrect
			(at 0.598 0.298)
			(size 0.2 0.4)
			(layers "F.Cu" "F.Mask" "F.Paste")
			(roundrect_rratio 0.25)
			(net 1115 "/Supervisior MCU/USB_SPARE1")
			(pinfunction "R4.1")
			(pintype "passive")
		)
		(pad "5" smd roundrect
			(at 0.598 -0.3)
			(size 0.2 0.4)
			(layers "F.Cu" "F.Mask" "F.Paste")
			(roundrect_rratio 0.25)
			(net 1383 "/SUP_MCU.SPARE1")
			(pinfunction "R4.2")
			(pintype "passive")
		)
		(pad "6" smd roundrect
			(at 0.2 -0.3)
			(size 0.2 0.4)
			(layers "F.Cu" "F.Mask" "F.Paste")
			(roundrect_rratio 0.25)
			(net 1384 "/SUP_MCU.SPARE2")
			(pinfunction "R3.2")
			(pintype "passive")
		)
		(pad "7" smd roundrect
			(at -0.202 -0.3)
			(size 0.2 0.4)
			(layers "F.Cu" "F.Mask" "F.Paste")
			(roundrect_rratio 0.25)
			(net 1312 "/SUP_MCU.FPGA_M0")
			(pinfunction "R2.2")
			(pintype "passive")
		)
		(pad "8" smd roundrect
			(at -0.6 -0.3)
			(size 0.2 0.4)
			(layers "F.Cu" "F.Mask" "F.Paste")
			(roundrect_rratio 0.25)
			(net 1335 "/SUP_MCU.TEMP_ALERT_N")
			(pinfunction "R1.2")
			(pintype "passive")
		)
	)
	(footprint "antmicro-footprints:R_0402_1005Metric"
		(layer "F.Cu")
		(at 212.9 165.4 90)
		(descr "Resistor SMD 0402")
		(tags "resistor SMD 0402")
		(property "Reference" "R83"
			(at -0.4 -5.25 90)
			(layer "F.SilkS")
			(effects
				(font
					(size 0.7 0.7)
					(thickness 0.15)
				)
				(justify left bottom)
			)
		)
		(property "Value" "R_0R_0402"
			(at 0 1.4 90)
			(layer "F.Fab")
			(effects
				(font
					(size 0.7 0.7)
					(thickness 0.15)
				)
				(justify left bottom)
			)
		)
		(property "Description" "SMD Chip Resistor, Jumper, 0 ohm, 100 mW, 0402 [1005 Metric], Thick Film, General Purpose"
			(at 0 0 90)
			(layer "F.Fab")
			(hide yes)
			(effects
				(font
					(size 1.27 1.27)
					(thickness 0.15)
				)
			)
		)
		(property "Author" "Antmicro"
			(at 378.3 -47.5 0)
			(layer "F.Fab")
			(hide yes)
			(effects
				(font
					(size 1 1)
					(thickness 0.15)
				)
			)
		)
		(property "Current" "1A"
			(at 378.3 -47.5 0)
			(layer "F.Fab")
			(hide yes)
			(effects
				(font
					(size 1 1)
					(thickness 0.15)
				)
			)
		)
		(property "License" "Apache-2.0"
			(at 378.3 -47.5 0)
			(layer "F.Fab")
			(hide yes)
			(effects
				(font
					(size 1 1)
					(thickness 0.15)
				)
			)
		)
		(property "MPN" "ERJ2GE0R00X"
			(at 378.3 -47.5 0)
			(layer "F.Fab")
			(hide yes)
			(effects
				(font
					(size 1 1)
					(thickness 0.15)
				)
			)
		)
		(property "Manufacturer" "Panasonic"
			(at 378.3 -47.5 0)
			(layer "F.Fab")
			(hide yes)
			(effects
				(font
					(size 1 1)
					(thickness 0.15)
				)
			)
		)
		(property "Tolerance" ""
			(at 378.3 -47.5 0)
			(layer "F.Fab")
			(hide yes)
			(effects
				(font
					(size 1 1)
					(thickness 0.15)
				)
			)
		)
		(property "Val" "0R"
			(at 378.3 -47.5 0)
			(layer "F.Fab")
			(hide yes)
			(effects
				(font
					(size 1 1)
					(thickness 0.15)
				)
			)
		)
		(sheetname "SPI Flash + SD Card")
		(sheetfile "spi-flash.kicad_sch")
		(attr smd)
		(fp_rect
			(start -0.925 -0.47)
			(end 0.925 0.47)
			(stroke
				(width 0.05)
				(type default)
			)
			(fill no)
			(layer "F.CrtYd")
		)
		(fp_rect
			(start -0.5 -0.25)
			(end 0.5 0.25)
			(stroke
				(width 0.15)
				(type solid)
			)
			(fill no)
			(layer "F.Fab")
		)
		(pad "1" smd roundrect
			(at -0.48 0 90)
			(size 0.59 0.64)
			(layers "F.Cu" "F.Mask" "F.Paste")
			(roundrect_rratio 0.25)
			(net 411 "/FPGA Bank 33 & 34/USR_FLASH_0.DQ1")
			(pintype "passive")
		)
		(pad "2" smd roundrect
			(at 0.48 0 90)
			(size 0.59 0.64)
			(layers "F.Cu" "F.Mask" "F.Paste")
			(roundrect_rratio 0.25)
			(net 903 "/SPI Flash + SD Card/USR_FLASH_0_DQ1")
			(pintype "passive")
		)
	)
	(footprint "antmicro-footprints:USON-10_2.5x1mm_P0.5mm"
		(layer "F.Cu")
		(at 261.7 127 180)
		(descr "USON-10 2.5x1mm_ Pitch 0.5mm")
		(tags "USON-10 2.5x1mm Pitch 0.5mm")
		(property "Reference" "U21"
			(at 0.95 -2.45 180)
			(layer "F.SilkS")
			(effects
				(font
					(size 0.7 0.7)
					(thickness 0.15)
				)
				(justify left bottom)
			)
		)
		(property "Value" "TPD4E05U06QDQARQ1"
			(at 0.018 2.499 180)
			(layer "F.Fab")
			(effects
				(font
					(size 0.7 0.7)
					(thickness 0.15)
				)
				(justify left bottom)
			)
		)
		(property "Description" "ESD protection"
			(at 0 0 180)
			(layer "F.Fab")
			(hide yes)
			(effects
				(font
					(size 1.27 1.27)
					(thickness 0.15)
				)
			)
		)
		(property "Author" "Antmicro"
			(at 523.4 254 0)
			(layer "F.Fab")
			(hide yes)
			(effects
				(font
					(size 1 1)
					(thickness 0.15)
				)
			)
		)
		(property "License" "Apache-2.0"
			(at 523.4 254 0)
			(layer "F.Fab")
			(hide yes)
			(effects
				(font
					(size 1 1)
					(thickness 0.15)
				)
			)
		)
		(property "MPN" "TPD4E05U06QDQARQ1"
			(at 523.4 254 0)
			(layer "F.Fab")
			(hide yes)
			(effects
				(font
					(size 1 1)
					(thickness 0.15)
				)
			)
		)
		(property "Manufacturer" "Texas Instruments"
			(at 523.4 254 0)
			(layer "F.Fab")
			(hide yes)
			(effects
				(font
					(size 1 1)
					(thickness 0.15)
				)
			)
		)
		(sheetname "USB PHY")
		(sheetfile "usb-phy.kicad_sch")
		(attr smd)
		(fp_line
			(start 0.498 1.398)
			(end -0.5 1.398)
			(stroke
				(width 0.15)
				(type solid)
			)
			(layer "F.SilkS")
		)
		(fp_line
			(start 0.498 -1.401)
			(end -0.5 -1.401)
			(stroke
				(width 0.15)
				(type solid)
			)
			(layer "F.SilkS")
		)
		(fp_circle
			(center -0.68 -1.27)
			(end -0.63 -1.27)
			(stroke
				(width 0.15)
				(type solid)
			)
			(fill yes)
			(layer "F.SilkS")
		)
		(fp_rect
			(start -0.8 -1.5)
			(end 0.8 1.499)
			(stroke
				(width 0.05)
				(type solid)
			)
			(fill no)
			(layer "F.CrtYd")
		)
		(fp_line
			(start 0.498 -1.25)
			(end 0.498 1.249)
			(stroke
				(width 0.15)
				(type solid)
			)
			(layer "F.Fab")
		)
		(fp_line
			(start 0.498 -1.25)
			(end -0.25 -1.25)
			(stroke
				(width 0.15)
				(type solid)
			)
			(layer "F.Fab")
		)
		(fp_line
			(start -0.25 -1.25)
			(end -0.5 -1)
			(stroke
				(width 0.15)
				(type solid)
			)
			(layer "F.Fab")
		)
		(fp_line
			(start -0.5 1.249)
			(end 0.498 1.249)
			(stroke
				(width 0.15)
				(type solid)
			)
			(layer "F.Fab")
		)
		(fp_line
			(start -0.5 -1)
			(end -0.5 1.249)
			(stroke
				(width 0.15)
				(type solid)
			)
			(layer "F.Fab")
		)
		(pad "1" smd roundrect
			(at -0.387 -1 90)
			(size 0.25 0.55)
			(layers "F.Cu" "F.Mask" "F.Paste")
			(roundrect_rratio 0.25)
			(net 841 "/USB PHY/USB_USR_CC1")
			(pintype "passive")
		)
		(pad "2" smd roundrect
			(at -0.387 -0.5 90)
			(size 0.25 0.55)
			(layers "F.Cu" "F.Mask" "F.Paste")
			(roundrect_rratio 0.25)
			(net 842 "/USB PHY/USB_USR_CONN_D+")
			(pintype "passive")
		)
		(pad "3" smd roundrect
			(at -0.387 0 90)
			(size 0.4 0.55)
			(layers "F.Cu" "F.Mask" "F.Paste")
			(roundrect_rratio 0.25)
			(net 1 "GND")
			(pintype "power_in")
		)
		(pad "4" smd roundrect
			(at -0.387 0.498 90)
			(size 0.25 0.55)
			(layers "F.Cu" "F.Mask" "F.Paste")
			(roundrect_rratio 0.25)
			(net 843 "/USB PHY/USB_USR_CONN_D-")
			(pintype "passive")
		)
		(pad "5" smd roundrect
			(at -0.387 0.998 90)
			(size 0.25 0.55)
			(layers "F.Cu" "F.Mask" "F.Paste")
			(roundrect_rratio 0.25)
			(net 844 "/USB PHY/USB_USR_CC2")
			(pintype "passive")
		)
		(pad "6" smd roundrect
			(at 0.385 0.998 90)
			(size 0.25 0.55)
			(layers "F.Cu" "F.Mask" "F.Paste")
			(roundrect_rratio 0.25)
			(net 844 "/USB PHY/USB_USR_CC2")
			(pintype "passive")
		)
		(pad "7" smd roundrect
			(at 0.385 0.498 90)
			(size 0.25 0.55)
			(layers "F.Cu" "F.Mask" "F.Paste")
			(roundrect_rratio 0.25)
			(net 843 "/USB PHY/USB_USR_CONN_D-")
			(pintype "passive")
		)
		(pad "8" smd roundrect
			(at 0.385 0 90)
			(size 0.4 0.55)
			(layers "F.Cu" "F.Mask" "F.Paste")
			(roundrect_rratio 0.25)
			(net 1 "GND")
			(pintype "passive")
		)
		(pad "9" smd roundrect
			(at 0.385 -0.5 90)
			(size 0.25 0.55)
			(layers "F.Cu" "F.Mask" "F.Paste")
			(roundrect_rratio 0.25)
			(net 842 "/USB PHY/USB_USR_CONN_D+")
			(pintype "passive")
		)
		(pad "10" smd roundrect
			(at 0.385 -1 90)
			(size 0.25 0.55)
			(layers "F.Cu" "F.Mask" "F.Paste")
			(roundrect_rratio 0.25)
			(net 841 "/USB PHY/USB_USR_CC1")
			(pintype "passive")
		)
	)
	(footprint "antmicro-footprints:R_0402_1005Metric"
		(layer "F.Cu")
		(at 259.6 125.5 180)
		(descr "Resistor SMD 0402")
		(tags "resistor SMD 0402")
		(property "Reference" "R362"
			(at 1.05 5.65 180)
			(layer "F.SilkS")
			(effects
				(font
					(size 0.7 0.7)
					(thickness 0.15)
				)
				(justify left bottom)
			)
		)
		(property "Value" "R_5k1_0402"
			(at 0 1.4 180)
			(layer "F.Fab")
			(effects
				(font
					(size 0.7 0.7)
					(thickness 0.15)
				)
				(justify left bottom)
			)
		)
		(property "Description" "SMD Chip Resistor, 5.1 kohm, ± 1%, 63 mW, 0402 [1005 Metric], Thick Film, General Purpose"
			(at 0 0 180)
			(layer "F.Fab")
			(hide yes)
			(effects
				(font
					(size 1.27 1.27)
					(thickness 0.15)
				)
			)
		)
		(property "Author" "Antmicro"
			(at 519.2 251 0)
			(layer "F.Fab")
			(hide yes)
			(effects
				(font
					(size 1 1)
					(thickness 0.15)
				)
			)
		)
		(property "License" "Apache-2.0"
			(at 519.2 251 0)
			(layer "F.Fab")
			(hide yes)
			(effects
				(font
					(size 1 1)
					(thickness 0.15)
				)
			)
		)
		(property "MPN" "CR0402-FX-5101GLF"
			(at 519.2 251 0)
			(layer "F.Fab")
			(hide yes)
			(effects
				(font
					(size 1 1)
					(thickness 0.15)
				)
			)
		)
		(property "Manufacturer" "Bourns"
			(at 519.2 251 0)
			(layer "F.Fab")
			(hide yes)
			(effects
				(font
					(size 1 1)
					(thickness 0.15)
				)
			)
		)
		(property "Tolerance" "1%"
			(at 519.2 251 0)
			(layer "F.Fab")
			(hide yes)
			(effects
				(font
					(size 1 1)
					(thickness 0.15)
				)
			)
		)
		(property "Val" "5k1"
			(at 519.2 251 0)
			(layer "F.Fab")
			(hide yes)
			(effects
				(font
					(size 1 1)
					(thickness 0.15)
				)
			)
		)
		(sheetname "USB PHY")
		(sheetfile "usb-phy.kicad_sch")
		(attr smd)
		(fp_rect
			(start -0.925 -0.47)
			(end 0.925 0.47)
			(stroke
				(width 0.05)
				(type default)
			)
			(fill no)
			(layer "F.CrtYd")
		)
		(fp_rect
			(start -0.5 -0.25)
			(end 0.5 0.25)
			(stroke
				(width 0.15)
				(type solid)
			)
			(fill no)
			(layer "F.Fab")
		)
		(pad "1" smd roundrect
			(at -0.48 0 180)
			(size 0.59 0.64)
			(layers "F.Cu" "F.Mask" "F.Paste")
			(roundrect_rratio 0.25)
			(net 844 "/USB PHY/USB_USR_CC2")
			(pintype "passive")
		)
		(pad "2" smd roundrect
			(at 0.48 0 180)
			(size 0.59 0.64)
			(layers "F.Cu" "F.Mask" "F.Paste")
			(roundrect_rratio 0.25)
			(net 1 "GND")
			(pintype "passive")
		)
	)
	(footprint "antmicro-footprints:R_0402_1005Metric"
		(layer "F.Cu")
		(at 236.2 129.55 180)
		(descr "Resistor SMD 0402")
		(tags "resistor SMD 0402")
		(property "Reference" "R179"
			(at 1.825 3.525 180)
			(layer "F.SilkS")
			(effects
				(font
					(size 0.7 0.7)
					(thickness 0.15)
				)
				(justify left bottom)
			)
		)
		(property "Value" "R_33R_0402"
			(at 0 1.4 180)
			(layer "F.Fab")
			(effects
				(font
					(size 0.7 0.7)
					(thickness 0.15)
				)
				(justify left bottom)
			)
		)
		(property "Description" "SMD Chip Resistor, 33 ohm, ± 1%, 62.5 mW, 0402 [1005 Metric], Thick Film, General Purpose"
			(at 0 0 180)
			(layer "F.Fab")
			(hide yes)
			(effects
				(font
					(size 1.27 1.27)
					(thickness 0.15)
				)
			)
		)
		(property "Author" "Antmicro"
			(at 472.4 259.1 0)
			(layer "F.Fab")
			(hide yes)
			(effects
				(font
					(size 1 1)
					(thickness 0.15)
				)
			)
		)
		(property "License" "Apache-2.0"
			(at 472.4 259.1 0)
			(layer "F.Fab")
			(hide yes)
			(effects
				(font
					(size 1 1)
					(thickness 0.15)
				)
			)
		)
		(property "MPN" "CR0402-FX-33R0GLF"
			(at 472.4 259.1 0)
			(layer "F.Fab")
			(hide yes)
			(effects
				(font
					(size 1 1)
					(thickness 0.15)
				)
			)
		)
		(property "Manufacturer" "Bourns"
			(at 472.4 259.1 0)
			(layer "F.Fab")
			(hide yes)
			(effects
				(font
					(size 1 1)
					(thickness 0.15)
				)
			)
		)
		(property "Tolerance" "1%"
			(at 472.4 259.1 0)
			(layer "F.Fab")
			(hide yes)
			(effects
				(font
					(size 1 1)
					(thickness 0.15)
				)
			)
		)
		(property "Val" "33R"
			(at 472.4 259.1 0)
			(layer "F.Fab")
			(hide yes)
			(effects
				(font
					(size 1 1)
					(thickness 0.15)
				)
			)
		)
		(sheetname "USB PHY")
		(sheetfile "usb-phy.kicad_sch")
		(attr smd)
		(fp_rect
			(start -0.925 -0.47)
			(end 0.925 0.47)
			(stroke
				(width 0.05)
				(type default)
			)
			(fill no)
			(layer "F.CrtYd")
		)
		(fp_rect
			(start -0.5 -0.25)
			(end 0.5 0.25)
			(stroke
				(width 0.15)
				(type solid)
			)
			(fill no)
			(layer "F.Fab")
		)
		(pad "1" smd roundrect
			(at -0.48 0 180)
			(size 0.59 0.64)
			(layers "F.Cu" "F.Mask" "F.Paste")
			(roundrect_rratio 0.25)
			(net 371 "Net-(U22-B4)")
			(pintype "passive")
		)
		(pad "2" smd roundrect
			(at 0.48 0 180)
			(size 0.59 0.64)
			(layers "F.Cu" "F.Mask" "F.Paste")
			(roundrect_rratio 0.25)
			(net 190 "/FPGA Config/JTAG.TDO")
			(pintype "passive")
		)
	)
	(footprint "antmicro-footprints:C_0402_1005Metric"
		(layer "F.Cu")
		(at 260.3 135.7 90)
		(descr "Capacitor SMD 0402")
		(tags "capacitor SMD 0402")
		(property "Reference" "C224"
			(at -1.75 -0.45 90)
			(layer "F.SilkS")
			(effects
				(font
					(size 0.7 0.7)
					(thickness 0.15)
				)
				(justify left bottom)
			)
		)
		(property "Value" "C_100n_0402"
			(at 0 1.169 90)
			(layer "F.Fab")
			(effects
				(font
					(size 0.7 0.7)
					(thickness 0.15)
				)
				(justify left bottom)
			)
		)
		(property "Description" "SMD Multilayer Ceramic Capacitor, 0.1 µF, 50 V, 0402 [1005 Metric], ± 10%, X5R, GRM Series"
			(at 0 0 90)
			(layer "F.Fab")
			(hide yes)
			(effects
				(font
					(size 1.27 1.27)
					(thickness 0.15)
				)
			)
		)
		(property "Author" "Antmicro"
			(at 396 -124.6 0)
			(layer "F.Fab")
			(hide yes)
			(effects
				(font
					(size 1 1)
					(thickness 0.15)
				)
			)
		)
		(property "Dielectric" "X5R"
			(at 396 -124.6 0)
			(layer "F.Fab")
			(hide yes)
			(effects
				(font
					(size 1 1)
					(thickness 0.15)
				)
			)
		)
		(property "License" "Apache-2.0"
			(at 396 -124.6 0)
			(layer "F.Fab")
			(hide yes)
			(effects
				(font
					(size 1 1)
					(thickness 0.15)
				)
			)
		)
		(property "MPN" "GRM155R61H104KE14D"
			(at 396 -124.6 0)
			(layer "F.Fab")
			(hide yes)
			(effects
				(font
					(size 1 1)
					(thickness 0.15)
				)
			)
		)
		(property "Manufacturer" "Murata"
			(at 396 -124.6 0)
			(layer "F.Fab")
			(hide yes)
			(effects
				(font
					(size 1 1)
					(thickness 0.15)
				)
			)
		)
		(property "Val" "100n"
			(at 396 -124.6 0)
			(layer "F.Fab")
			(hide yes)
			(effects
				(font
					(size 1 1)
					(thickness 0.15)
				)
			)
		)
		(property "Voltage" "50V"
			(at 396 -124.6 0)
			(layer "F.Fab")
			(hide yes)
			(effects
				(font
					(size 1 1)
					(thickness 0.15)
				)
			)
		)
		(sheetname "USB PHY")
		(sheetfile "usb-phy.kicad_sch")
		(attr smd)
		(fp_rect
			(start -0.925 -0.47)
			(end 0.925 0.47)
			(stroke
				(width 0.05)
				(type default)
			)
			(fill no)
			(layer "F.CrtYd")
		)
		(fp_line
			(start 0.504 -0.25)
			(end 0.504 0.248)
			(stroke
				(width 0.15)
				(type solid)
			)
			(layer "F.Fab")
		)
		(fp_line
			(start -0.494 -0.25)
			(end 0.504 -0.25)
			(stroke
				(width 0.15)
				(type solid)
			)
			(layer "F.Fab")
		)
		(fp_line
			(start 0.504 0.248)
			(end -0.494 0.248)
			(stroke
				(width 0.15)
				(type solid)
			)
			(layer "F.Fab")
		)
		(fp_line
			(start -0.494 0.248)
			(end -0.494 -0.25)
			(stroke
				(width 0.15)
				(type solid)
			)
			(layer "F.Fab")
		)
		(pad "1" smd roundrect
			(at -0.48 0 90)
			(size 0.59 0.64)
			(layers "F.Cu" "F.Mask" "F.Paste")
			(roundrect_rratio 0.25)
			(net 1 "GND")
			(pintype "passive")
		)
		(pad "2" smd roundrect
			(at 0.48 0 90)
			(size 0.59 0.64)
			(layers "F.Cu" "F.Mask" "F.Paste")
			(roundrect_rratio 0.25)
			(net 707 "/USB PHY/FTDI_3V3")
			(pintype "passive")
		)
	)
	(footprint "antmicro-footprints:C_Pol_EIA-B"
		(layer "F.Cu")
		(at 206.15592 152.9)
		(property "Reference" "C133"
			(at -1.46592 2.6 0)
			(layer "F.SilkS")
			(effects
				(font
					(size 0.7 0.7)
					(thickness 0.15)
				)
				(justify left bottom)
			)
		)
		(property "Value" "C_Pol_330u_6.3V_KEMET-T520-B"
			(at -2.34 2.45 0)
			(layer "F.Fab")
			(effects
				(font
					(size 0.7 0.7)
					(thickness 0.15)
				)
				(justify left bottom)
			)
		)
		(property "Description" "Tantalum Polymer Capacitor, KO-CAP®, 330 µF, ± 20%, 6.3 V, B, 0.04 ohm, 1411 [3528 Metric]"
			(at 0 0 0)
			(layer "F.Fab")
			(hide yes)
			(effects
				(font
					(size 1.27 1.27)
					(thickness 0.15)
				)
			)
		)
		(property "Author" "Antmicro"
			(at 0 0 0)
			(layer "F.Fab")
			(hide yes)
			(effects
				(font
					(size 1 1)
					(thickness 0.15)
				)
			)
		)
		(property "Dielectric" ""
			(at 0 0 0)
			(layer "F.Fab")
			(hide yes)
			(effects
				(font
					(size 1 1)
					(thickness 0.15)
				)
			)
		)
		(property "License" "Apache-2.0"
			(at 0 0 0)
			(layer "F.Fab")
			(hide yes)
			(effects
				(font
					(size 1 1)
					(thickness 0.15)
				)
			)
		)
		(property "MPN" "T520B337M006ATE040"
			(at 0 0 0)
			(layer "F.Fab")
			(hide yes)
			(effects
				(font
					(size 1 1)
					(thickness 0.15)
				)
			)
		)
		(property "Manufacturer" "KEMET"
			(at 0 0 0)
			(layer "F.Fab")
			(hide yes)
			(effects
				(font
					(size 1 1)
					(thickness 0.15)
				)
			)
		)
		(property "Val" "330u"
			(at 0 0 0)
			(layer "F.Fab")
			(hide yes)
			(effects
				(font
					(size 1 1)
					(thickness 0.15)
				)
			)
		)
		(property "Voltage" "6.3V"
			(at 0 0 0)
			(layer "F.Fab")
			(hide yes)
			(effects
				(font
					(size 1 1)
					(thickness 0.15)
				)
			)
		)
		(sheetname "FPGA supply")
		(sheetfile "fpga-supply.kicad_sch")
		(attr smd)
		(fp_line
			(start -2.521 -1.676)
			(end -2.123 -1.676)
			(stroke
				(width 0.15)
				(type solid)
			)
			(layer "F.SilkS")
		)
		(fp_line
			(start -2.325 -1.475)
			(end -2.325 -1.878)
			(stroke
				(width 0.15)
				(type solid)
			)
			(layer "F.SilkS")
		)
		(fp_line
			(start -1.8 -1.6)
			(end 1.8 -1.6)
			(stroke
				(width 0.15)
				(type solid)
			)
			(layer "F.SilkS")
		)
		(fp_line
			(start -1.8 -1.3)
			(end -1.8 -1.6)
			(stroke
				(width 0.15)
				(type solid)
			)
			(layer "F.SilkS")
		)
		(fp_line
			(start -1.8 1.3)
			(end -1.8 1.6)
			(stroke
				(width 0.15)
				(type solid)
			)
			(layer "F.SilkS")
		)
		(fp_line
			(start 1.8 -1.3)
			(end 1.8 -1.6)
			(stroke
				(width 0.15)
				(type solid)
			)
			(layer "F.SilkS")
		)
		(fp_line
			(start 1.8 1.3)
			(end 1.8 1.6)
			(stroke
				(width 0.15)
				(type solid)
			)
			(layer "F.SilkS")
		)
		(fp_line
			(start 1.8 1.6)
			(end -1.8 1.6)
			(stroke
				(width 0.15)
				(type solid)
			)
			(layer "F.SilkS")
		)
		(fp_line
			(start -2.411 -1.35)
			(end -2.41 1.35)
			(stroke
				(width 0.05)
				(type solid)
			)
			(layer "F.CrtYd")
		)
		(fp_line
			(start -1.97 -1.75)
			(end -1.97 -1.35)
			(stroke
				(width 0.05)
				(type solid)
			)
			(layer "F.CrtYd")
		)
		(fp_line
			(start -1.97 -1.35)
			(end -2.41 -1.35)
			(stroke
				(width 0.05)
				(type solid)
			)
			(layer "F.CrtYd")
		)
		(fp_line
			(start -1.97 1.35)
			(end -2.41 1.35)
			(stroke
				(width 0.05)
				(type solid)
			)
			(layer "F.CrtYd")
		)
		(fp_line
			(start -1.97 1.35)
			(end -1.97 1.75)
			(stroke
				(width 0.05)
				(type solid)
			)
			(layer "F.CrtYd")
		)
		(fp_line
			(start 1.959 -1.75)
			(end -1.971 -1.75)
			(stroke
				(width 0.05)
				(type solid)
			)
			(layer "F.CrtYd")
		)
		(fp_line
			(start 1.959 -1.75)
			(end 1.959 -1.35)
			(stroke
				(width 0.05)
				(type solid)
			)
			(layer "F.CrtYd")
		)
		(fp_line
			(start 1.96 1.35)
			(end 1.96 1.75)
			(stroke
				(width 0.05)
				(type solid)
			)
			(layer "F.CrtYd")
		)
		(fp_line
			(start 1.96 1.75)
			(end -1.97 1.75)
			(stroke
				(width 0.05)
				(type solid)
			)
			(layer "F.CrtYd")
		)
		(fp_line
			(start 2.399 -1.35)
			(end 1.959 -1.35)
			(stroke
				(width 0.05)
				(type solid)
			)
			(layer "F.CrtYd")
		)
		(fp_line
			(start 2.399 -1.35)
			(end 2.4 1.35)
			(stroke
				(width 0.05)
				(type solid)
			)
			(layer "F.CrtYd")
		)
		(fp_line
			(start 2.4 1.35)
			(end 1.96 1.35)
			(stroke
				(width 0.05)
				(type solid)
			)
			(layer "F.CrtYd")
		)
		(fp_line
			(start -1.7 1.324)
			(end -1.551 1.475)
			(stroke
				(width 0.15)
				(type solid)
			)
			(layer "F.Fab")
		)
		(fp_rect
			(start -1.72 -1.5)
			(end 1.719 1.499)
			(stroke
				(width 0.15)
				(type solid)
			)
			(fill no)
			(layer "F.Fab")
		)
		(pad "1" smd roundrect
			(at -1.551 0)
			(size 1.2 2.2)
			(layers "F.Cu" "F.Mask" "F.Paste")
			(roundrect_rratio 0.1)
			(net 650 "+1V0")
			(pintype "passive")
		)
		(pad "2" smd roundrect
			(at 1.55 0)
			(size 1.2 2.2)
			(layers "F.Cu" "F.Mask" "F.Paste")
			(roundrect_rratio 0.1)
			(net 1 "GND")
			(pintype "passive")
		)
	)
	(footprint "antmicro-footprints:C_0603_1608Metric"
		(layer "B.Cu")
		(at 191.2 114 180)
		(descr "Capacitor SMD 0603")
		(tags "capacitor 0603")
		(property "Reference" "C112"
			(at -1.45 0.575 0)
			(layer "B.SilkS")
			(effects
				(font
					(size 0.7 0.7)
					(thickness 0.15)
				)
				(justify left bottom mirror)
			)
		)
		(property "Value" "C_47u_0603"
			(at 0 -1.6 0)
			(layer "B.Fab")
			(effects
				(font
					(size 0.7 0.7)
					(thickness 0.15)
				)
				(justify left bottom mirror)
			)
		)
		(property "Description" "SMD Multilayer Ceramic Capacitor, 47 µF, 6.3 V, 0603 [1608 Metric], ± 20%, X5R, GRM Series"
			(at 0 0 180)
			(layer "F.Fab")
			(hide yes)
			(effects
				(font
					(size 1.27 1.27)
					(thickness 0.15)
				)
			)
		)
		(property "Author" "Antmicro"
			(at 382.4 228 0)
			(layer "B.Fab")
			(hide yes)
			(effects
				(font
					(size 1 1)
					(thickness 0.15)
				)
				(justify mirror)
			)
		)
		(property "Dielectric" ""
			(at 382.4 228 0)
			(layer "B.Fab")
			(hide yes)
			(effects
				(font
					(size 1 1)
					(thickness 0.15)
				)
				(justify mirror)
			)
		)
		(property "License" "Apache-2.0"
			(at 382.4 228 0)
			(layer "B.Fab")
			(hide yes)
			(effects
				(font
					(size 1 1)
					(thickness 0.15)
				)
				(justify mirror)
			)
		)
		(property "MPN" "GRM188R60J476ME15D"
			(at 382.4 228 0)
			(layer "B.Fab")
			(hide yes)
			(effects
				(font
					(size 1 1)
					(thickness 0.15)
				)
				(justify mirror)
			)
		)
		(property "Manufacturer" "Murata"
			(at 382.4 228 0)
			(layer "B.Fab")
			(hide yes)
			(effects
				(font
					(size 1 1)
					(thickness 0.15)
				)
				(justify mirror)
			)
		)
		(property "Val" "47u"
			(at 382.4 228 0)
			(layer "B.Fab")
			(hide yes)
			(effects
				(font
					(size 1 1)
					(thickness 0.15)
				)
				(justify mirror)
			)
		)
		(property "Voltage" ""
			(at 382.4 228 0)
			(layer "B.Fab")
			(hide yes)
			(effects
				(font
					(size 1 1)
					(thickness 0.15)
				)
				(justify mirror)
			)
		)
		(sheetname "FPGA supply")
		(sheetfile "fpga-supply.kicad_sch")
		(attr smd)
		(fp_line
			(start -0.15 0.4)
			(end 0.15 0.4)
			(stroke
				(width 0.15)
				(type solid)
			)
			(layer "B.SilkS")
		)
		(fp_line
			(start -0.15 -0.4)
			(end 0.15 -0.4)
			(stroke
				(width 0.15)
				(type solid)
			)
			(layer "B.SilkS")
		)
		(fp_rect
			(start -1.25 0.65)
			(end 1.25 -0.65)
			(stroke
				(width 0.05)
				(type solid)
			)
			(fill no)
			(layer "B.CrtYd")
		)
		(fp_rect
			(start -0.8 0.4)
			(end 0.8 -0.4)
			(stroke
				(width 0.15)
				(type solid)
			)
			(fill no)
			(layer "B.Fab")
		)
		(pad "1" smd roundrect
			(at -0.7 0 180)
			(size 0.8 1)
			(layers "B.Cu" "B.Mask" "B.Paste")
			(roundrect_rratio 0.2)
			(net 6 "+1V0_MGTAVCC")
			(pintype "passive")
		)
		(pad "2" smd roundrect
			(at 0.7 0 180)
			(size 0.8 1)
			(layers "B.Cu" "B.Mask" "B.Paste")
			(roundrect_rratio 0.2)
			(net 1 "GND")
			(pintype "passive")
		)
	)
	(footprint "antmicro-footprints:R_0402_1005Metric"
		(layer "B.Cu")
		(at 251.001 129.7 180)
		(descr "Resistor SMD 0402")
		(tags "resistor SMD 0402")
		(property "Reference" "R98"
			(at -1.274 -1.275 0)
			(layer "B.SilkS")
			(effects
				(font
					(size 0.7 0.7)
					(thickness 0.15)
				)
				(justify left bottom mirror)
			)
		)
		(property "Value" "R_100R_0402"
			(at 0 -1.4 0)
			(layer "B.Fab")
			(effects
				(font
					(size 0.7 0.7)
					(thickness 0.15)
				)
				(justify left bottom mirror)
			)
		)
		(property "Description" "SMD Chip Resistor, 100 ohm, ± 1%, 62.5 mW, 0402 [1005 Metric], Thick Film, General Purpose"
			(at 0 0 180)
			(layer "F.Fab")
			(hide yes)
			(effects
				(font
					(size 1.27 1.27)
					(thickness 0.15)
				)
			)
		)
		(property "Author" "Antmicro"
			(at 502.002 259.4 0)
			(layer "B.Fab")
			(hide yes)
			(effects
				(font
					(size 1 1)
					(thickness 0.15)
				)
				(justify mirror)
			)
		)
		(property "License" "Apache-2.0"
			(at 502.002 259.4 0)
			(layer "B.Fab")
			(hide yes)
			(effects
				(font
					(size 1 1)
					(thickness 0.15)
				)
				(justify mirror)
			)
		)
		(property "MPN" "CR0402-FX-1000GLF"
			(at 502.002 259.4 0)
			(layer "B.Fab")
			(hide yes)
			(effects
				(font
					(size 1 1)
					(thickness 0.15)
				)
				(justify mirror)
			)
		)
		(property "Manufacturer" "Bourns"
			(at 502.002 259.4 0)
			(layer "B.Fab")
			(hide yes)
			(effects
				(font
					(size 1 1)
					(thickness 0.15)
				)
				(justify mirror)
			)
		)
		(property "Tolerance" "1%"
			(at 502.002 259.4 0)
			(layer "B.Fab")
			(hide yes)
			(effects
				(font
					(size 1 1)
					(thickness 0.15)
				)
				(justify mirror)
			)
		)
		(property "Val" "100R"
			(at 502.002 259.4 0)
			(layer "B.Fab")
			(hide yes)
			(effects
				(font
					(size 1 1)
					(thickness 0.15)
				)
				(justify mirror)
			)
		)
		(sheetname "SPI Flash + SD Card")
		(sheetfile "spi-flash.kicad_sch")
		(attr smd)
		(fp_rect
			(start -0.925 0.47)
			(end 0.925 -0.47)
			(stroke
				(width 0.05)
				(type default)
			)
			(fill no)
			(layer "B.CrtYd")
		)
		(fp_rect
			(start -0.5 0.25)
			(end 0.5 -0.25)
			(stroke
				(width 0.15)
				(type solid)
			)
			(fill no)
			(layer "B.Fab")
		)
		(pad "1" smd roundrect
			(at -0.48 0 180)
			(size 0.59 0.64)
			(layers "B.Cu" "B.Mask" "B.Paste")
			(roundrect_rratio 0.25)
			(net 74 "/SPI Flash + SD Card/SD_CARD_~{CD}")
			(pintype "passive")
		)
		(pad "2" smd roundrect
			(at 0.48 0 180)
			(size 0.59 0.64)
			(layers "B.Cu" "B.Mask" "B.Paste")
			(roundrect_rratio 0.25)
			(net 416 "/FPGA Bank 33 & 34/SD_CARD.~{CD}")
			(pintype "passive")
		)
	)
	(footprint "antmicro-footprints:C_0201"
		(layer "B.Cu")
		(at 188.000001 130.500001 180)
		(descr "Capacitor SMD 0201")
		(tags "capacitor SMD 0201")
		(property "Reference" "C151"
			(at 0.550001 -0.349999 0)
			(layer "B.SilkS")
			(effects
				(font
					(size 0.7 0.7)
					(thickness 0.15)
				)
				(justify left bottom mirror)
			)
		)
		(property "Value" "C_100n_0201"
			(at 0 -1.4 0)
			(layer "B.Fab")
			(effects
				(font
					(size 0.7 0.7)
					(thickness 0.15)
				)
				(justify left bottom mirror)
			)
		)
		(property "Description" "SMD Multilayer Ceramic Capacitor, 0.1 µF, 6.3 V, 0201 [0603 Metric], ± 10%, X6S, CC Series"
			(at 0 0 180)
			(layer "F.Fab")
			(hide yes)
			(effects
				(font
					(size 1.27 1.27)
					(thickness 0.15)
				)
			)
		)
		(property "Author" "Antmicro"
			(at 376.000002 261.000002 0)
			(layer "B.Fab")
			(hide yes)
			(effects
				(font
					(size 1 1)
					(thickness 0.15)
				)
				(justify mirror)
			)
		)
		(property "Dielectric" ""
			(at 376.000002 261.000002 0)
			(layer "B.Fab")
			(hide yes)
			(effects
				(font
					(size 1 1)
					(thickness 0.15)
				)
				(justify mirror)
			)
		)
		(property "License" "Apache-2.0"
			(at 376.000002 261.000002 0)
			(layer "B.Fab")
			(hide yes)
			(effects
				(font
					(size 1 1)
					(thickness 0.15)
				)
				(justify mirror)
			)
		)
		(property "MPN" "CC0201KRX6S5BB104"
			(at 376.000002 261.000002 0)
			(layer "B.Fab")
			(hide yes)
			(effects
				(font
					(size 1 1)
					(thickness 0.15)
				)
				(justify mirror)
			)
		)
		(property "Manufacturer" "YAGEO"
			(at 376.000002 261.000002 0)
			(layer "B.Fab")
			(hide yes)
			(effects
				(font
					(size 1 1)
					(thickness 0.15)
				)
				(justify mirror)
			)
		)
		(property "Val" "100n"
			(at 376.000002 261.000002 0)
			(layer "B.Fab")
			(hide yes)
			(effects
				(font
					(size 1 1)
					(thickness 0.15)
				)
				(justify mirror)
			)
		)
		(property "Voltage" ""
			(at 376.000002 261.000002 0)
			(layer "B.Fab")
			(hide yes)
			(effects
				(font
					(size 1 1)
					(thickness 0.15)
				)
				(justify mirror)
			)
		)
		(sheetname "FPGA supply")
		(sheetfile "fpga-supply.kicad_sch")
		(attr smd)
		(fp_rect
			(start -0.7 0.35)
			(end 0.7 -0.35)
			(stroke
				(width 0.05)
				(type default)
			)
			(fill no)
			(layer "B.CrtYd")
		)
		(fp_rect
			(start 0.3 -0.15)
			(end -0.301 0.149)
			(stroke
				(width 0.15)
				(type solid)
			)
			(fill no)
			(layer "B.Fab")
		)
		(pad "" smd roundrect
			(at -0.349 0.002 180)
			(size 0.318 0.36)
			(layers "B.Paste")
			(roundrect_rratio 0.25)
		)
		(pad "" smd roundrect
			(at 0.341 0.002 180)
			(size 0.318 0.36)
			(layers "B.Paste")
			(roundrect_rratio 0.25)
		)
		(pad "1" smd roundrect
			(at -0.321 0.002 180)
			(size 0.46 0.4)
			(layers "B.Cu" "B.Mask")
			(roundrect_rratio 0.25)
			(net 1 "GND")
			(pintype "passive")
		)
		(pad "2" smd roundrect
			(at 0.32 0.002 180)
			(size 0.46 0.4)
			(layers "B.Cu" "B.Mask")
			(roundrect_rratio 0.25)
			(net 8 "+1V2_MGTAVTT")
			(pintype "passive")
		)
	)
	(footprint "antmicro-footprints:R_0402_1005Metric"
		(layer "B.Cu")
		(at 266.001 126.7)
		(descr "Resistor SMD 0402")
		(tags "resistor SMD 0402")
		(property "Reference" "R172"
			(at -0.901 0.675 180)
			(layer "B.SilkS")
			(effects
				(font
					(size 0.7 0.7)
					(thickness 0.15)
				)
				(justify left bottom mirror)
			)
		)
		(property "Value" "R_1k5_0402"
			(at 0 -1.4 180)
			(layer "B.Fab")
			(effects
				(font
					(size 0.7 0.7)
					(thickness 0.15)
				)
				(justify left bottom mirror)
			)
		)
		(property "Description" "SMD Chip Resistor, 1.5 kohm, ± 1%, 62.5 mW, 0402 [1005 Metric], Thick Film, General Purpose"
			(at 0 0 0)
			(layer "F.Fab")
			(hide yes)
			(effects
				(font
					(size 1.27 1.27)
					(thickness 0.15)
				)
			)
		)
		(property "Author" "Antmicro"
			(at 0 0 0)
			(layer "B.Fab")
			(hide yes)
			(effects
				(font
					(size 1 1)
					(thickness 0.15)
				)
				(justify mirror)
			)
		)
		(property "DNP" "DNP"
			(at 0 0 0)
			(layer "B.Fab")
			(hide yes)
			(effects
				(font
					(size 1 1)
					(thickness 0.15)
				)
				(justify mirror)
			)
		)
		(property "License" "Apache-2.0"
			(at 0 0 0)
			(layer "B.Fab")
			(hide yes)
			(effects
				(font
					(size 1 1)
					(thickness 0.15)
				)
				(justify mirror)
			)
		)
		(property "MPN" "CR0402-FX-1501GLF"
			(at 0 0 0)
			(layer "B.Fab")
			(hide yes)
			(effects
				(font
					(size 1 1)
					(thickness 0.15)
				)
				(justify mirror)
			)
		)
		(property "Manufacturer" "Bourns"
			(at 0 0 0)
			(layer "B.Fab")
			(hide yes)
			(effects
				(font
					(size 1 1)
					(thickness 0.15)
				)
				(justify mirror)
			)
		)
		(property "Tolerance" "1%"
			(at 0 0 0)
			(layer "B.Fab")
			(hide yes)
			(effects
				(font
					(size 1 1)
					(thickness 0.15)
				)
				(justify mirror)
			)
		)
		(property "Val" "1k5"
			(at 0 0 0)
			(layer "B.Fab")
			(hide yes)
			(effects
				(font
					(size 1 1)
					(thickness 0.15)
				)
				(justify mirror)
			)
		)
		(property "dnp" ""
			(at 0 0 0)
			(layer "B.Fab")
			(hide yes)
			(effects
				(font
					(size 1 1)
					(thickness 0.15)
				)
				(justify mirror)
			)
		)
		(property "exclude_from_bom" ""
			(at 0 0 0)
			(layer "B.Fab")
			(hide yes)
			(effects
				(font
					(size 1 1)
					(thickness 0.15)
				)
				(justify mirror)
			)
		)
		(sheetname "USB PHY")
		(sheetfile "usb-phy.kicad_sch")
		(attr smd exclude_from_bom)
		(fp_rect
			(start -0.925 0.47)
			(end 0.925 -0.47)
			(stroke
				(width 0.05)
				(type default)
			)
			(fill no)
			(layer "B.CrtYd")
		)
		(fp_rect
			(start -0.5 0.25)
			(end 0.5 -0.25)
			(stroke
				(width 0.15)
				(type solid)
			)
			(fill no)
			(layer "B.Fab")
		)
		(pad "1" smd roundrect
			(at -0.48 0)
			(size 0.59 0.64)
			(layers "B.Cu" "B.Mask" "B.Paste")
			(roundrect_rratio 0.25)
			(net 843 "/USB PHY/USB_USR_CONN_D-")
			(pintype "passive")
		)
		(pad "2" smd roundrect
			(at 0.48 0)
			(size 0.59 0.64)
			(layers "B.Cu" "B.Mask" "B.Paste")
			(roundrect_rratio 0.25)
			(net 926 "/USB PHY/USB_USR_VPU")
			(pintype "passive")
		)
	)
	(footprint "antmicro-footprints:R_0402_1005Metric"
		(layer "B.Cu")
		(at 168.55 185.95 -90)
		(descr "Resistor SMD 0402")
		(tags "resistor SMD 0402")
		(property "Reference" "R322"
			(at -3.625 -0.525 90)
			(layer "B.SilkS")
			(effects
				(font
					(size 0.7 0.7)
					(thickness 0.15)
				)
				(justify left bottom mirror)
			)
		)
		(property "Value" "R_47k_0402"
			(at 0 -1.4 90)
			(layer "B.Fab")
			(effects
				(font
					(size 0.7 0.7)
					(thickness 0.15)
				)
				(justify left bottom mirror)
			)
		)
		(property "Description" "SMD Chip Resistor, 47 kohm, ± 1%, 62.5 mW, 0402 [1005 Metric], Thick Film, General Purpose"
			(at 0 0 270)
			(layer "F.Fab")
			(hide yes)
			(effects
				(font
					(size 1.27 1.27)
					(thickness 0.15)
				)
			)
		)
		(property "Author" "Antmicro"
			(at -17.4 354.5 0)
			(layer "B.Fab")
			(hide yes)
			(effects
				(font
					(size 1 1)
					(thickness 0.15)
				)
				(justify mirror)
			)
		)
		(property "License" "Apache-2.0"
			(at -17.4 354.5 0)
			(layer "B.Fab")
			(hide yes)
			(effects
				(font
					(size 1 1)
					(thickness 0.15)
				)
				(justify mirror)
			)
		)
		(property "MPN" "CR0402-FX-4702GLF"
			(at -17.4 354.5 0)
			(layer "B.Fab")
			(hide yes)
			(effects
				(font
					(size 1 1)
					(thickness 0.15)
				)
				(justify mirror)
			)
		)
		(property "Manufacturer" "Bourns"
			(at -17.4 354.5 0)
			(layer "B.Fab")
			(hide yes)
			(effects
				(font
					(size 1 1)
					(thickness 0.15)
				)
				(justify mirror)
			)
		)
		(property "Tolerance" "1%"
			(at -17.4 354.5 0)
			(layer "B.Fab")
			(hide yes)
			(effects
				(font
					(size 1 1)
					(thickness 0.15)
				)
				(justify mirror)
			)
		)
		(property "Val" "47k"
			(at -17.4 354.5 0)
			(layer "B.Fab")
			(hide yes)
			(effects
				(font
					(size 1 1)
					(thickness 0.15)
				)
				(justify mirror)
			)
		)
		(sheetname "DC-DC Converters")
		(sheetfile "dc-dc.kicad_sch")
		(attr smd)
		(fp_rect
			(start -0.925 0.47)
			(end 0.925 -0.47)
			(stroke
				(width 0.05)
				(type default)
			)
			(fill no)
			(layer "B.CrtYd")
		)
		(fp_rect
			(start -0.5 0.25)
			(end 0.5 -0.25)
			(stroke
				(width 0.15)
				(type solid)
			)
			(fill no)
			(layer "B.Fab")
		)
		(pad "1" smd roundrect
			(at -0.48 0 270)
			(size 0.59 0.64)
			(layers "B.Cu" "B.Mask" "B.Paste")
			(roundrect_rratio 0.25)
			(net 968 "/DC-DC Converters/EN3")
			(pintype "passive")
		)
		(pad "2" smd roundrect
			(at 0.48 0 270)
			(size 0.59 0.64)
			(layers "B.Cu" "B.Mask" "B.Paste")
			(roundrect_rratio 0.25)
			(net 37 "+3V3_AON")
			(pintype "passive")
		)
	)
	(footprint "antmicro-footprints:R_0402_1005Metric"
		(layer "B.Cu")
		(at 195.691252 94.85 180)
		(descr "Resistor SMD 0402")
		(tags "resistor SMD 0402")
		(property "Reference" "R202"
			(at 0.716252 -0.425 0)
			(layer "B.SilkS")
			(effects
				(font
					(size 0.7 0.7)
					(thickness 0.15)
				)
				(justify left bottom mirror)
			)
		)
		(property "Value" "R_10k_0402"
			(at 0 -1.4 0)
			(layer "B.Fab")
			(effects
				(font
					(size 0.7 0.7)
					(thickness 0.15)
				)
				(justify left bottom mirror)
			)
		)
		(property "Description" "SMD Chip Resistor, 10 kohm, ± 1%, 62.5 mW, 0402 [1005 Metric], Thick Film, General Purpose"
			(at 0 0 180)
			(layer "F.Fab")
			(hide yes)
			(effects
				(font
					(size 1.27 1.27)
					(thickness 0.15)
				)
			)
		)
		(property "Author" "Antmicro"
			(at 391.382504 189.7 0)
			(layer "B.Fab")
			(hide yes)
			(effects
				(font
					(size 1 1)
					(thickness 0.15)
				)
				(justify mirror)
			)
		)
		(property "DNP" "DNP"
			(at 391.382504 189.7 0)
			(layer "B.Fab")
			(hide yes)
			(effects
				(font
					(size 1 1)
					(thickness 0.15)
				)
				(justify mirror)
			)
		)
		(property "License" "Apache-2.0"
			(at 391.382504 189.7 0)
			(layer "B.Fab")
			(hide yes)
			(effects
				(font
					(size 1 1)
					(thickness 0.15)
				)
				(justify mirror)
			)
		)
		(property "MPN" "CR0402-FX-1002GLF"
			(at 391.382504 189.7 0)
			(layer "B.Fab")
			(hide yes)
			(effects
				(font
					(size 1 1)
					(thickness 0.15)
				)
				(justify mirror)
			)
		)
		(property "Manufacturer" "Bourns"
			(at 391.382504 189.7 0)
			(layer "B.Fab")
			(hide yes)
			(effects
				(font
					(size 1 1)
					(thickness 0.15)
				)
				(justify mirror)
			)
		)
		(property "Tolerance" "1%"
			(at 391.382504 189.7 0)
			(layer "B.Fab")
			(hide yes)
			(effects
				(font
					(size 1 1)
					(thickness 0.15)
				)
				(justify mirror)
			)
		)
		(property "Val" "10k"
			(at 391.382504 189.7 0)
			(layer "B.Fab")
			(hide yes)
			(effects
				(font
					(size 1 1)
					(thickness 0.15)
				)
				(justify mirror)
			)
		)
		(property "dnp" ""
			(at 391.382504 189.7 0)
			(layer "B.Fab")
			(hide yes)
			(effects
				(font
					(size 1 1)
					(thickness 0.15)
				)
				(justify mirror)
			)
		)
		(property "exclude_from_bom" ""
			(at 391.382504 189.7 0)
			(layer "B.Fab")
			(hide yes)
			(effects
				(font
					(size 1 1)
					(thickness 0.15)
				)
				(justify mirror)
			)
		)
		(sheetname "HDMI + Ethernet")
		(sheetfile "hdmi-ethernet.kicad_sch")
		(attr smd exclude_from_bom)
		(fp_rect
			(start -0.925 0.47)
			(end 0.925 -0.47)
			(stroke
				(width 0.05)
				(type default)
			)
			(fill no)
			(layer "B.CrtYd")
		)
		(fp_rect
			(start -0.5 0.25)
			(end 0.5 -0.25)
			(stroke
				(width 0.15)
				(type solid)
			)
			(fill no)
			(layer "B.Fab")
		)
		(pad "1" smd roundrect
			(at -0.48 0 180)
			(size 0.59 0.64)
			(layers "B.Cu" "B.Mask" "B.Paste")
			(roundrect_rratio 0.25)
			(net 506 "/FPGA Bank 16 & 17/GBE_RGMII.RXD0")
			(pintype "passive")
		)
		(pad "2" smd roundrect
			(at 0.48 0 180)
			(size 0.59 0.64)
			(layers "B.Cu" "B.Mask" "B.Paste")
			(roundrect_rratio 0.25)
			(net 24 "+3V3")
			(pintype "passive")
		)
	)
	(footprint "antmicro-footprints:C_0402_1005Metric"
		(layer "B.Cu")
		(at 256.101 161.6 -90)
		(descr "Capacitor SMD 0402")
		(tags "capacitor SMD 0402")
		(property "Reference" "C273"
			(at -1.35 -5.124 90)
			(layer "B.SilkS")
			(effects
				(font
					(size 0.7 0.7)
					(thickness 0.15)
				)
				(justify left bottom mirror)
			)
		)
		(property "Value" "C_10p_0402"
			(at 0 -1.4 90)
			(layer "B.Fab")
			(effects
				(font
					(size 0.7 0.7)
					(thickness 0.15)
				)
				(justify left bottom mirror)
			)
		)
		(property "Description" "SMD Multilayer Ceramic Capacitor, 10 pF, 50 V, 0402 [1005 Metric], ± 2%, C0G / NP0, GCM"
			(at 0 0 270)
			(layer "F.Fab")
			(hide yes)
			(effects
				(font
					(size 1.27 1.27)
					(thickness 0.15)
				)
			)
		)
		(property "Author" "Antmicro"
			(at 94.501 417.701 0)
			(layer "B.Fab")
			(hide yes)
			(effects
				(font
					(size 1 1)
					(thickness 0.15)
				)
				(justify mirror)
			)
		)
		(property "Dielectric" "C0G"
			(at 94.501 417.701 0)
			(layer "B.Fab")
			(hide yes)
			(effects
				(font
					(size 1 1)
					(thickness 0.15)
				)
				(justify mirror)
			)
		)
		(property "License" "Apache-2.0"
			(at 94.501 417.701 0)
			(layer "B.Fab")
			(hide yes)
			(effects
				(font
					(size 1 1)
					(thickness 0.15)
				)
				(justify mirror)
			)
		)
		(property "MPN" "GCM1555C1H100GA16D"
			(at 94.501 417.701 0)
			(layer "B.Fab")
			(hide yes)
			(effects
				(font
					(size 1 1)
					(thickness 0.15)
				)
				(justify mirror)
			)
		)
		(property "Manufacturer" "Murata"
			(at 94.501 417.701 0)
			(layer "B.Fab")
			(hide yes)
			(effects
				(font
					(size 1 1)
					(thickness 0.15)
				)
				(justify mirror)
			)
		)
		(property "Val" "10p"
			(at 94.501 417.701 0)
			(layer "B.Fab")
			(hide yes)
			(effects
				(font
					(size 1 1)
					(thickness 0.15)
				)
				(justify mirror)
			)
		)
		(property "Voltage" "50V"
			(at 94.501 417.701 0)
			(layer "B.Fab")
			(hide yes)
			(effects
				(font
					(size 1 1)
					(thickness 0.15)
				)
				(justify mirror)
			)
		)
		(sheetname "HDMI + Ethernet")
		(sheetfile "hdmi-ethernet.kicad_sch")
		(attr smd)
		(fp_rect
			(start -0.925 0.47)
			(end 0.925 -0.47)
			(stroke
				(width 0.05)
				(type default)
			)
			(fill no)
			(layer "B.CrtYd")
		)
		(fp_line
			(start -0.494 0.25)
			(end 0.504 0.25)
			(stroke
				(width 0.15)
				(type solid)
			)
			(layer "B.Fab")
		)
		(fp_line
			(start 0.504 0.25)
			(end 0.504 -0.248)
			(stroke
				(width 0.15)
				(type solid)
			)
			(layer "B.Fab")
		)
		(fp_line
			(start -0.494 -0.248)
			(end -0.494 0.25)
			(stroke
				(width 0.15)
				(type solid)
			)
			(layer "B.Fab")
		)
		(fp_line
			(start 0.504 -0.248)
			(end -0.494 -0.248)
			(stroke
				(width 0.15)
				(type solid)
			)
			(layer "B.Fab")
		)
		(pad "1" smd roundrect
			(at -0.48 0 270)
			(size 0.59 0.64)
			(layers "B.Cu" "B.Mask" "B.Paste")
			(roundrect_rratio 0.25)
			(net 1 "GND")
			(pintype "passive")
		)
		(pad "2" smd roundrect
			(at 0.48 0 270)
			(size 0.59 0.64)
			(layers "B.Cu" "B.Mask" "B.Paste")
			(roundrect_rratio 0.25)
			(net 724 "/HDMI + Ethernet/ETH1_P")
			(pintype "passive")
		)
	)
	(footprint "antmicro-footprints:R_0402_1005Metric"
		(layer "B.Cu")
		(at 186.800001 79.800001 90)
		(descr "Resistor SMD 0402")
		(tags "resistor SMD 0402")
		(property "Reference" "R143"
			(at -0.725 0.4 270)
			(layer "B.SilkS")
			(effects
				(font
					(size 0.7 0.7)
					(thickness 0.15)
				)
				(justify left bottom mirror)
			)
		)
		(property "Value" "R_100R_0402"
			(at 0 -1.4 270)
			(layer "B.Fab")
			(effects
				(font
					(size 0.7 0.7)
					(thickness 0.15)
				)
				(justify left bottom mirror)
			)
		)
		(property "Description" "SMD Chip Resistor, 100 ohm, ± 1%, 62.5 mW, 0402 [1005 Metric], Thick Film, General Purpose"
			(at 0 0 90)
			(layer "F.Fab")
			(hide yes)
			(effects
				(font
					(size 1.27 1.27)
					(thickness 0.15)
				)
			)
		)
		(property "Author" "Antmicro"
			(at 266.600002 -107 0)
			(layer "B.Fab")
			(hide yes)
			(effects
				(font
					(size 1 1)
					(thickness 0.15)
				)
				(justify mirror)
			)
		)
		(property "License" "Apache-2.0"
			(at 266.600002 -107 0)
			(layer "B.Fab")
			(hide yes)
			(effects
				(font
					(size 1 1)
					(thickness 0.15)
				)
				(justify mirror)
			)
		)
		(property "MPN" "CR0402-FX-1000GLF"
			(at 266.600002 -107 0)
			(layer "B.Fab")
			(hide yes)
			(effects
				(font
					(size 1 1)
					(thickness 0.15)
				)
				(justify mirror)
			)
		)
		(property "Manufacturer" "Bourns"
			(at 266.600002 -107 0)
			(layer "B.Fab")
			(hide yes)
			(effects
				(font
					(size 1 1)
					(thickness 0.15)
				)
				(justify mirror)
			)
		)
		(property "Tolerance" "1%"
			(at 266.600002 -107 0)
			(layer "B.Fab")
			(hide yes)
			(effects
				(font
					(size 1 1)
					(thickness 0.15)
				)
				(justify mirror)
			)
		)
		(property "Val" "100R"
			(at 266.600002 -107 0)
			(layer "B.Fab")
			(hide yes)
			(effects
				(font
					(size 1 1)
					(thickness 0.15)
				)
				(justify mirror)
			)
		)
		(sheetname "User GPIO + LED + button + DIP switch")
		(sheetfile "user-gpio.kicad_sch")
		(attr smd)
		(fp_rect
			(start -0.925 0.47)
			(end 0.925 -0.47)
			(stroke
				(width 0.05)
				(type default)
			)
			(fill no)
			(layer "B.CrtYd")
		)
		(fp_rect
			(start -0.5 0.25)
			(end 0.5 -0.25)
			(stroke
				(width 0.15)
				(type solid)
			)
			(fill no)
			(layer "B.Fab")
		)
		(pad "1" smd roundrect
			(at -0.48 0 90)
			(size 0.59 0.64)
			(layers "B.Cu" "B.Mask" "B.Paste")
			(roundrect_rratio 0.25)
			(net 488 "/FPGA Bank 12 & 13/CW_HEADER.HS2")
			(pintype "passive")
		)
		(pad "2" smd roundrect
			(at 0.48 0 90)
			(size 0.59 0.64)
			(layers "B.Cu" "B.Mask" "B.Paste")
			(roundrect_rratio 0.25)
			(net 824 "/User GPIO + LED + button + DIP switch/CW_20PIN_HS2")
			(pintype "passive")
		)
	)
	(footprint "antmicro-footprints:R_0402_1005Metric"
		(layer "B.Cu")
		(at 195.691252 91.85 180)
		(descr "Resistor SMD 0402")
		(tags "resistor SMD 0402")
		(property "Reference" "R199"
			(at 0.716252 -0.425 0)
			(layer "B.SilkS")
			(effects
				(font
					(size 0.7 0.7)
					(thickness 0.15)
				)
				(justify left bottom mirror)
			)
		)
		(property "Value" "R_10k_0402"
			(at 0 -1.4 0)
			(layer "B.Fab")
			(effects
				(font
					(size 0.7 0.7)
					(thickness 0.15)
				)
				(justify left bottom mirror)
			)
		)
		(property "Description" "SMD Chip Resistor, 10 kohm, ± 1%, 62.5 mW, 0402 [1005 Metric], Thick Film, General Purpose"
			(at 0 0 180)
			(layer "F.Fab")
			(hide yes)
			(effects
				(font
					(size 1.27 1.27)
					(thickness 0.15)
				)
			)
		)
		(property "Author" "Antmicro"
			(at 391.382504 183.7 0)
			(layer "B.Fab")
			(hide yes)
			(effects
				(font
					(size 1 1)
					(thickness 0.15)
				)
				(justify mirror)
			)
		)
		(property "License" "Apache-2.0"
			(at 391.382504 183.7 0)
			(layer "B.Fab")
			(hide yes)
			(effects
				(font
					(size 1 1)
					(thickness 0.15)
				)
				(justify mirror)
			)
		)
		(property "MPN" "CR0402-FX-1002GLF"
			(at 391.382504 183.7 0)
			(layer "B.Fab")
			(hide yes)
			(effects
				(font
					(size 1 1)
					(thickness 0.15)
				)
				(justify mirror)
			)
		)
		(property "Manufacturer" "Bourns"
			(at 391.382504 183.7 0)
			(layer "B.Fab")
			(hide yes)
			(effects
				(font
					(size 1 1)
					(thickness 0.15)
				)
				(justify mirror)
			)
		)
		(property "Tolerance" "1%"
			(at 391.382504 183.7 0)
			(layer "B.Fab")
			(hide yes)
			(effects
				(font
					(size 1 1)
					(thickness 0.15)
				)
				(justify mirror)
			)
		)
		(property "Val" "10k"
			(at 391.382504 183.7 0)
			(layer "B.Fab")
			(hide yes)
			(effects
				(font
					(size 1 1)
					(thickness 0.15)
				)
				(justify mirror)
			)
		)
		(sheetname "HDMI + Ethernet")
		(sheetfile "hdmi-ethernet.kicad_sch")
		(attr smd)
		(fp_rect
			(start -0.925 0.47)
			(end 0.925 -0.47)
			(stroke
				(width 0.05)
				(type default)
			)
			(fill no)
			(layer "B.CrtYd")
		)
		(fp_rect
			(start -0.5 0.25)
			(end 0.5 -0.25)
			(stroke
				(width 0.15)
				(type solid)
			)
			(fill no)
			(layer "B.Fab")
		)
		(pad "1" smd roundrect
			(at -0.48 0 180)
			(size 0.59 0.64)
			(layers "B.Cu" "B.Mask" "B.Paste")
			(roundrect_rratio 0.25)
			(net 503 "/FPGA Bank 16 & 17/GBE_RGMII.RXD3")
			(pintype "passive")
		)
		(pad "2" smd roundrect
			(at 0.48 0 180)
			(size 0.59 0.64)
			(layers "B.Cu" "B.Mask" "B.Paste")
			(roundrect_rratio 0.25)
			(net 24 "+3V3")
			(pintype "passive")
		)
	)
	(footprint "antmicro-footprints:C_0603_1608Metric"
		(layer "B.Cu")
		(at 200 131.325 -90)
		(descr "Capacitor SMD 0603")
		(tags "capacitor 0603")
		(property "Reference" "C384"
			(at -30.7 -25.75 90)
			(layer "B.SilkS")
			(effects
				(font
					(size 0.7 0.7)
					(thickness 0.15)
				)
				(justify left bottom mirror)
			)
		)
		(property "Value" "C_47u_0603"
			(at 0 -1.6 90)
			(layer "B.Fab")
			(effects
				(font
					(size 0.7 0.7)
					(thickness 0.15)
				)
				(justify left bottom mirror)
			)
		)
		(property "Description" "SMD Multilayer Ceramic Capacitor, 47 µF, 6.3 V, 0603 [1608 Metric], ± 20%, X5R, GRM Series"
			(at 0 0 270)
			(layer "F.Fab")
			(hide yes)
			(effects
				(font
					(size 1.27 1.27)
					(thickness 0.15)
				)
			)
		)
		(property "Author" "Antmicro"
			(at 68.675 331.325 0)
			(layer "B.Fab")
			(hide yes)
			(effects
				(font
					(size 1 1)
					(thickness 0.15)
				)
				(justify mirror)
			)
		)
		(property "Dielectric" ""
			(at 68.675 331.325 0)
			(layer "B.Fab")
			(hide yes)
			(effects
				(font
					(size 1 1)
					(thickness 0.15)
				)
				(justify mirror)
			)
		)
		(property "License" "Apache-2.0"
			(at 68.675 331.325 0)
			(layer "B.Fab")
			(hide yes)
			(effects
				(font
					(size 1 1)
					(thickness 0.15)
				)
				(justify mirror)
			)
		)
		(property "MPN" "GRM188R60J476ME15D"
			(at 68.675 331.325 0)
			(layer "B.Fab")
			(hide yes)
			(effects
				(font
					(size 1 1)
					(thickness 0.15)
				)
				(justify mirror)
			)
		)
		(property "Manufacturer" "Murata"
			(at 68.675 331.325 0)
			(layer "B.Fab")
			(hide yes)
			(effects
				(font
					(size 1 1)
					(thickness 0.15)
				)
				(justify mirror)
			)
		)
		(property "Val" "47u"
			(at 68.675 331.325 0)
			(layer "B.Fab")
			(hide yes)
			(effects
				(font
					(size 1 1)
					(thickness 0.15)
				)
				(justify mirror)
			)
		)
		(property "Voltage" ""
			(at 68.675 331.325 0)
			(layer "B.Fab")
			(hide yes)
			(effects
				(font
					(size 1 1)
					(thickness 0.15)
				)
				(justify mirror)
			)
		)
		(sheetname "FPGA supply")
		(sheetfile "fpga-supply.kicad_sch")
		(attr smd)
		(fp_line
			(start -0.15 0.4)
			(end 0.15 0.4)
			(stroke
				(width 0.15)
				(type solid)
			)
			(layer "B.SilkS")
		)
		(fp_line
			(start -0.15 -0.4)
			(end 0.15 -0.4)
			(stroke
				(width 0.15)
				(type solid)
			)
			(layer "B.SilkS")
		)
		(fp_rect
			(start -1.25 0.65)
			(end 1.25 -0.65)
			(stroke
				(width 0.05)
				(type solid)
			)
			(fill no)
			(layer "B.CrtYd")
		)
		(fp_rect
			(start -0.8 0.4)
			(end 0.8 -0.4)
			(stroke
				(width 0.15)
				(type solid)
			)
			(fill no)
			(layer "B.Fab")
		)
		(pad "1" smd roundrect
			(at -0.7 0 270)
			(size 0.8 1)
			(layers "B.Cu" "B.Mask" "B.Paste")
			(roundrect_rratio 0.2)
			(net 1 "GND")
			(pintype "passive")
		)
		(pad "2" smd roundrect
			(at 0.7 0 270)
			(size 0.8 1)
			(layers "B.Cu" "B.Mask" "B.Paste")
			(roundrect_rratio 0.2)
			(net 650 "+1V0")
			(pintype "passive")
		)
	)
	(footprint "antmicro-footprints:C_0201"
		(layer "B.Cu")
		(at 203.45 131.6 -90)
		(descr "Capacitor SMD 0201")
		(tags "capacitor SMD 0201")
		(property "Reference" "C22"
			(at -29.575 -28.2 90)
			(layer "B.SilkS")
			(effects
				(font
					(size 0.7 0.7)
					(thickness 0.15)
				)
				(justify left bottom mirror)
			)
		)
		(property "Value" "C_4u7_0201"
			(at 0 -1.4 90)
			(layer "B.Fab")
			(effects
				(font
					(size 0.7 0.7)
					(thickness 0.15)
				)
				(justify left bottom mirror)
			)
		)
		(property "Description" "SMD Multilayer Ceramic Capacitor, 4.7 µF, 6.3 V, 0201 [0603 Metric], ± 20%, X5R, GRM Series"
			(at 0 0 270)
			(layer "F.Fab")
			(hide yes)
			(effects
				(font
					(size 1.27 1.27)
					(thickness 0.15)
				)
			)
		)
		(property "Author" "Antmicro"
			(at 71.85 335.05 0)
			(layer "B.Fab")
			(hide yes)
			(effects
				(font
					(size 1 1)
					(thickness 0.15)
				)
				(justify mirror)
			)
		)
		(property "Dielectric" ""
			(at 71.85 335.05 0)
			(layer "B.Fab")
			(hide yes)
			(effects
				(font
					(size 1 1)
					(thickness 0.15)
				)
				(justify mirror)
			)
		)
		(property "License" "Apache-2.0"
			(at 71.85 335.05 0)
			(layer "B.Fab")
			(hide yes)
			(effects
				(font
					(size 1 1)
					(thickness 0.15)
				)
				(justify mirror)
			)
		)
		(property "MPN" "GRM035R60J475ME15D"
			(at 71.85 335.05 0)
			(layer "B.Fab")
			(hide yes)
			(effects
				(font
					(size 1 1)
					(thickness 0.15)
				)
				(justify mirror)
			)
		)
		(property "Manufacturer" "Murata"
			(at 71.85 335.05 0)
			(layer "B.Fab")
			(hide yes)
			(effects
				(font
					(size 1 1)
					(thickness 0.15)
				)
				(justify mirror)
			)
		)
		(property "Val" "4u7"
			(at 71.85 335.05 0)
			(layer "B.Fab")
			(hide yes)
			(effects
				(font
					(size 1 1)
					(thickness 0.15)
				)
				(justify mirror)
			)
		)
		(property "Voltage" ""
			(at 71.85 335.05 0)
			(layer "B.Fab")
			(hide yes)
			(effects
				(font
					(size 1 1)
					(thickness 0.15)
				)
				(justify mirror)
			)
		)
		(sheetname "FPGA supply")
		(sheetfile "fpga-supply.kicad_sch")
		(attr smd)
		(fp_rect
			(start -0.7 0.35)
			(end 0.7 -0.35)
			(stroke
				(width 0.05)
				(type default)
			)
			(fill no)
			(layer "B.CrtYd")
		)
		(fp_rect
			(start 0.3 -0.15)
			(end -0.301 0.149)
			(stroke
				(width 0.15)
				(type solid)
			)
			(fill no)
			(layer "B.Fab")
		)
		(pad "" smd roundrect
			(at -0.349 0.002 270)
			(size 0.318 0.36)
			(layers "B.Paste")
			(roundrect_rratio 0.25)
		)
		(pad "" smd roundrect
			(at 0.341 0.002 270)
			(size 0.318 0.36)
			(layers "B.Paste")
			(roundrect_rratio 0.25)
		)
		(pad "1" smd roundrect
			(at -0.321 0.002 270)
			(size 0.46 0.4)
			(layers "B.Cu" "B.Mask")
			(roundrect_rratio 0.25)
			(net 1 "GND")
			(pintype "passive")
		)
		(pad "2" smd roundrect
			(at 0.32 0.002 270)
			(size 0.46 0.4)
			(layers "B.Cu" "B.Mask")
			(roundrect_rratio 0.25)
			(net 650 "+1V0")
			(pintype "passive")
		)
	)
	(footprint "antmicro-footprints:R_0402_1005Metric"
		(layer "B.Cu")
		(at 258.4 83.8 -90)
		(descr "Resistor SMD 0402")
		(tags "resistor SMD 0402")
		(property "Reference" "R353"
			(at -1.375 -1.25 90)
			(layer "B.SilkS")
			(effects
				(font
					(size 0.7 0.7)
					(thickness 0.15)
				)
				(justify left bottom mirror)
			)
		)
		(property "Value" "R_100k_0402"
			(at 0 -1.4 90)
			(layer "B.Fab")
			(effects
				(font
					(size 0.7 0.7)
					(thickness 0.15)
				)
				(justify left bottom mirror)
			)
		)
		(property "Description" "SMD Chip Resistor, 100 kohm, ± 1%, 62.5 mW, 0402 [1005 Metric], Thick Film, General Purpose"
			(at 0 0 270)
			(layer "F.Fab")
			(hide yes)
			(effects
				(font
					(size 1.27 1.27)
					(thickness 0.15)
				)
			)
		)
		(property "Author" "Antmicro"
			(at 174.6 342.2 0)
			(layer "B.Fab")
			(hide yes)
			(effects
				(font
					(size 1 1)
					(thickness 0.15)
				)
				(justify mirror)
			)
		)
		(property "License" "Apache-2.0"
			(at 174.6 342.2 0)
			(layer "B.Fab")
			(hide yes)
			(effects
				(font
					(size 1 1)
					(thickness 0.15)
				)
				(justify mirror)
			)
		)
		(property "MPN" "CR0402-FX-1003GLF"
			(at 174.6 342.2 0)
			(layer "B.Fab")
			(hide yes)
			(effects
				(font
					(size 1 1)
					(thickness 0.15)
				)
				(justify mirror)
			)
		)
		(property "Manufacturer" "Bourns"
			(at 174.6 342.2 0)
			(layer "B.Fab")
			(hide yes)
			(effects
				(font
					(size 1 1)
					(thickness 0.15)
				)
				(justify mirror)
			)
		)
		(property "Tolerance" "1%"
			(at 174.6 342.2 0)
			(layer "B.Fab")
			(hide yes)
			(effects
				(font
					(size 1 1)
					(thickness 0.15)
				)
				(justify mirror)
			)
		)
		(property "Val" "100k"
			(at 174.6 342.2 0)
			(layer "B.Fab")
			(hide yes)
			(effects
				(font
					(size 1 1)
					(thickness 0.15)
				)
				(justify mirror)
			)
		)
		(sheetname "User GPIO + LED + button + DIP switch")
		(sheetfile "user-gpio.kicad_sch")
		(attr smd)
		(fp_rect
			(start -0.925 0.47)
			(end 0.925 -0.47)
			(stroke
				(width 0.05)
				(type default)
			)
			(fill no)
			(layer "B.CrtYd")
		)
		(fp_rect
			(start -0.5 0.25)
			(end 0.5 -0.25)
			(stroke
				(width 0.15)
				(type solid)
			)
			(fill no)
			(layer "B.Fab")
		)
		(pad "1" smd roundrect
			(at -0.48 0 270)
			(size 0.59 0.64)
			(layers "B.Cu" "B.Mask" "B.Paste")
			(roundrect_rratio 0.25)
			(net 1299 "/USER_IO.LED_GREEN0")
			(pintype "passive")
		)
		(pad "2" smd roundrect
			(at 0.48 0 270)
			(size 0.59 0.64)
			(layers "B.Cu" "B.Mask" "B.Paste")
			(roundrect_rratio 0.25)
			(net 1 "GND")
			(pintype "passive")
		)
	)
	(footprint "antmicro-footprints:R_0402_1005Metric"
		(layer "B.Cu")
		(at 268.001 126.7)
		(descr "Resistor SMD 0402")
		(tags "resistor SMD 0402")
		(property "Reference" "R253"
			(at 1.724 -0.55 180)
			(layer "B.SilkS")
			(effects
				(font
					(size 0.7 0.7)
					(thickness 0.15)
				)
				(justify left bottom mirror)
			)
		)
		(property "Value" "R_100R_0402"
			(at 0 -1.4 180)
			(layer "B.Fab")
			(effects
				(font
					(size 0.7 0.7)
					(thickness 0.15)
				)
				(justify left bottom mirror)
			)
		)
		(property "Description" "SMD Chip Resistor, 100 ohm, ± 1%, 62.5 mW, 0402 [1005 Metric], Thick Film, General Purpose"
			(at 0 0 0)
			(layer "F.Fab")
			(hide yes)
			(effects
				(font
					(size 1.27 1.27)
					(thickness 0.15)
				)
			)
		)
		(property "Author" "Antmicro"
			(at 0 0 0)
			(layer "B.Fab")
			(hide yes)
			(effects
				(font
					(size 1 1)
					(thickness 0.15)
				)
				(justify mirror)
			)
		)
		(property "License" "Apache-2.0"
			(at 0 0 0)
			(layer "B.Fab")
			(hide yes)
			(effects
				(font
					(size 1 1)
					(thickness 0.15)
				)
				(justify mirror)
			)
		)
		(property "MPN" "CR0402-FX-1000GLF"
			(at 0 0 0)
			(layer "B.Fab")
			(hide yes)
			(effects
				(font
					(size 1 1)
					(thickness 0.15)
				)
				(justify mirror)
			)
		)
		(property "Manufacturer" "Bourns"
			(at 0 0 0)
			(layer "B.Fab")
			(hide yes)
			(effects
				(font
					(size 1 1)
					(thickness 0.15)
				)
				(justify mirror)
			)
		)
		(property "Tolerance" "1%"
			(at 0 0 0)
			(layer "B.Fab")
			(hide yes)
			(effects
				(font
					(size 1 1)
					(thickness 0.15)
				)
				(justify mirror)
			)
		)
		(property "Val" "100R"
			(at 0 0 0)
			(layer "B.Fab")
			(hide yes)
			(effects
				(font
					(size 1 1)
					(thickness 0.15)
				)
				(justify mirror)
			)
		)
		(sheetname "SPI Flash + SD Card")
		(sheetfile "spi-flash.kicad_sch")
		(attr smd)
		(fp_rect
			(start -0.925 0.47)
			(end 0.925 -0.47)
			(stroke
				(width 0.05)
				(type default)
			)
			(fill no)
			(layer "B.CrtYd")
		)
		(fp_rect
			(start -0.5 0.25)
			(end 0.5 -0.25)
			(stroke
				(width 0.15)
				(type solid)
			)
			(fill no)
			(layer "B.Fab")
		)
		(pad "1" smd roundrect
			(at -0.48 0)
			(size 0.59 0.64)
			(layers "B.Cu" "B.Mask" "B.Paste")
			(roundrect_rratio 0.25)
			(net 1 "GND")
			(pintype "passive")
		)
		(pad "2" smd roundrect
			(at 0.48 0)
			(size 0.59 0.64)
			(layers "B.Cu" "B.Mask" "B.Paste")
			(roundrect_rratio 0.25)
			(net 16 "Net-(J23-SHIELD)")
			(pintype "passive")
		)
	)
	(footprint "antmicro-footprints:C_0402_1005Metric"
		(layer "B.Cu")
		(at 174.5 173.7625 -90)
		(descr "Capacitor SMD 0402")
		(tags "capacitor SMD 0402")
		(property "Reference" "C318"
			(at -1.4375 -1.25 90)
			(layer "B.SilkS")
			(effects
				(font
					(size 0.7 0.7)
					(thickness 0.15)
				)
				(justify left bottom mirror)
			)
		)
		(property "Value" "C_1u_0402"
			(at 0 -1.4 90)
			(layer "B.Fab")
			(effects
				(font
					(size 0.7 0.7)
					(thickness 0.15)
				)
				(justify left bottom mirror)
			)
		)
		(property "Description" "SMD Multilayer Ceramic Capacitor, 1 µF, 10 V, 0402 [1005 Metric], ± 10%, X6S, C"
			(at 0 0 270)
			(layer "F.Fab")
			(hide yes)
			(effects
				(font
					(size 1.27 1.27)
					(thickness 0.15)
				)
			)
		)
		(property "Author" "Antmicro"
			(at 0.7375 348.2625 0)
			(layer "B.Fab")
			(hide yes)
			(effects
				(font
					(size 1 1)
					(thickness 0.15)
				)
				(justify mirror)
			)
		)
		(property "Dielectric" ""
			(at 0.7375 348.2625 0)
			(layer "B.Fab")
			(hide yes)
			(effects
				(font
					(size 1 1)
					(thickness 0.15)
				)
				(justify mirror)
			)
		)
		(property "License" "Apache-2.0"
			(at 0.7375 348.2625 0)
			(layer "B.Fab")
			(hide yes)
			(effects
				(font
					(size 1 1)
					(thickness 0.15)
				)
				(justify mirror)
			)
		)
		(property "MPN" "C1005X6S1A105K050BC"
			(at 0.7375 348.2625 0)
			(layer "B.Fab")
			(hide yes)
			(effects
				(font
					(size 1 1)
					(thickness 0.15)
				)
				(justify mirror)
			)
		)
		(property "Manufacturer" "TDK"
			(at 0.7375 348.2625 0)
			(layer "B.Fab")
			(hide yes)
			(effects
				(font
					(size 1 1)
					(thickness 0.15)
				)
				(justify mirror)
			)
		)
		(property "Val" "1u"
			(at 0.7375 348.2625 0)
			(layer "B.Fab")
			(hide yes)
			(effects
				(font
					(size 1 1)
					(thickness 0.15)
				)
				(justify mirror)
			)
		)
		(property "Voltage" ""
			(at 0.7375 348.2625 0)
			(layer "B.Fab")
			(hide yes)
			(effects
				(font
					(size 1 1)
					(thickness 0.15)
				)
				(justify mirror)
			)
		)
		(sheetname "DC-DC Converters")
		(sheetfile "dc-dc.kicad_sch")
		(attr smd)
		(fp_rect
			(start -0.925 0.47)
			(end 0.925 -0.47)
			(stroke
				(width 0.05)
				(type default)
			)
			(fill no)
			(layer "B.CrtYd")
		)
		(fp_line
			(start -0.494 0.25)
			(end 0.504 0.25)
			(stroke
				(width 0.15)
				(type solid)
			)
			(layer "B.Fab")
		)
		(fp_line
			(start 0.504 0.25)
			(end 0.504 -0.248)
			(stroke
				(width 0.15)
				(type solid)
			)
			(layer "B.Fab")
		)
		(fp_line
			(start -0.494 -0.248)
			(end -0.494 0.25)
			(stroke
				(width 0.15)
				(type solid)
			)
			(layer "B.Fab")
		)
		(fp_line
			(start 0.504 -0.248)
			(end -0.494 -0.248)
			(stroke
				(width 0.15)
				(type solid)
			)
			(layer "B.Fab")
		)
		(pad "1" smd roundrect
			(at -0.48 0 270)
			(size 0.59 0.64)
			(layers "B.Cu" "B.Mask" "B.Paste")
			(roundrect_rratio 0.25)
			(net 1 "GND")
			(pintype "passive")
		)
		(pad "2" smd roundrect
			(at 0.48 0 270)
			(size 0.59 0.64)
			(layers "B.Cu" "B.Mask" "B.Paste")
			(roundrect_rratio 0.25)
			(net 732 "/DC-DC Converters/QDCDC2_VCC")
			(pintype "passive")
		)
	)
	(footprint "antmicro-footprints:C_0402_1005Metric"
		(layer "B.Cu")
		(at 169.5 143.2 90)
		(descr "Capacitor SMD 0402")
		(tags "capacitor SMD 0402")
		(property "Reference" "C392"
			(at 1.075 2.35 270)
			(layer "B.SilkS")
			(effects
				(font
					(size 0.7 0.7)
					(thickness 0.15)
				)
				(justify left bottom mirror)
			)
		)
		(property "Value" "C_100n_0402"
			(at 0 -1.169 270)
			(layer "B.Fab")
			(effects
				(font
					(size 0.7 0.7)
					(thickness 0.15)
				)
				(justify left bottom mirror)
			)
		)
		(property "Description" "SMD Multilayer Ceramic Capacitor, 0.1 µF, 50 V, 0402 [1005 Metric], ± 10%, X5R, GRM Series"
			(at 0 0 90)
			(layer "F.Fab")
			(hide yes)
			(effects
				(font
					(size 1.27 1.27)
					(thickness 0.15)
				)
			)
		)
		(property "Author" "Antmicro"
			(at 312.7 -26.3 0)
			(layer "B.Fab")
			(hide yes)
			(effects
				(font
					(size 1 1)
					(thickness 0.15)
				)
				(justify mirror)
			)
		)
		(property "Dielectric" "X5R"
			(at 312.7 -26.3 0)
			(layer "B.Fab")
			(hide yes)
			(effects
				(font
					(size 1 1)
					(thickness 0.15)
				)
				(justify mirror)
			)
		)
		(property "License" "Apache-2.0"
			(at 312.7 -26.3 0)
			(layer "B.Fab")
			(hide yes)
			(effects
				(font
					(size 1 1)
					(thickness 0.15)
				)
				(justify mirror)
			)
		)
		(property "MPN" "GRM155R61H104KE14D"
			(at 312.7 -26.3 0)
			(layer "B.Fab")
			(hide yes)
			(effects
				(font
					(size 1 1)
					(thickness 0.15)
				)
				(justify mirror)
			)
		)
		(property "Manufacturer" "Murata"
			(at 312.7 -26.3 0)
			(layer "B.Fab")
			(hide yes)
			(effects
				(font
					(size 1 1)
					(thickness 0.15)
				)
				(justify mirror)
			)
		)
		(property "Val" "100n"
			(at 312.7 -26.3 0)
			(layer "B.Fab")
			(hide yes)
			(effects
				(font
					(size 1 1)
					(thickness 0.15)
				)
				(justify mirror)
			)
		)
		(property "Voltage" "50V"
			(at 312.7 -26.3 0)
			(layer "B.Fab")
			(hide yes)
			(effects
				(font
					(size 1 1)
					(thickness 0.15)
				)
				(justify mirror)
			)
		)
		(sheetname "DRAM + SRAM")
		(sheetfile "ram.kicad_sch")
		(attr smd)
		(fp_rect
			(start -0.925 0.47)
			(end 0.925 -0.47)
			(stroke
				(width 0.05)
				(type default)
			)
			(fill no)
			(layer "B.CrtYd")
		)
		(fp_line
			(start 0.504 -0.248)
			(end -0.494 -0.248)
			(stroke
				(width 0.15)
				(type solid)
			)
			(layer "B.Fab")
		)
		(fp_line
			(start -0.494 -0.248)
			(end -0.494 0.25)
			(stroke
				(width 0.15)
				(type solid)
			)
			(layer "B.Fab")
		)
		(fp_line
			(start 0.504 0.25)
			(end 0.504 -0.248)
			(stroke
				(width 0.15)
				(type solid)
			)
			(layer "B.Fab")
		)
		(fp_line
			(start -0.494 0.25)
			(end 0.504 0.25)
			(stroke
				(width 0.15)
				(type solid)
			)
			(layer "B.Fab")
		)
		(pad "1" smd roundrect
			(at -0.48 0 90)
			(size 0.59 0.64)
			(layers "B.Cu" "B.Mask" "B.Paste")
			(roundrect_rratio 0.25)
			(net 1 "GND")
			(pintype "passive")
		)
		(pad "2" smd roundrect
			(at 0.48 0 90)
			(size 0.59 0.64)
			(layers "B.Cu" "B.Mask" "B.Paste")
			(roundrect_rratio 0.25)
			(net 25 "+1V35")
			(pintype "passive")
		)
	)
	(footprint "antmicro-footprints:USON-10_2.5x1mm_P0.5mm"
		(layer "B.Cu")
		(at 253.751 110.3 90)
		(descr "USON-10 2.5x1mm_ Pitch 0.5mm")
		(tags "USON-10 2.5x1mm Pitch 0.5mm")
		(property "Reference" "U29"
			(at 0.8 1.074 0)
			(layer "B.SilkS")
			(effects
				(font
					(size 0.7 0.7)
					(thickness 0.15)
				)
				(justify left bottom mirror)
			)
		)
		(property "Value" "TPD4E05U06QDQARQ1"
			(at 0.018 -2.499 270)
			(layer "B.Fab")
			(effects
				(font
					(size 0.7 0.7)
					(thickness 0.15)
				)
				(justify left bottom mirror)
			)
		)
		(property "Description" "ESD protection"
			(at 0 0 90)
			(layer "F.Fab")
			(hide yes)
			(effects
				(font
					(size 1.27 1.27)
					(thickness 0.15)
				)
			)
		)
		(property "Author" "Antmicro"
			(at 364.051 -143.451 0)
			(layer "B.Fab")
			(hide yes)
			(effects
				(font
					(size 1 1)
					(thickness 0.15)
				)
				(justify mirror)
			)
		)
		(property "License" "Apache-2.0"
			(at 364.051 -143.451 0)
			(layer "B.Fab")
			(hide yes)
			(effects
				(font
					(size 1 1)
					(thickness 0.15)
				)
				(justify mirror)
			)
		)
		(property "MPN" "TPD4E05U06QDQARQ1"
			(at 364.051 -143.451 0)
			(layer "B.Fab")
			(hide yes)
			(effects
				(font
					(size 1 1)
					(thickness 0.15)
				)
				(justify mirror)
			)
		)
		(property "Manufacturer" "Texas Instruments"
			(at 364.051 -143.451 0)
			(layer "B.Fab")
			(hide yes)
			(effects
				(font
					(size 1 1)
					(thickness 0.15)
				)
				(justify mirror)
			)
		)
		(sheetname "HDMI + Ethernet")
		(sheetfile "hdmi-ethernet.kicad_sch")
		(attr smd)
		(fp_line
			(start 0.498 -1.398)
			(end -0.5 -1.398)
			(stroke
				(width 0.15)
				(type solid)
			)
			(layer "B.SilkS")
		)
		(fp_line
			(start 0.498 1.401)
			(end -0.5 1.401)
			(stroke
				(width 0.15)
				(type solid)
			)
			(layer "B.SilkS")
		)
		(fp_circle
			(center -0.68 1.27)
			(end -0.63 1.27)
			(stroke
				(width 0.15)
				(type solid)
			)
			(fill yes)
			(layer "B.SilkS")
		)
		(fp_rect
			(start -0.8 1.5)
			(end 0.8 -1.499)
			(stroke
				(width 0.05)
				(type solid)
			)
			(fill no)
			(layer "B.CrtYd")
		)
		(fp_line
			(start -0.5 -1.249)
			(end 0.498 -1.249)
			(stroke
				(width 0.15)
				(type solid)
			)
			(layer "B.Fab")
		)
		(fp_line
			(start -0.5 1)
			(end -0.5 -1.249)
			(stroke
				(width 0.15)
				(type solid)
			)
			(layer "B.Fab")
		)
		(fp_line
			(start 0.498 1.25)
			(end 0.498 -1.249)
			(stroke
				(width 0.15)
				(type solid)
			)
			(layer "B.Fab")
		)
		(fp_line
			(start 0.498 1.25)
			(end -0.25 1.25)
			(stroke
				(width 0.15)
				(type solid)
			)
			(layer "B.Fab")
		)
		(fp_line
			(start -0.25 1.25)
			(end -0.5 1)
			(stroke
				(width 0.15)
				(type solid)
			)
			(layer "B.Fab")
		)
		(pad "1" smd roundrect
			(at -0.387 1 180)
			(size 0.25 0.55)
			(layers "B.Cu" "B.Mask" "B.Paste")
			(roundrect_rratio 0.25)
			(net 863 "/HDMI + Ethernet/HDMI_CONN_D0_P")
			(pintype "passive")
		)
		(pad "2" smd roundrect
			(at -0.387 0.5 180)
			(size 0.25 0.55)
			(layers "B.Cu" "B.Mask" "B.Paste")
			(roundrect_rratio 0.25)
			(net 862 "/HDMI + Ethernet/HDMI_CONN_D0_N")
			(pintype "passive")
		)
		(pad "3" smd roundrect
			(at -0.387 0 180)
			(size 0.4 0.55)
			(layers "B.Cu" "B.Mask" "B.Paste")
			(roundrect_rratio 0.25)
			(net 1 "GND")
			(pintype "power_in")
		)
		(pad "4" smd roundrect
			(at -0.387 -0.498 180)
			(size 0.25 0.55)
			(layers "B.Cu" "B.Mask" "B.Paste")
			(roundrect_rratio 0.25)
			(net 861 "/HDMI + Ethernet/HDMI_CONN_CLK_P")
			(pintype "passive")
		)
		(pad "5" smd roundrect
			(at -0.387 -0.998 180)
			(size 0.25 0.55)
			(layers "B.Cu" "B.Mask" "B.Paste")
			(roundrect_rratio 0.25)
			(net 868 "/HDMI + Ethernet/HDMI_CONN_CLK_N")
			(pintype "passive")
		)
		(pad "6" smd roundrect
			(at 0.385 -0.998 180)
			(size 0.25 0.55)
			(layers "B.Cu" "B.Mask" "B.Paste")
			(roundrect_rratio 0.25)
			(net 868 "/HDMI + Ethernet/HDMI_CONN_CLK_N")
			(pintype "passive")
		)
		(pad "7" smd roundrect
			(at 0.385 -0.498 180)
			(size 0.25 0.55)
			(layers "B.Cu" "B.Mask" "B.Paste")
			(roundrect_rratio 0.25)
			(net 861 "/HDMI + Ethernet/HDMI_CONN_CLK_P")
			(pintype "passive")
		)
		(pad "8" smd roundrect
			(at 0.385 0 180)
			(size 0.4 0.55)
			(layers "B.Cu" "B.Mask" "B.Paste")
			(roundrect_rratio 0.25)
			(net 1 "GND")
			(pintype "passive")
		)
		(pad "9" smd roundrect
			(at 0.385 0.5 180)
			(size 0.25 0.55)
			(layers "B.Cu" "B.Mask" "B.Paste")
			(roundrect_rratio 0.25)
			(net 862 "/HDMI + Ethernet/HDMI_CONN_D0_N")
			(pintype "passive")
		)
		(pad "10" smd roundrect
			(at 0.385 1 180)
			(size 0.25 0.55)
			(layers "B.Cu" "B.Mask" "B.Paste")
			(roundrect_rratio 0.25)
			(net 863 "/HDMI + Ethernet/HDMI_CONN_D0_P")
			(pintype "passive")
		)
	)
	(footprint "antmicro-footprints:C_0201"
		(layer "B.Cu")
		(at 189.8 119.5 180)
		(descr "Capacitor SMD 0201")
		(tags "capacitor SMD 0201")
		(property "Reference" "C149"
			(at 0.55 -0.25 0)
			(layer "B.SilkS")
			(effects
				(font
					(size 0.7 0.7)
					(thickness 0.15)
				)
				(justify left bottom mirror)
			)
		)
		(property "Value" "C_100n_0201"
			(at 0 -1.4 0)
			(layer "B.Fab")
			(effects
				(font
					(size 0.7 0.7)
					(thickness 0.15)
				)
				(justify left bottom mirror)
			)
		)
		(property "Description" "SMD Multilayer Ceramic Capacitor, 0.1 µF, 6.3 V, 0201 [0603 Metric], ± 10%, X6S, CC Series"
			(at 0 0 180)
			(layer "F.Fab")
			(hide yes)
			(effects
				(font
					(size 1.27 1.27)
					(thickness 0.15)
				)
			)
		)
		(property "Author" "Antmicro"
			(at 379.6 239 0)
			(layer "B.Fab")
			(hide yes)
			(effects
				(font
					(size 1 1)
					(thickness 0.15)
				)
				(justify mirror)
			)
		)
		(property "Dielectric" ""
			(at 379.6 239 0)
			(layer "B.Fab")
			(hide yes)
			(effects
				(font
					(size 1 1)
					(thickness 0.15)
				)
				(justify mirror)
			)
		)
		(property "License" "Apache-2.0"
			(at 379.6 239 0)
			(layer "B.Fab")
			(hide yes)
			(effects
				(font
					(size 1 1)
					(thickness 0.15)
				)
				(justify mirror)
			)
		)
		(property "MPN" "CC0201KRX6S5BB104"
			(at 379.6 239 0)
			(layer "B.Fab")
			(hide yes)
			(effects
				(font
					(size 1 1)
					(thickness 0.15)
				)
				(justify mirror)
			)
		)
		(property "Manufacturer" "YAGEO"
			(at 379.6 239 0)
			(layer "B.Fab")
			(hide yes)
			(effects
				(font
					(size 1 1)
					(thickness 0.15)
				)
				(justify mirror)
			)
		)
		(property "Val" "100n"
			(at 379.6 239 0)
			(layer "B.Fab")
			(hide yes)
			(effects
				(font
					(size 1 1)
					(thickness 0.15)
				)
				(justify mirror)
			)
		)
		(property "Voltage" ""
			(at 379.6 239 0)
			(layer "B.Fab")
			(hide yes)
			(effects
				(font
					(size 1 1)
					(thickness 0.15)
				)
				(justify mirror)
			)
		)
		(sheetname "FPGA supply")
		(sheetfile "fpga-supply.kicad_sch")
		(attr smd)
		(fp_rect
			(start -0.7 0.35)
			(end 0.7 -0.35)
			(stroke
				(width 0.05)
				(type default)
			)
			(fill no)
			(layer "B.CrtYd")
		)
		(fp_rect
			(start 0.3 -0.15)
			(end -0.301 0.149)
			(stroke
				(width 0.15)
				(type solid)
			)
			(fill no)
			(layer "B.Fab")
		)
		(pad "" smd roundrect
			(at -0.349 0.002 180)
			(size 0.318 0.36)
			(layers "B.Paste")
			(roundrect_rratio 0.25)
		)
		(pad "" smd roundrect
			(at 0.341 0.002 180)
			(size 0.318 0.36)
			(layers "B.Paste")
			(roundrect_rratio 0.25)
		)
		(pad "1" smd roundrect
			(at -0.321 0.002 180)
			(size 0.46 0.4)
			(layers "B.Cu" "B.Mask")
			(roundrect_rratio 0.25)
			(net 1 "GND")
			(pintype "passive")
		)
		(pad "2" smd roundrect
			(at 0.32 0.002 180)
			(size 0.46 0.4)
			(layers "B.Cu" "B.Mask")
			(roundrect_rratio 0.25)
			(net 8 "+1V2_MGTAVTT")
			(pintype "passive")
		)
	)
	(footprint "antmicro-footprints:C_0402_1005Metric"
		(layer "B.Cu")
		(at 258.201 166.8 90)
		(descr "Capacitor SMD 0402")
		(tags "capacitor SMD 0402")
		(property "Reference" "C275"
			(at 0.375 1.049 225)
			(layer "B.SilkS")
			(effects
				(font
					(size 0.7 0.7)
					(thickness 0.15)
				)
				(justify right bottom mirror)
			)
		)
		(property "Value" "C_10p_0402"
			(at 0 -1.4 90)
			(layer "B.Fab")
			(effects
				(font
					(size 0.7 0.7)
					(thickness 0.15)
				)
				(justify right bottom mirror)
			)
		)
		(property "Description" "SMD Multilayer Ceramic Capacitor, 10 pF, 50 V, 0402 [1005 Metric], ± 2%, C0G / NP0, GCM"
			(at 0 0 90)
			(layer "F.Fab")
			(hide yes)
			(effects
				(font
					(size 1.27 1.27)
					(thickness 0.15)
				)
			)
		)
		(property "Author" "Antmicro"
			(at 425.001 -91.401 0)
			(layer "B.Fab")
			(hide yes)
			(effects
				(font
					(size 1 1)
					(thickness 0.15)
				)
				(justify mirror)
			)
		)
		(property "Dielectric" "C0G"
			(at 425.001 -91.401 0)
			(layer "B.Fab")
			(hide yes)
			(effects
				(font
					(size 1 1)
					(thickness 0.15)
				)
				(justify mirror)
			)
		)
		(property "License" "Apache-2.0"
			(at 425.001 -91.401 0)
			(layer "B.Fab")
			(hide yes)
			(effects
				(font
					(size 1 1)
					(thickness 0.15)
				)
				(justify mirror)
			)
		)
		(property "MPN" "GCM1555C1H100GA16D"
			(at 425.001 -91.401 0)
			(layer "B.Fab")
			(hide yes)
			(effects
				(font
					(size 1 1)
					(thickness 0.15)
				)
				(justify mirror)
			)
		)
		(property "Manufacturer" "Murata"
			(at 425.001 -91.401 0)
			(layer "B.Fab")
			(hide yes)
			(effects
				(font
					(size 1 1)
					(thickness 0.15)
				)
				(justify mirror)
			)
		)
		(property "Val" "10p"
			(at 425.001 -91.401 0)
			(layer "B.Fab")
			(hide yes)
			(effects
				(font
					(size 1 1)
					(thickness 0.15)
				)
				(justify mirror)
			)
		)
		(property "Voltage" "50V"
			(at 425.001 -91.401 0)
			(layer "B.Fab")
			(hide yes)
			(effects
				(font
					(size 1 1)
					(thickness 0.15)
				)
				(justify mirror)
			)
		)
		(sheetname "HDMI + Ethernet")
		(sheetfile "hdmi-ethernet.kicad_sch")
		(attr smd)
		(fp_rect
			(start -0.925 0.47)
			(end 0.925 -0.47)
			(stroke
				(width 0.05)
				(type default)
			)
			(fill no)
			(layer "B.CrtYd")
		)
		(fp_line
			(start 0.504 -0.248)
			(end -0.494 -0.248)
			(stroke
				(width 0.15)
				(type solid)
			)
			(layer "B.Fab")
		)
		(fp_line
			(start -0.494 -0.248)
			(end -0.494 0.25)
			(stroke
				(width 0.15)
				(type solid)
			)
			(layer "B.Fab")
		)
		(fp_line
			(start 0.504 0.25)
			(end 0.504 -0.248)
			(stroke
				(width 0.15)
				(type solid)
			)
			(layer "B.Fab")
		)
		(fp_line
			(start -0.494 0.25)
			(end 0.504 0.25)
			(stroke
				(width 0.15)
				(type solid)
			)
			(layer "B.Fab")
		)
		(pad "1" smd roundrect
			(at -0.48 0 90)
			(size 0.59 0.64)
			(layers "B.Cu" "B.Mask" "B.Paste")
			(roundrect_rratio 0.25)
			(net 1 "GND")
			(pintype "passive")
		)
		(pad "2" smd roundrect
			(at 0.48 0 90)
			(size 0.59 0.64)
			(layers "B.Cu" "B.Mask" "B.Paste")
			(roundrect_rratio 0.25)
			(net 725 "/HDMI + Ethernet/ETH1_N")
			(pintype "passive")
		)
	)
	(footprint "antmicro-footprints:C_0402_1005Metric"
		(layer "B.Cu")
		(at 216.09 128.51 135)
		(descr "Capacitor SMD 0402")
		(tags "capacitor SMD 0402")
		(property "Reference" "C42"
			(at -1.078338 -1.240972 315)
			(unlocked yes)
			(layer "B.SilkS")
			(effects
				(font
					(size 0.7 0.7)
					(thickness 0.15)
				)
				(justify left bottom mirror)
			)
		)
		(property "Value" "C_100n_0402"
			(at 0 -1.169 315)
			(layer "B.Fab")
			(effects
				(font
					(size 0.7 0.7)
					(thickness 0.15)
				)
				(justify left bottom mirror)
			)
		)
		(property "Description" "SMD Multilayer Ceramic Capacitor, 0.1 µF, 50 V, 0402 [1005 Metric], ± 10%, X5R, GRM Series"
			(at 0 0 135)
			(layer "F.Fab")
			(hide yes)
			(effects
				(font
					(size 1.27 1.27)
					(thickness 0.15)
				)
			)
		)
		(property "Author" "Antmicro"
			(at 459.758997 66.581588 0)
			(layer "B.Fab")
			(hide yes)
			(effects
				(font
					(size 1 1)
					(thickness 0.15)
				)
				(justify mirror)
			)
		)
		(property "Dielectric" "X5R"
			(at 459.758997 66.581588 0)
			(layer "B.Fab")
			(hide yes)
			(effects
				(font
					(size 1 1)
					(thickness 0.15)
				)
				(justify mirror)
			)
		)
		(property "License" "Apache-2.0"
			(at 459.758997 66.581588 0)
			(layer "B.Fab")
			(hide yes)
			(effects
				(font
					(size 1 1)
					(thickness 0.15)
				)
				(justify mirror)
			)
		)
		(property "MPN" "GRM155R61H104KE14D"
			(at 459.758997 66.581588 0)
			(layer "B.Fab")
			(hide yes)
			(effects
				(font
					(size 1 1)
					(thickness 0.15)
				)
				(justify mirror)
			)
		)
		(property "Manufacturer" "Murata"
			(at 459.758997 66.581588 0)
			(layer "B.Fab")
			(hide yes)
			(effects
				(font
					(size 1 1)
					(thickness 0.15)
				)
				(justify mirror)
			)
		)
		(property "Val" "100n"
			(at 459.758997 66.581588 0)
			(layer "B.Fab")
			(hide yes)
			(effects
				(font
					(size 1 1)
					(thickness 0.15)
				)
				(justify mirror)
			)
		)
		(property "Voltage" "50V"
			(at 459.758997 66.581588 0)
			(layer "B.Fab")
			(hide yes)
			(effects
				(font
					(size 1 1)
					(thickness 0.15)
				)
				(justify mirror)
			)
		)
		(sheetname "FPGA Bank 14 & 15")
		(sheetfile "fpga-bank-14-15.kicad_sch")
		(attr smd)
		(fp_poly
			(pts
				(xy -0.925 0.47) (xy 0.925 0.47) (xy 0.925 -0.47) (xy -0.925 -0.47)
			)
			(stroke
				(width 0.05)
				(type default)
			)
			(fill no)
			(layer "B.CrtYd")
		)
		(fp_line
			(start 0.504 -0.248)
			(end -0.494 -0.248)
			(stroke
				(width 0.15)
				(type solid)
			)
			(layer "B.Fab")
		)
		(fp_line
			(start 0.504 0.25)
			(end 0.504 -0.248)
			(stroke
				(width 0.15)
				(type solid)
			)
			(layer "B.Fab")
		)
		(fp_line
			(start -0.494 -0.248)
			(end -0.494 0.25)
			(stroke
				(width 0.15)
				(type solid)
			)
			(layer "B.Fab")
		)
		(fp_line
			(start -0.494 0.25)
			(end 0.504 0.25)
			(stroke
				(width 0.15)
				(type solid)
			)
			(layer "B.Fab")
		)
		(pad "1" smd roundrect
			(at -0.48 0 135)
			(size 0.59 0.64)
			(layers "B.Cu" "B.Mask" "B.Paste")
			(roundrect_rratio 0.25)
			(net 1 "GND")
			(pintype "passive")
		)
		(pad "2" smd roundrect
			(at 0.48 0 135)
			(size 0.59 0.64)
			(layers "B.Cu" "B.Mask" "B.Paste")
			(roundrect_rratio 0.25)
			(net 24 "+3V3")
			(pintype "passive")
		)
	)
	(footprint "antmicro-footprints:R_0402_1005Metric"
		(layer "B.Cu")
		(at 203.2 92.7 -90)
		(descr "Resistor SMD 0402")
		(tags "resistor SMD 0402")
		(property "Reference" "R214"
			(at -0.9 -2.4 90)
			(layer "B.SilkS")
			(effects
				(font
					(size 0.7 0.7)
					(thickness 0.15)
				)
				(justify left bottom mirror)
			)
		)
		(property "Value" "R_2k2_0402"
			(at 0 -1.4 90)
			(layer "B.Fab")
			(effects
				(font
					(size 0.7 0.7)
					(thickness 0.15)
				)
				(justify left bottom mirror)
			)
		)
		(property "Description" "SMD Chip Resistor, 2.2 kohm, ± 1%, 62.5 mW, 0402 [1005 Metric], Thick Film, General Purpose"
			(at 0 0 270)
			(layer "F.Fab")
			(hide yes)
			(effects
				(font
					(size 1.27 1.27)
					(thickness 0.15)
				)
			)
		)
		(property "Author" "Antmicro"
			(at 110.5 295.9 0)
			(layer "B.Fab")
			(hide yes)
			(effects
				(font
					(size 1 1)
					(thickness 0.15)
				)
				(justify mirror)
			)
		)
		(property "DNP" "DNP"
			(at 110.5 295.9 0)
			(layer "B.Fab")
			(hide yes)
			(effects
				(font
					(size 1 1)
					(thickness 0.15)
				)
				(justify mirror)
			)
		)
		(property "License" "Apache-2.0"
			(at 110.5 295.9 0)
			(layer "B.Fab")
			(hide yes)
			(effects
				(font
					(size 1 1)
					(thickness 0.15)
				)
				(justify mirror)
			)
		)
		(property "MPN" "CR0402-FX-2201GLF"
			(at 110.5 295.9 0)
			(layer "B.Fab")
			(hide yes)
			(effects
				(font
					(size 1 1)
					(thickness 0.15)
				)
				(justify mirror)
			)
		)
		(property "Manufacturer" "Bourns"
			(at 110.5 295.9 0)
			(layer "B.Fab")
			(hide yes)
			(effects
				(font
					(size 1 1)
					(thickness 0.15)
				)
				(justify mirror)
			)
		)
		(property "Tolerance" "1%"
			(at 110.5 295.9 0)
			(layer "B.Fab")
			(hide yes)
			(effects
				(font
					(size 1 1)
					(thickness 0.15)
				)
				(justify mirror)
			)
		)
		(property "Val" "2k2"
			(at 110.5 295.9 0)
			(layer "B.Fab")
			(hide yes)
			(effects
				(font
					(size 1 1)
					(thickness 0.15)
				)
				(justify mirror)
			)
		)
		(property "dnp" ""
			(at 110.5 295.9 0)
			(layer "B.Fab")
			(hide yes)
			(effects
				(font
					(size 1 1)
					(thickness 0.15)
				)
				(justify mirror)
			)
		)
		(property "exclude_from_bom" ""
			(at 110.5 295.9 0)
			(layer "B.Fab")
			(hide yes)
			(effects
				(font
					(size 1 1)
					(thickness 0.15)
				)
				(justify mirror)
			)
		)
		(sheetname "HDMI + Ethernet")
		(sheetfile "hdmi-ethernet.kicad_sch")
		(attr smd exclude_from_bom)
		(fp_rect
			(start -0.925 0.47)
			(end 0.925 -0.47)
			(stroke
				(width 0.05)
				(type default)
			)
			(fill no)
			(layer "B.CrtYd")
		)
		(fp_rect
			(start -0.5 0.25)
			(end 0.5 -0.25)
			(stroke
				(width 0.15)
				(type solid)
			)
			(fill no)
			(layer "B.Fab")
		)
		(pad "1" smd roundrect
			(at -0.48 0 270)
			(size 0.59 0.64)
			(layers "B.Cu" "B.Mask" "B.Paste")
			(roundrect_rratio 0.25)
			(net 850 "/HDMI + Ethernet/GBE_LED_SPD-")
			(pintype "passive")
		)
		(pad "2" smd roundrect
			(at 0.48 0 270)
			(size 0.59 0.64)
			(layers "B.Cu" "B.Mask" "B.Paste")
			(roundrect_rratio 0.25)
			(net 1 "GND")
			(pintype "passive")
		)
	)
	(footprint "antmicro-footprints:C_0402_1005Metric"
		(layer "B.Cu")
		(at 187.950001 132.775001 180)
		(descr "Capacitor SMD 0402")
		(tags "capacitor SMD 0402")
		(property "Reference" "C155"
			(at -0.949999 -1.199999 0)
			(layer "B.SilkS")
			(effects
				(font
					(size 0.7 0.7)
					(thickness 0.15)
				)
				(justify left bottom mirror)
			)
		)
		(property "Value" "C_100n_0402"
			(at 0 -1.169 0)
			(layer "B.Fab")
			(effects
				(font
					(size 0.7 0.7)
					(thickness 0.15)
				)
				(justify left bottom mirror)
			)
		)
		(property "Description" "SMD Multilayer Ceramic Capacitor, 0.1 µF, 50 V, 0402 [1005 Metric], ± 10%, X5R, GRM Series"
			(at 0 0 180)
			(layer "F.Fab")
			(hide yes)
			(effects
				(font
					(size 1.27 1.27)
					(thickness 0.15)
				)
			)
		)
		(property "Author" "Antmicro"
			(at 375.900002 265.550002 0)
			(layer "B.Fab")
			(hide yes)
			(effects
				(font
					(size 1 1)
					(thickness 0.15)
				)
				(justify mirror)
			)
		)
		(property "Dielectric" "X5R"
			(at 375.900002 265.550002 0)
			(layer "B.Fab")
			(hide yes)
			(effects
				(font
					(size 1 1)
					(thickness 0.15)
				)
				(justify mirror)
			)
		)
		(property "License" "Apache-2.0"
			(at 375.900002 265.550002 0)
			(layer "B.Fab")
			(hide yes)
			(effects
				(font
					(size 1 1)
					(thickness 0.15)
				)
				(justify mirror)
			)
		)
		(property "MPN" "GRM155R61H104KE14D"
			(at 375.900002 265.550002 0)
			(layer "B.Fab")
			(hide yes)
			(effects
				(font
					(size 1 1)
					(thickness 0.15)
				)
				(justify mirror)
			)
		)
		(property "Manufacturer" "Murata"
			(at 375.900002 265.550002 0)
			(layer "B.Fab")
			(hide yes)
			(effects
				(font
					(size 1 1)
					(thickness 0.15)
				)
				(justify mirror)
			)
		)
		(property "Val" "100n"
			(at 375.900002 265.550002 0)
			(layer "B.Fab")
			(hide yes)
			(effects
				(font
					(size 1 1)
					(thickness 0.15)
				)
				(justify mirror)
			)
		)
		(property "Voltage" "50V"
			(at 375.900002 265.550002 0)
			(layer "B.Fab")
			(hide yes)
			(effects
				(font
					(size 1 1)
					(thickness 0.15)
				)
				(justify mirror)
			)
		)
		(sheetname "FPGA supply")
		(sheetfile "fpga-supply.kicad_sch")
		(attr smd)
		(fp_rect
			(start -0.925 0.47)
			(end 0.925 -0.47)
			(stroke
				(width 0.05)
				(type default)
			)
			(fill no)
			(layer "B.CrtYd")
		)
		(fp_line
			(start 0.504 0.25)
			(end 0.504 -0.248)
			(stroke
				(width 0.15)
				(type solid)
			)
			(layer "B.Fab")
		)
		(fp_line
			(start 0.504 -0.248)
			(end -0.494 -0.248)
			(stroke
				(width 0.15)
				(type solid)
			)
			(layer "B.Fab")
		)
		(fp_line
			(start -0.494 0.25)
			(end 0.504 0.25)
			(stroke
				(width 0.15)
				(type solid)
			)
			(layer "B.Fab")
		)
		(fp_line
			(start -0.494 -0.248)
			(end -0.494 0.25)
			(stroke
				(width 0.15)
				(type solid)
			)
			(layer "B.Fab")
		)
		(pad "1" smd roundrect
			(at -0.48 0 180)
			(size 0.59 0.64)
			(layers "B.Cu" "B.Mask" "B.Paste")
			(roundrect_rratio 0.25)
			(net 1 "GND")
			(pintype "passive")
		)
		(pad "2" smd roundrect
			(at 0.48 0 180)
			(size 0.59 0.64)
			(layers "B.Cu" "B.Mask" "B.Paste")
			(roundrect_rratio 0.25)
			(net 8 "+1V2_MGTAVTT")
			(pintype "passive")
		)
	)
	(footprint "antmicro-footprints:R_0402_1005Metric"
		(layer "B.Cu")
		(at 251.301 141.25 -90)
		(descr "Resistor SMD 0402")
		(tags "resistor SMD 0402")
		(property "Reference" "R86"
			(at 0.75 -0.399 90)
			(layer "B.SilkS")
			(effects
				(font
					(size 0.7 0.7)
					(thickness 0.15)
				)
				(justify left bottom mirror)
			)
		)
		(property "Value" "R_10k_0402"
			(at 0 -1.4 90)
			(layer "B.Fab")
			(effects
				(font
					(size 0.7 0.7)
					(thickness 0.15)
				)
				(justify left bottom mirror)
			)
		)
		(property "Description" "SMD Chip Resistor, 10 kohm, ± 1%, 62.5 mW, 0402 [1005 Metric], Thick Film, General Purpose"
			(at 0 0 270)
			(layer "F.Fab")
			(hide yes)
			(effects
				(font
					(size 1.27 1.27)
					(thickness 0.15)
				)
			)
		)
		(property "Author" "Antmicro"
			(at 110.051 392.551 0)
			(layer "B.Fab")
			(hide yes)
			(effects
				(font
					(size 1 1)
					(thickness 0.15)
				)
				(justify mirror)
			)
		)
		(property "License" "Apache-2.0"
			(at 110.051 392.551 0)
			(layer "B.Fab")
			(hide yes)
			(effects
				(font
					(size 1 1)
					(thickness 0.15)
				)
				(justify mirror)
			)
		)
		(property "MPN" "CR0402-FX-1002GLF"
			(at 110.051 392.551 0)
			(layer "B.Fab")
			(hide yes)
			(effects
				(font
					(size 1 1)
					(thickness 0.15)
				)
				(justify mirror)
			)
		)
		(property "Manufacturer" "Bourns"
			(at 110.051 392.551 0)
			(layer "B.Fab")
			(hide yes)
			(effects
				(font
					(size 1 1)
					(thickness 0.15)
				)
				(justify mirror)
			)
		)
		(property "Tolerance" "1%"
			(at 110.051 392.551 0)
			(layer "B.Fab")
			(hide yes)
			(effects
				(font
					(size 1 1)
					(thickness 0.15)
				)
				(justify mirror)
			)
		)
		(property "Val" "10k"
			(at 110.051 392.551 0)
			(layer "B.Fab")
			(hide yes)
			(effects
				(font
					(size 1 1)
					(thickness 0.15)
				)
				(justify mirror)
			)
		)
		(sheetname "SPI Flash + SD Card")
		(sheetfile "spi-flash.kicad_sch")
		(attr smd)
		(fp_rect
			(start -0.925 0.47)
			(end 0.925 -0.47)
			(stroke
				(width 0.05)
				(type default)
			)
			(fill no)
			(layer "B.CrtYd")
		)
		(fp_rect
			(start -0.5 0.25)
			(end 0.5 -0.25)
			(stroke
				(width 0.15)
				(type solid)
			)
			(fill no)
			(layer "B.Fab")
		)
		(pad "1" smd roundrect
			(at -0.48 0 270)
			(size 0.59 0.64)
			(layers "B.Cu" "B.Mask" "B.Paste")
			(roundrect_rratio 0.25)
			(net 390 "/FPGA Bank 33 & 34/SD_CARD.DAT2")
			(pintype "passive")
		)
		(pad "2" smd roundrect
			(at 0.48 0 270)
			(size 0.59 0.64)
			(layers "B.Cu" "B.Mask" "B.Paste")
			(roundrect_rratio 0.25)
			(net 24 "+3V3")
			(pintype "passive")
		)
	)
	(footprint "antmicro-footprints:C_0402_1005Metric"
		(layer "B.Cu")
		(at 160.45 188.6)
		(descr "Capacitor SMD 0402")
		(tags "capacitor SMD 0402")
		(property "Reference" "C336"
			(at -3.575 0.4 0)
			(layer "B.SilkS")
			(effects
				(font
					(size 0.7 0.7)
					(thickness 0.15)
				)
				(justify right bottom mirror)
			)
		)
		(property "Value" "C_100n_0402"
			(at 0 -1.4 0)
			(layer "B.Fab")
			(effects
				(font
					(size 0.7 0.7)
					(thickness 0.15)
				)
				(justify right bottom mirror)
			)
		)
		(property "Description" "SMD Multilayer Ceramic Capacitor, 0.1 µF, 50 V, 0402 [1005 Metric], ± 10%, X5R, GRM Series"
			(at 0 0 0)
			(layer "F.Fab")
			(hide yes)
			(effects
				(font
					(size 1.27 1.27)
					(thickness 0.15)
				)
			)
		)
		(property "Author" "Antmicro"
			(at 0 0 0)
			(layer "B.Fab")
			(hide yes)
			(effects
				(font
					(size 1 1)
					(thickness 0.15)
				)
				(justify mirror)
			)
		)
		(property "Dielectric" "X5R"
			(at 0 0 0)
			(layer "B.Fab")
			(hide yes)
			(effects
				(font
					(size 1 1)
					(thickness 0.15)
				)
				(justify mirror)
			)
		)
		(property "License" "Apache-2.0"
			(at 0 0 0)
			(layer "B.Fab")
			(hide yes)
			(effects
				(font
					(size 1 1)
					(thickness 0.15)
				)
				(justify mirror)
			)
		)
		(property "MPN" "GRM155R61H104KE14D"
			(at 0 0 0)
			(layer "B.Fab")
			(hide yes)
			(effects
				(font
					(size 1 1)
					(thickness 0.15)
				)
				(justify mirror)
			)
		)
		(property "Manufacturer" "Murata"
			(at 0 0 0)
			(layer "B.Fab")
			(hide yes)
			(effects
				(font
					(size 1 1)
					(thickness 0.15)
				)
				(justify mirror)
			)
		)
		(property "Val" "100n"
			(at 0 0 0)
			(layer "B.Fab")
			(hide yes)
			(effects
				(font
					(size 1 1)
					(thickness 0.15)
				)
				(justify mirror)
			)
		)
		(property "Voltage" "50V"
			(at 0 0 0)
			(layer "B.Fab")
			(hide yes)
			(effects
				(font
					(size 1 1)
					(thickness 0.15)
				)
				(justify mirror)
			)
		)
		(sheetname "DC-DC Converters")
		(sheetfile "dc-dc.kicad_sch")
		(attr smd)
		(fp_rect
			(start -0.925 0.47)
			(end 0.925 -0.47)
			(stroke
				(width 0.05)
				(type default)
			)
			(fill no)
			(layer "B.CrtYd")
		)
		(fp_line
			(start -0.494 -0.248)
			(end -0.494 0.25)
			(stroke
				(width 0.15)
				(type solid)
			)
			(layer "B.Fab")
		)
		(fp_line
			(start -0.494 0.25)
			(end 0.504 0.25)
			(stroke
				(width 0.15)
				(type solid)
			)
			(layer "B.Fab")
		)
		(fp_line
			(start 0.504 -0.248)
			(end -0.494 -0.248)
			(stroke
				(width 0.15)
				(type solid)
			)
			(layer "B.Fab")
		)
		(fp_line
			(start 0.504 0.25)
			(end 0.504 -0.248)
			(stroke
				(width 0.15)
				(type solid)
			)
			(layer "B.Fab")
		)
		(pad "1" smd roundrect
			(at -0.48 0)
			(size 0.59 0.64)
			(layers "B.Cu" "B.Mask" "B.Paste")
			(roundrect_rratio 0.25)
			(net 1 "GND")
			(pintype "passive")
		)
		(pad "2" smd roundrect
			(at 0.48 0)
			(size 0.59 0.64)
			(layers "B.Cu" "B.Mask" "B.Paste")
			(roundrect_rratio 0.25)
			(net 37 "+3V3_AON")
			(pintype "passive")
		)
	)
	(footprint "antmicro-footprints:R_0402_1005Metric"
		(layer "B.Cu")
		(at 193.1 84.8 90)
		(descr "Resistor SMD 0402")
		(tags "resistor SMD 0402")
		(property "Reference" "R139"
			(at -0.725 0.4 270)
			(layer "B.SilkS")
			(effects
				(font
					(size 0.7 0.7)
					(thickness 0.15)
				)
				(justify left bottom mirror)
			)
		)
		(property "Value" "R_100R_0402"
			(at 0 -1.4 270)
			(layer "B.Fab")
			(effects
				(font
					(size 0.7 0.7)
					(thickness 0.15)
				)
				(justify left bottom mirror)
			)
		)
		(property "Description" "SMD Chip Resistor, 100 ohm, ± 1%, 62.5 mW, 0402 [1005 Metric], Thick Film, General Purpose"
			(at 0 0 90)
			(layer "F.Fab")
			(hide yes)
			(effects
				(font
					(size 1.27 1.27)
					(thickness 0.15)
				)
			)
		)
		(property "Author" "Antmicro"
			(at 277.9 -108.3 0)
			(layer "B.Fab")
			(hide yes)
			(effects
				(font
					(size 1 1)
					(thickness 0.15)
				)
				(justify mirror)
			)
		)
		(property "License" "Apache-2.0"
			(at 277.9 -108.3 0)
			(layer "B.Fab")
			(hide yes)
			(effects
				(font
					(size 1 1)
					(thickness 0.15)
				)
				(justify mirror)
			)
		)
		(property "MPN" "CR0402-FX-1000GLF"
			(at 277.9 -108.3 0)
			(layer "B.Fab")
			(hide yes)
			(effects
				(font
					(size 1 1)
					(thickness 0.15)
				)
				(justify mirror)
			)
		)
		(property "Manufacturer" "Bourns"
			(at 277.9 -108.3 0)
			(layer "B.Fab")
			(hide yes)
			(effects
				(font
					(size 1 1)
					(thickness 0.15)
				)
				(justify mirror)
			)
		)
		(property "Tolerance" "1%"
			(at 277.9 -108.3 0)
			(layer "B.Fab")
			(hide yes)
			(effects
				(font
					(size 1 1)
					(thickness 0.15)
				)
				(justify mirror)
			)
		)
		(property "Val" "100R"
			(at 277.9 -108.3 0)
			(layer "B.Fab")
			(hide yes)
			(effects
				(font
					(size 1 1)
					(thickness 0.15)
				)
				(justify mirror)
			)
		)
		(sheetname "User GPIO + LED + button + DIP switch")
		(sheetfile "user-gpio.kicad_sch")
		(attr smd)
		(fp_rect
			(start -0.925 0.47)
			(end 0.925 -0.47)
			(stroke
				(width 0.05)
				(type default)
			)
			(fill no)
			(layer "B.CrtYd")
		)
		(fp_rect
			(start -0.5 0.25)
			(end 0.5 -0.25)
			(stroke
				(width 0.15)
				(type solid)
			)
			(fill no)
			(layer "B.Fab")
		)
		(pad "1" smd roundrect
			(at -0.48 0 90)
			(size 0.59 0.64)
			(layers "B.Cu" "B.Mask" "B.Paste")
			(roundrect_rratio 0.25)
			(net 832 "/User GPIO + LED + button + DIP switch/CW_20PIN_TPDID")
			(pintype "passive")
		)
		(pad "2" smd roundrect
			(at 0.48 0 90)
			(size 0.59 0.64)
			(layers "B.Cu" "B.Mask" "B.Paste")
			(roundrect_rratio 0.25)
			(net 485 "/FPGA Bank 12 & 13/CW_HEADER.TPDID")
			(pintype "passive")
		)
	)
	(footprint "antmicro-footprints:R_Array_4x0201_Panasonic_EXB18V"
		(layer "B.Cu")
		(at 251.901 149.15)
		(property "Reference" "R31"
			(at 1.024 1.525 0)
			(layer "B.SilkS")
			(effects
				(font
					(size 0.7 0.7)
					(thickness 0.15)
				)
				(justify left bottom mirror)
			)
		)
		(property "Value" "R_4x33R_0201_array"
			(at -1.1 -1.8 0)
			(layer "B.Fab")
			(effects
				(font
					(size 0.7 0.7)
					(thickness 0.15)
				)
				(justify right bottom mirror)
			)
		)
		(property "Description" "Fixed Network Resistor, 33 ohm, Isolated, 4 Resistors, 0502 [1406 Metric], Flat, ± 5%"
			(at 0 0 0)
			(layer "F.Fab")
			(hide yes)
			(effects
				(font
					(size 1.27 1.27)
					(thickness 0.15)
				)
			)
		)
		(property "Author" "Antmicro"
			(at 0 0 0)
			(layer "B.Fab")
			(hide yes)
			(effects
				(font
					(size 1 1)
					(thickness 0.15)
				)
				(justify mirror)
			)
		)
		(property "License" "Apache-2.0"
			(at 0 0 0)
			(layer "B.Fab")
			(hide yes)
			(effects
				(font
					(size 1 1)
					(thickness 0.15)
				)
				(justify mirror)
			)
		)
		(property "MPN" "EXB-18V330JX"
			(at 0 0 0)
			(layer "B.Fab")
			(hide yes)
			(effects
				(font
					(size 1 1)
					(thickness 0.15)
				)
				(justify mirror)
			)
		)
		(property "Manufacturer" "Panasonic"
			(at 0 0 0)
			(layer "B.Fab")
			(hide yes)
			(effects
				(font
					(size 1 1)
					(thickness 0.15)
				)
				(justify mirror)
			)
		)
		(property "Val" "R_4x33R_0201"
			(at 0 0 0)
			(layer "B.Fab")
			(hide yes)
			(effects
				(font
					(size 1 1)
					(thickness 0.15)
				)
				(justify mirror)
			)
		)
		(sheetname "Supervisior MCU")
		(sheetfile "supervisor-mcu.kicad_sch")
		(attr smd)
		(fp_line
			(start -0.8 0.45)
			(end -0.8 -0.45)
			(stroke
				(width 0.12)
				(type solid)
			)
			(layer "B.SilkS")
		)
		(fp_line
			(start 0.8 0.45)
			(end 0.8 -0.45)
			(stroke
				(width 0.12)
				(type solid)
			)
			(layer "B.SilkS")
		)
		(fp_rect
			(start -0.898 0.66)
			(end 0.898 -0.65)
			(stroke
				(width 0.05)
				(type solid)
			)
			(fill no)
			(layer "B.CrtYd")
		)
		(pad "1" smd roundrect
			(at -0.6 -0.298)
			(size 0.2 0.4)
			(layers "B.Cu" "B.Mask" "B.Paste")
			(roundrect_rratio 0.25)
			(net 1413 "/SUP_MCU.PG_1V2")
			(pinfunction "R1.1")
			(pintype "passive")
		)
		(pad "2" smd roundrect
			(at -0.202 -0.298)
			(size 0.2 0.4)
			(layers "B.Cu" "B.Mask" "B.Paste")
			(roundrect_rratio 0.25)
			(net 1314 "/SUP_MCU.FPGA_M2")
			(pinfunction "R2.1")
			(pintype "passive")
		)
		(pad "3" smd roundrect
			(at 0.2 -0.298)
			(size 0.2 0.4)
			(layers "B.Cu" "B.Mask" "B.Paste")
			(roundrect_rratio 0.25)
			(net 1378 "/SUP_MCU.A8")
			(pinfunction "R3.1")
			(pintype "passive")
		)
		(pad "4" smd roundrect
			(at 0.598 -0.298)
			(size 0.2 0.4)
			(layers "B.Cu" "B.Mask" "B.Paste")
			(roundrect_rratio 0.25)
			(net 1321 "/SUP_MCU.MOSI")
			(pinfunction "R4.1")
			(pintype "passive")
		)
		(pad "5" smd roundrect
			(at 0.598 0.3)
			(size 0.2 0.4)
			(layers "B.Cu" "B.Mask" "B.Paste")
			(roundrect_rratio 0.25)
			(net 1090 "/Supervisior MCU/USB_SPI_COPI")
			(pinfunction "R4.2")
			(pintype "passive")
		)
		(pad "6" smd roundrect
			(at 0.2 0.3)
			(size 0.2 0.4)
			(layers "B.Cu" "B.Mask" "B.Paste")
			(roundrect_rratio 0.25)
			(net 1069 "/Supervisior MCU/USB_A8")
			(pinfunction "R3.2")
			(pintype "passive")
		)
		(pad "7" smd roundrect
			(at -0.202 0.3)
			(size 0.2 0.4)
			(layers "B.Cu" "B.Mask" "B.Paste")
			(roundrect_rratio 0.25)
			(net 1105 "/Supervisior MCU/FPGA_M2")
			(pinfunction "R2.2")
			(pintype "passive")
		)
		(pad "8" smd roundrect
			(at -0.6 0.3)
			(size 0.2 0.4)
			(layers "B.Cu" "B.Mask" "B.Paste")
			(roundrect_rratio 0.25)
			(net 1088 "/Supervisior MCU/PGOOD_1V2")
			(pinfunction "R1.2")
			(pintype "passive")
		)
	)
	(footprint "antmicro-footprints:R_Array_4x0201_Panasonic_EXB18V"
		(layer "B.Cu")
		(at 245.901 149.15)
		(property "Reference" "R28"
			(at 1.074 -0.675 0)
			(layer "B.SilkS")
			(effects
				(font
					(size 0.7 0.7)
					(thickness 0.15)
				)
				(justify left bottom mirror)
			)
		)
		(property "Value" "R_4x33R_0201_array"
			(at -1.1 -1.8 0)
			(layer "B.Fab")
			(effects
				(font
					(size 0.7 0.7)
					(thickness 0.15)
				)
				(justify right bottom mirror)
			)
		)
		(property "Description" "Fixed Network Resistor, 33 ohm, Isolated, 4 Resistors, 0502 [1406 Metric], Flat, ± 5%"
			(at 0 0 0)
			(layer "F.Fab")
			(hide yes)
			(effects
				(font
					(size 1.27 1.27)
					(thickness 0.15)
				)
			)
		)
		(property "Author" "Antmicro"
			(at 0 0 0)
			(layer "B.Fab")
			(hide yes)
			(effects
				(font
					(size 1 1)
					(thickness 0.15)
				)
				(justify mirror)
			)
		)
		(property "License" "Apache-2.0"
			(at 0 0 0)
			(layer "B.Fab")
			(hide yes)
			(effects
				(font
					(size 1 1)
					(thickness 0.15)
				)
				(justify mirror)
			)
		)
		(property "MPN" "EXB-18V330JX"
			(at 0 0 0)
			(layer "B.Fab")
			(hide yes)
			(effects
				(font
					(size 1 1)
					(thickness 0.15)
				)
				(justify mirror)
			)
		)
		(property "Manufacturer" "Panasonic"
			(at 0 0 0)
			(layer "B.Fab")
			(hide yes)
			(effects
				(font
					(size 1 1)
					(thickness 0.15)
				)
				(justify mirror)
			)
		)
		(property "Val" "R_4x33R_0201"
			(at 0 0 0)
			(layer "B.Fab")
			(hide yes)
			(effects
				(font
					(size 1 1)
					(thickness 0.15)
				)
				(justify mirror)
			)
		)
		(sheetname "Supervisior MCU")
		(sheetfile "supervisor-mcu.kicad_sch")
		(attr smd)
		(fp_line
			(start -0.8 0.45)
			(end -0.8 -0.45)
			(stroke
				(width 0.12)
				(type solid)
			)
			(layer "B.SilkS")
		)
		(fp_line
			(start 0.8 0.45)
			(end 0.8 -0.45)
			(stroke
				(width 0.12)
				(type solid)
			)
			(layer "B.SilkS")
		)
		(fp_rect
			(start -0.898 0.66)
			(end 0.898 -0.65)
			(stroke
				(width 0.05)
				(type solid)
			)
			(fill no)
			(layer "B.CrtYd")
		)
		(pad "1" smd roundrect
			(at -0.6 -0.298)
			(size 0.2 0.4)
			(layers "B.Cu" "B.Mask" "B.Paste")
			(roundrect_rratio 0.25)
			(net 358 "unconnected-(R28-R1.1-Pad1)")
			(pinfunction "R1.1")
			(pintype "passive+no_connect")
		)
		(pad "2" smd roundrect
			(at -0.202 -0.298)
			(size 0.2 0.4)
			(layers "B.Cu" "B.Mask" "B.Paste")
			(roundrect_rratio 0.25)
			(net 359 "unconnected-(R28-R2.1-Pad2)")
			(pinfunction "R2.1")
			(pintype "passive+no_connect")
		)
		(pad "3" smd roundrect
			(at 0.2 -0.298)
			(size 0.2 0.4)
			(layers "B.Cu" "B.Mask" "B.Paste")
			(roundrect_rratio 0.25)
			(net 1372 "/SUP_MCU.D0")
			(pinfunction "R3.1")
			(pintype "passive")
		)
		(pad "4" smd roundrect
			(at 0.598 -0.298)
			(size 0.2 0.4)
			(layers "B.Cu" "B.Mask" "B.Paste")
			(roundrect_rratio 0.25)
			(net 1373 "/SUP_MCU.D3")
			(pinfunction "R4.1")
			(pintype "passive")
		)
		(pad "5" smd roundrect
			(at 0.598 0.3)
			(size 0.2 0.4)
			(layers "B.Cu" "B.Mask" "B.Paste")
			(roundrect_rratio 0.25)
			(net 1109 "/Supervisior MCU/USB_D3")
			(pinfunction "R4.2")
			(pintype "passive")
		)
		(pad "6" smd roundrect
			(at 0.2 0.3)
			(size 0.2 0.4)
			(layers "B.Cu" "B.Mask" "B.Paste")
			(roundrect_rratio 0.25)
			(net 1099 "/Supervisior MCU/USB_D0")
			(pinfunction "R3.2")
			(pintype "passive")
		)
		(pad "7" smd roundrect
			(at -0.202 0.3)
			(size 0.2 0.4)
			(layers "B.Cu" "B.Mask" "B.Paste")
			(roundrect_rratio 0.25)
			(net 360 "unconnected-(R28-R2.2-Pad7)")
			(pinfunction "R2.2")
			(pintype "passive+no_connect")
		)
		(pad "8" smd roundrect
			(at -0.6 0.3)
			(size 0.2 0.4)
			(layers "B.Cu" "B.Mask" "B.Paste")
			(roundrect_rratio 0.25)
			(net 361 "unconnected-(R28-R1.2-Pad8)")
			(pinfunction "R1.2")
			(pintype "passive+no_connect")
		)
	)
	(footprint "antmicro-footprints:C_0402_1005Metric"
		(layer "B.Cu")
		(at 157.65 144.5 -90)
		(descr "Capacitor SMD 0402")
		(tags "capacitor SMD 0402")
		(property "Reference" "C175"
			(at -1.9 3.475 90)
			(layer "B.SilkS")
			(effects
				(font
					(size 0.7 0.7)
					(thickness 0.15)
				)
				(justify left bottom mirror)
			)
		)
		(property "Value" "C_100n_0402"
			(at 0 -1.169 90)
			(layer "B.Fab")
			(effects
				(font
					(size 0.7 0.7)
					(thickness 0.15)
				)
				(justify left bottom mirror)
			)
		)
		(property "Description" "SMD Multilayer Ceramic Capacitor, 0.1 µF, 50 V, 0402 [1005 Metric], ± 10%, X5R, GRM Series"
			(at 0 0 270)
			(layer "F.Fab")
			(hide yes)
			(effects
				(font
					(size 1.27 1.27)
					(thickness 0.15)
				)
			)
		)
		(property "Author" "Antmicro"
			(at 13.15 302.15 0)
			(layer "B.Fab")
			(hide yes)
			(effects
				(font
					(size 1 1)
					(thickness 0.15)
				)
				(justify mirror)
			)
		)
		(property "Dielectric" "X5R"
			(at 13.15 302.15 0)
			(layer "B.Fab")
			(hide yes)
			(effects
				(font
					(size 1 1)
					(thickness 0.15)
				)
				(justify mirror)
			)
		)
		(property "License" "Apache-2.0"
			(at 13.15 302.15 0)
			(layer "B.Fab")
			(hide yes)
			(effects
				(font
					(size 1 1)
					(thickness 0.15)
				)
				(justify mirror)
			)
		)
		(property "MPN" "GRM155R61H104KE14D"
			(at 13.15 302.15 0)
			(layer "B.Fab")
			(hide yes)
			(effects
				(font
					(size 1 1)
					(thickness 0.15)
				)
				(justify mirror)
			)
		)
		(property "Manufacturer" "Murata"
			(at 13.15 302.15 0)
			(layer "B.Fab")
			(hide yes)
			(effects
				(font
					(size 1 1)
					(thickness 0.15)
				)
				(justify mirror)
			)
		)
		(property "Val" "100n"
			(at 13.15 302.15 0)
			(layer "B.Fab")
			(hide yes)
			(effects
				(font
					(size 1 1)
					(thickness 0.15)
				)
				(justify mirror)
			)
		)
		(property "Voltage" "50V"
			(at 13.15 302.15 0)
			(layer "B.Fab")
			(hide yes)
			(effects
				(font
					(size 1 1)
					(thickness 0.15)
				)
				(justify mirror)
			)
		)
		(sheetname "DRAM + SRAM")
		(sheetfile "ram.kicad_sch")
		(attr smd)
		(fp_rect
			(start -0.925 0.47)
			(end 0.925 -0.47)
			(stroke
				(width 0.05)
				(type default)
			)
			(fill no)
			(layer "B.CrtYd")
		)
		(fp_line
			(start -0.494 0.25)
			(end 0.504 0.25)
			(stroke
				(width 0.15)
				(type solid)
			)
			(layer "B.Fab")
		)
		(fp_line
			(start 0.504 0.25)
			(end 0.504 -0.248)
			(stroke
				(width 0.15)
				(type solid)
			)
			(layer "B.Fab")
		)
		(fp_line
			(start -0.494 -0.248)
			(end -0.494 0.25)
			(stroke
				(width 0.15)
				(type solid)
			)
			(layer "B.Fab")
		)
		(fp_line
			(start 0.504 -0.248)
			(end -0.494 -0.248)
			(stroke
				(width 0.15)
				(type solid)
			)
			(layer "B.Fab")
		)
		(pad "1" smd roundrect
			(at -0.48 0 270)
			(size 0.59 0.64)
			(layers "B.Cu" "B.Mask" "B.Paste")
			(roundrect_rratio 0.25)
			(net 1 "GND")
			(pintype "passive")
		)
		(pad "2" smd roundrect
			(at 0.48 0 270)
			(size 0.59 0.64)
			(layers "B.Cu" "B.Mask" "B.Paste")
			(roundrect_rratio 0.25)
			(net 7 "+0V675_VTT")
			(pintype "passive")
		)
	)
	(footprint "antmicro-footprints:MicroSD_DM3AT-SF-PEJM5"
		(layer "B.Cu")
		(at 261.027 136.677 -90)
		(descr "Micro SD, SMD, right-angle, push-pull")
		(tags "Micro SD")
		(property "Reference" "J23"
			(at 1.753 8.907 90)
			(layer "B.SilkS")
			(effects
				(font
					(size 0.7 0.7)
					(thickness 0.15)
				)
				(justify left bottom mirror)
			)
		)
		(property "Value" "DM3AT-SF-PEJM5"
			(at 0 -9.6 90)
			(layer "B.Fab")
			(effects
				(font
					(size 0.7 0.7)
					(thickness 0.15)
				)
				(justify left bottom mirror)
			)
		)
		(property "Description" "Memory Card Connector, MicroSD, Push-Push, 8 Contacts, Copper Alloy, Gold Plated Contacts, DM3"
			(at 0 0 270)
			(layer "F.Fab")
			(hide yes)
			(effects
				(font
					(size 1.27 1.27)
					(thickness 0.15)
				)
			)
		)
		(property "Author" "Antmicro"
			(at 124.35 397.704 0)
			(layer "B.Fab")
			(hide yes)
			(effects
				(font
					(size 1 1)
					(thickness 0.15)
				)
				(justify mirror)
			)
		)
		(property "License" "Apache-2.0"
			(at 124.35 397.704 0)
			(layer "B.Fab")
			(hide yes)
			(effects
				(font
					(size 1 1)
					(thickness 0.15)
				)
				(justify mirror)
			)
		)
		(property "MPN" "DM3AT-SF-PEJM5"
			(at 124.35 397.704 0)
			(layer "B.Fab")
			(hide yes)
			(effects
				(font
					(size 1 1)
					(thickness 0.15)
				)
				(justify mirror)
			)
		)
		(property "Manufacturer" "Hirose Electric"
			(at 124.35 397.704 0)
			(layer "B.Fab")
			(hide yes)
			(effects
				(font
					(size 1 1)
					(thickness 0.15)
				)
				(justify mirror)
			)
		)
		(sheetname "SPI Flash + SD Card")
		(sheetfile "spi-flash.kicad_sch")
		(attr smd)
		(fp_line
			(start -7 8.11)
			(end -7 4.502)
			(stroke
				(width 0.15)
				(type solid)
			)
			(layer "B.SilkS")
		)
		(fp_line
			(start -6.553 8.11)
			(end -7 8.11)
			(stroke
				(width 0.15)
				(type solid)
			)
			(layer "B.SilkS")
		)
		(fp_line
			(start 5.049 8.11)
			(end 6.967 8.11)
			(stroke
				(width 0.15)
				(type solid)
			)
			(layer "B.SilkS")
		)
		(fp_line
			(start 6.967 8.11)
			(end 6.967 -5.897)
			(stroke
				(width 0.15)
				(type solid)
			)
			(layer "B.SilkS")
		)
		(fp_line
			(start -7 2.802)
			(end -7 -1.898)
			(stroke
				(width 0.15)
				(type solid)
			)
			(layer "B.SilkS")
		)
		(fp_line
			(start -7 -3.197)
			(end -7 -4.998)
			(stroke
				(width 0.15)
				(type solid)
			)
			(layer "B.SilkS")
		)
		(fp_line
			(start -3.9 -7.809)
			(end 2.47 -7.809)
			(stroke
				(width 0.15)
				(type solid)
			)
			(layer "B.SilkS")
		)
		(fp_line
			(start -3.9 -7.809)
			(end -3.9 -7.959)
			(stroke
				(width 0.15)
				(type solid)
			)
			(layer "B.SilkS")
		)
		(fp_line
			(start 5.488 -7.959)
			(end 5.749 -7.959)
			(stroke
				(width 0.15)
				(type solid)
			)
			(layer "B.SilkS")
		)
		(fp_line
			(start -5.971 -8.157)
			(end -6.17 -7.959)
			(stroke
				(width 0.15)
				(type solid)
			)
			(layer "B.SilkS")
		)
		(fp_line
			(start -5.971 -8.157)
			(end -4.111 -8.157)
			(stroke
				(width 0.15)
				(type solid)
			)
			(layer "B.SilkS")
		)
		(fp_line
			(start -4.111 -8.157)
			(end -3.9 -7.959)
			(stroke
				(width 0.15)
				(type solid)
			)
			(layer "B.SilkS")
		)
		(fp_line
			(start 2.979 -8.157)
			(end 2.47 -7.809)
			(stroke
				(width 0.15)
				(type solid)
			)
			(layer "B.SilkS")
		)
		(fp_line
			(start 5.289 -8.157)
			(end 5.488 -7.959)
			(stroke
				(width 0.15)
				(type solid)
			)
			(layer "B.SilkS")
		)
		(fp_line
			(start 5.289 -8.157)
			(end 2.979 -8.157)
			(stroke
				(width 0.15)
				(type solid)
			)
			(layer "B.SilkS")
		)
		(fp_circle
			(center 3.19 8.71)
			(end 3.239 8.71)
			(stroke
				(width 0.15)
				(type solid)
			)
			(fill yes)
			(layer "B.SilkS")
		)
		(fp_rect
			(start -7.7 8.9)
			(end 7.4 -8.6)
			(stroke
				(width 0.05)
				(type solid)
			)
			(fill no)
			(layer "B.CrtYd")
		)
		(fp_line
			(start 6.898 8.051)
			(end -6.951 8.051)
			(stroke
				(width 0.15)
				(type solid)
			)
			(layer "B.Fab")
		)
		(fp_line
			(start 2.483 -7.748)
			(end -3.94 -7.748)
			(stroke
				(width 0.15)
				(type solid)
			)
			(layer "B.Fab")
		)
		(fp_line
			(start -6.951 -7.898)
			(end -6.951 8.051)
			(stroke
				(width 0.15)
				(type solid)
			)
			(layer "B.Fab")
		)
		(fp_line
			(start -6.141 -7.898)
			(end -6.951 -7.898)
			(stroke
				(width 0.15)
				(type solid)
			)
			(layer "B.Fab")
		)
		(fp_line
			(start -3.94 -7.898)
			(end -3.94 -7.748)
			(stroke
				(width 0.15)
				(type solid)
			)
			(layer "B.Fab")
		)
		(fp_line
			(start -3.94 -7.898)
			(end -4.141 -8.099)
			(stroke
				(width 0.15)
				(type solid)
			)
			(layer "B.Fab")
		)
		(fp_line
			(start 5.459 -7.898)
			(end 6.898 -7.898)
			(stroke
				(width 0.15)
				(type solid)
			)
			(layer "B.Fab")
		)
		(fp_line
			(start 6.898 -7.898)
			(end 6.898 8.051)
			(stroke
				(width 0.15)
				(type solid)
			)
			(layer "B.Fab")
		)
		(fp_line
			(start -5.951 -8.099)
			(end -5.951 -12.998)
			(stroke
				(width 0.15)
				(type solid)
			)
			(layer "B.Fab")
		)
		(fp_line
			(start -5.941 -8.099)
			(end -6.141 -7.898)
			(stroke
				(width 0.15)
				(type solid)
			)
			(layer "B.Fab")
		)
		(fp_line
			(start -4.141 -8.099)
			(end -5.941 -8.099)
			(stroke
				(width 0.15)
				(type solid)
			)
			(layer "B.Fab")
		)
		(fp_line
			(start 3.01 -8.099)
			(end 2.483 -7.748)
			(stroke
				(width 0.15)
				(type solid)
			)
			(layer "B.Fab")
		)
		(fp_line
			(start 5.259 -8.099)
			(end 5.459 -7.898)
			(stroke
				(width 0.15)
				(type solid)
			)
			(layer "B.Fab")
		)
		(fp_line
			(start 5.259 -8.099)
			(end 3.01 -8.099)
			(stroke
				(width 0.15)
				(type solid)
			)
			(layer "B.Fab")
		)
		(fp_line
			(start -5.451 -9.497)
			(end 4.549 -9.497)
			(stroke
				(width 0.15)
				(type solid)
			)
			(layer "B.Fab")
		)
		(fp_line
			(start 5.049 -12.998)
			(end 5.049 -8.099)
			(stroke
				(width 0.15)
				(type solid)
			)
			(layer "B.Fab")
		)
		(fp_line
			(start -5.451 -13.498)
			(end 4.549 -13.498)
			(stroke
				(width 0.15)
				(type solid)
			)
			(layer "B.Fab")
		)
		(fp_arc
			(start -5.951 -8.997)
			(mid -5.8055 -9.3515)
			(end -5.451 -9.497)
			(stroke
				(width 0.15)
				(type solid)
			)
			(layer "B.Fab")
		)
		(fp_arc
			(start 4.549 -9.497)
			(mid 4.903498 -9.351498)
			(end 5.049 -8.997)
			(stroke
				(width 0.15)
				(type solid)
			)
			(layer "B.Fab")
		)
		(fp_arc
			(start -5.951 -12.998)
			(mid -5.805 -13.352)
			(end -5.451 -13.498)
			(stroke
				(width 0.15)
				(type solid)
			)
			(layer "B.Fab")
		)
		(fp_arc
			(start 4.549 -13.498)
			(mid 4.903 -13.352)
			(end 5.049 -12.998)
			(stroke
				(width 0.15)
				(type solid)
			)
			(layer "B.Fab")
		)
		(pad "1" smd rect
			(at 2.749 7.952 270)
			(size 0.7 1.2)
			(layers "B.Cu" "B.Mask" "B.Paste")
			(net 327 "Net-(J23-DAT2)")
			(pinfunction "DAT2")
			(pintype "bidirectional")
		)
		(pad "2" smd rect
			(at 1.65 7.952 270)
			(size 0.7 1.2)
			(layers "B.Cu" "B.Mask" "B.Paste")
			(net 328 "Net-(J23-DAT3{slash}CD)")
			(pinfunction "DAT3/CD")
			(pintype "bidirectional")
		)
		(pad "3" smd rect
			(at 0.549 7.952 270)
			(size 0.7 1.2)
			(layers "B.Cu" "B.Mask" "B.Paste")
			(net 329 "Net-(J23-CMD)")
			(pinfunction "CMD")
			(pintype "input")
		)
		(pad "4" smd rect
			(at -0.552 7.952 270)
			(size 0.7 1.2)
			(layers "B.Cu" "B.Mask" "B.Paste")
			(net 24 "+3V3")
			(pinfunction "VDD")
			(pintype "power_in")
		)
		(pad "5" smd rect
			(at -1.651 7.952 270)
			(size 0.7 1.2)
			(layers "B.Cu" "B.Mask" "B.Paste")
			(net 330 "Net-(J23-CLK)")
			(pinfunction "CLK")
			(pintype "input")
		)
		(pad "6" smd rect
			(at -2.751 7.952 270)
			(size 0.7 1.2)
			(layers "B.Cu" "B.Mask" "B.Paste")
			(net 1 "GND")
			(pinfunction "VSS")
			(pintype "power_in")
		)
		(pad "7" smd rect
			(at -3.851 7.952 270)
			(size 0.7 1.2)
			(layers "B.Cu" "B.Mask" "B.Paste")
			(net 331 "Net-(J23-DAT0)")
			(pinfunction "DAT0")
			(pintype "input")
		)
		(pad "8" smd rect
			(at -4.951 7.952 270)
			(size 0.7 1.2)
			(layers "B.Cu" "B.Mask" "B.Paste")
			(net 332 "Net-(J23-DAT1)")
			(pinfunction "DAT1")
			(pintype "input")
		)
		(pad "9" smd rect
			(at -5.901 7.952 270)
			(size 0.7 1.2)
			(layers "B.Cu" "B.Mask" "B.Paste")
			(net 1 "GND")
			(pinfunction "DET_B")
			(pintype "passive")
		)
		(pad "10" smd rect
			(at -6.851 -2.547 270)
			(size 1 0.8)
			(layers "B.Cu" "B.Mask" "B.Paste")
			(net 74 "/SPI Flash + SD Card/SD_CARD_~{CD}")
			(pinfunction "DET_A")
			(pintype "passive")
		)
		(pad "11" smd rect
			(at -6.851 -6.698 270)
			(size 1 2.8)
			(layers "B.Cu" "B.Mask" "B.Paste")
			(net 16 "Net-(J23-SHIELD)")
			(pinfunction "SHIELD")
			(pintype "passive")
		)
		(pad "11" smd rect
			(at -6.851 3.652 270)
			(size 1 1.2)
			(layers "B.Cu" "B.Mask" "B.Paste")
			(net 16 "Net-(J23-SHIELD)")
			(pinfunction "SHIELD")
			(pintype "passive")
		)
		(pad "11" smd rect
			(at 4.299 7.952 270)
			(size 1 1.2)
			(layers "B.Cu" "B.Mask" "B.Paste")
			(net 16 "Net-(J23-SHIELD)")
			(pinfunction "SHIELD")
			(pintype "passive")
		)
		(pad "11" smd rect
			(at 6.648 -7.148 270)
			(size 1.3 1.9)
			(layers "B.Cu" "B.Mask" "B.Paste")
			(net 16 "Net-(J23-SHIELD)")
			(pinfunction "SHIELD")
			(pintype "passive")
		)
	)
	(footprint "antmicro-footprints:R_0402_1005Metric"
		(layer "B.Cu")
		(at 261.5 86.2)
		(descr "Resistor SMD 0402")
		(tags "resistor SMD 0402")
		(property "Reference" "R108"
			(at 1.4 1.275 180)
			(layer "B.SilkS")
			(effects
				(font
					(size 0.7 0.7)
					(thickness 0.15)
				)
				(justify left bottom mirror)
			)
		)
		(property "Value" "R_1k_0402"
			(at 0 -1.4 180)
			(layer "B.Fab")
			(effects
				(font
					(size 0.7 0.7)
					(thickness 0.15)
				)
				(justify left bottom mirror)
			)
		)
		(property "Description" "SMD Chip Resistor, 1 kohm, ± 1%, 63 mW, 0402 [1005 Metric], Thick Film, General Purpose"
			(at 0 0 0)
			(layer "F.Fab")
			(hide yes)
			(effects
				(font
					(size 1.27 1.27)
					(thickness 0.15)
				)
			)
		)
		(property "Author" "Antmicro"
			(at 0 0 0)
			(layer "B.Fab")
			(hide yes)
			(effects
				(font
					(size 1 1)
					(thickness 0.15)
				)
				(justify mirror)
			)
		)
		(property "License" "Apache-2.0"
			(at 0 0 0)
			(layer "B.Fab")
			(hide yes)
			(effects
				(font
					(size 1 1)
					(thickness 0.15)
				)
				(justify mirror)
			)
		)
		(property "MPN" "CR0402-FX-1001GLF"
			(at 0 0 0)
			(layer "B.Fab")
			(hide yes)
			(effects
				(font
					(size 1 1)
					(thickness 0.15)
				)
				(justify mirror)
			)
		)
		(property "Manufacturer" "Bourns"
			(at 0 0 0)
			(layer "B.Fab")
			(hide yes)
			(effects
				(font
					(size 1 1)
					(thickness 0.15)
				)
				(justify mirror)
			)
		)
		(property "Tolerance" "1%"
			(at 0 0 0)
			(layer "B.Fab")
			(hide yes)
			(effects
				(font
					(size 1 1)
					(thickness 0.15)
				)
				(justify mirror)
			)
		)
		(property "Val" "1k"
			(at 0 0 0)
			(layer "B.Fab")
			(hide yes)
			(effects
				(font
					(size 1 1)
					(thickness 0.15)
				)
				(justify mirror)
			)
		)
		(sheetname "User GPIO + LED + button + DIP switch")
		(sheetfile "user-gpio.kicad_sch")
		(attr smd)
		(fp_rect
			(start -0.925 0.47)
			(end 0.925 -0.47)
			(stroke
				(width 0.05)
				(type default)
			)
			(fill no)
			(layer "B.CrtYd")
		)
		(fp_rect
			(start -0.5 0.25)
			(end 0.5 -0.25)
			(stroke
				(width 0.15)
				(type solid)
			)
			(fill no)
			(layer "B.Fab")
		)
		(pad "1" smd roundrect
			(at -0.48 0)
			(size 0.59 0.64)
			(layers "B.Cu" "B.Mask" "B.Paste")
			(roundrect_rratio 0.25)
			(net 24 "+3V3")
			(pintype "passive")
		)
		(pad "2" smd roundrect
			(at 0.48 0)
			(size 0.59 0.64)
			(layers "B.Cu" "B.Mask" "B.Paste")
			(roundrect_rratio 0.25)
			(net 777 "Net-(D19-A)")
			(pintype "passive")
		)
	)
	(footprint "antmicro-footprints:C_0603_1608Metric"
		(layer "B.Cu")
		(at 200 118.3 90)
		(descr "Capacitor SMD 0603")
		(tags "capacitor 0603")
		(property "Reference" "C106"
			(at 5.275 -0.725 270)
			(layer "B.SilkS")
			(effects
				(font
					(size 0.7 0.7)
					(thickness 0.15)
				)
				(justify left bottom mirror)
			)
		)
		(property "Value" "C_47u_0603"
			(at 0 -1.6 270)
			(layer "B.Fab")
			(effects
				(font
					(size 0.7 0.7)
					(thickness 0.15)
				)
				(justify left bottom mirror)
			)
		)
		(property "Description" "SMD Multilayer Ceramic Capacitor, 47 µF, 6.3 V, 0603 [1608 Metric], ± 20%, X5R, GRM Series"
			(at 0 0 90)
			(layer "F.Fab")
			(hide yes)
			(effects
				(font
					(size 1.27 1.27)
					(thickness 0.15)
				)
			)
		)
		(property "Author" "Antmicro"
			(at 318.3 -81.7 0)
			(layer "B.Fab")
			(hide yes)
			(effects
				(font
					(size 1 1)
					(thickness 0.15)
				)
				(justify mirror)
			)
		)
		(property "Dielectric" ""
			(at 318.3 -81.7 0)
			(layer "B.Fab")
			(hide yes)
			(effects
				(font
					(size 1 1)
					(thickness 0.15)
				)
				(justify mirror)
			)
		)
		(property "License" "Apache-2.0"
			(at 318.3 -81.7 0)
			(layer "B.Fab")
			(hide yes)
			(effects
				(font
					(size 1 1)
					(thickness 0.15)
				)
				(justify mirror)
			)
		)
		(property "MPN" "GRM188R60J476ME15D"
			(at 318.3 -81.7 0)
			(layer "B.Fab")
			(hide yes)
			(effects
				(font
					(size 1 1)
					(thickness 0.15)
				)
				(justify mirror)
			)
		)
		(property "Manufacturer" "Murata"
			(at 318.3 -81.7 0)
			(layer "B.Fab")
			(hide yes)
			(effects
				(font
					(size 1 1)
					(thickness 0.15)
				)
				(justify mirror)
			)
		)
		(property "Val" "47u"
			(at 318.3 -81.7 0)
			(layer "B.Fab")
			(hide yes)
			(effects
				(font
					(size 1 1)
					(thickness 0.15)
				)
				(justify mirror)
			)
		)
		(property "Voltage" ""
			(at 318.3 -81.7 0)
			(layer "B.Fab")
			(hide yes)
			(effects
				(font
					(size 1 1)
					(thickness 0.15)
				)
				(justify mirror)
			)
		)
		(sheetname "FPGA Bank 18 & 32")
		(sheetfile "fpga-bank-18-32.kicad_sch")
		(attr smd)
		(fp_line
			(start -0.15 -0.4)
			(end 0.15 -0.4)
			(stroke
				(width 0.15)
				(type solid)
			)
			(layer "B.SilkS")
		)
		(fp_line
			(start -0.15 0.4)
			(end 0.15 0.4)
			(stroke
				(width 0.15)
				(type solid)
			)
			(layer "B.SilkS")
		)
		(fp_rect
			(start -1.25 0.65)
			(end 1.25 -0.65)
			(stroke
				(width 0.05)
				(type solid)
			)
			(fill no)
			(layer "B.CrtYd")
		)
		(fp_rect
			(start -0.8 0.4)
			(end 0.8 -0.4)
			(stroke
				(width 0.15)
				(type solid)
			)
			(fill no)
			(layer "B.Fab")
		)
		(pad "1" smd roundrect
			(at -0.7 0 90)
			(size 0.8 1)
			(layers "B.Cu" "B.Mask" "B.Paste")
			(roundrect_rratio 0.2)
			(net 24 "+3V3")
			(pintype "passive")
		)
		(pad "2" smd roundrect
			(at 0.7 0 90)
			(size 0.8 1)
			(layers "B.Cu" "B.Mask" "B.Paste")
			(roundrect_rratio 0.2)
			(net 1 "GND")
			(pintype "passive")
		)
	)
	(footprint "antmicro-footprints:C_0402_1005Metric"
		(layer "B.Cu")
		(at 213.5 132 -90)
		(descr "Capacitor SMD 0402")
		(tags "capacitor SMD 0402")
		(property "Reference" "C19"
			(at -1.075 -1.325 90)
			(layer "B.SilkS")
			(effects
				(font
					(size 0.7 0.7)
					(thickness 0.15)
				)
				(justify left bottom mirror)
			)
		)
		(property "Value" "C_100n_0402"
			(at 0 -1.169 90)
			(layer "B.Fab")
			(effects
				(font
					(size 0.7 0.7)
					(thickness 0.15)
				)
				(justify left bottom mirror)
			)
		)
		(property "Description" "SMD Multilayer Ceramic Capacitor, 0.1 µF, 50 V, 0402 [1005 Metric], ± 10%, X5R, GRM Series"
			(at 0 0 270)
			(layer "F.Fab")
			(hide yes)
			(effects
				(font
					(size 1.27 1.27)
					(thickness 0.15)
				)
			)
		)
		(property "Author" "Antmicro"
			(at 81.5 345.5 0)
			(layer "B.Fab")
			(hide yes)
			(effects
				(font
					(size 1 1)
					(thickness 0.15)
				)
				(justify mirror)
			)
		)
		(property "Dielectric" "X5R"
			(at 81.5 345.5 0)
			(layer "B.Fab")
			(hide yes)
			(effects
				(font
					(size 1 1)
					(thickness 0.15)
				)
				(justify mirror)
			)
		)
		(property "License" "Apache-2.0"
			(at 81.5 345.5 0)
			(layer "B.Fab")
			(hide yes)
			(effects
				(font
					(size 1 1)
					(thickness 0.15)
				)
				(justify mirror)
			)
		)
		(property "MPN" "GRM155R61H104KE14D"
			(at 81.5 345.5 0)
			(layer "B.Fab")
			(hide yes)
			(effects
				(font
					(size 1 1)
					(thickness 0.15)
				)
				(justify mirror)
			)
		)
		(property "Manufacturer" "Murata"
			(at 81.5 345.5 0)
			(layer "B.Fab")
			(hide yes)
			(effects
				(font
					(size 1 1)
					(thickness 0.15)
				)
				(justify mirror)
			)
		)
		(property "Val" "100n"
			(at 81.5 345.5 0)
			(layer "B.Fab")
			(hide yes)
			(effects
				(font
					(size 1 1)
					(thickness 0.15)
				)
				(justify mirror)
			)
		)
		(property "Voltage" "50V"
			(at 81.5 345.5 0)
			(layer "B.Fab")
			(hide yes)
			(effects
				(font
					(size 1 1)
					(thickness 0.15)
				)
				(justify mirror)
			)
		)
		(sheetname "FPGA Bank 14 & 15")
		(sheetfile "fpga-bank-14-15.kicad_sch")
		(attr smd)
		(fp_rect
			(start -0.925 0.47)
			(end 0.925 -0.47)
			(stroke
				(width 0.05)
				(type default)
			)
			(fill no)
			(layer "B.CrtYd")
		)
		(fp_line
			(start -0.494 0.25)
			(end 0.504 0.25)
			(stroke
				(width 0.15)
				(type solid)
			)
			(layer "B.Fab")
		)
		(fp_line
			(start 0.504 0.25)
			(end 0.504 -0.248)
			(stroke
				(width 0.15)
				(type solid)
			)
			(layer "B.Fab")
		)
		(fp_line
			(start -0.494 -0.248)
			(end -0.494 0.25)
			(stroke
				(width 0.15)
				(type solid)
			)
			(layer "B.Fab")
		)
		(fp_line
			(start 0.504 -0.248)
			(end -0.494 -0.248)
			(stroke
				(width 0.15)
				(type solid)
			)
			(layer "B.Fab")
		)
		(pad "1" smd roundrect
			(at -0.48 0 270)
			(size 0.59 0.64)
			(layers "B.Cu" "B.Mask" "B.Paste")
			(roundrect_rratio 0.25)
			(net 1 "GND")
			(pintype "passive")
		)
		(pad "2" smd roundrect
			(at 0.48 0 270)
			(size 0.59 0.64)
			(layers "B.Cu" "B.Mask" "B.Paste")
			(roundrect_rratio 0.25)
			(net 24 "+3V3")
			(pintype "passive")
		)
	)
	(footprint "antmicro-footprints:R_0402_1005Metric"
		(layer "B.Cu")
		(at 204.101 74.233 90)
		(descr "Resistor SMD 0402")
		(tags "resistor SMD 0402")
		(property "Reference" "R2"
			(at -0.767 0.424 270)
			(layer "B.SilkS")
			(effects
				(font
					(size 0.7 0.7)
					(thickness 0.15)
				)
				(justify left bottom mirror)
			)
		)
		(property "Value" "R_10k_0402"
			(at 0 -1.4 270)
			(layer "B.Fab")
			(effects
				(font
					(size 0.7 0.7)
					(thickness 0.15)
				)
				(justify left bottom mirror)
			)
		)
		(property "Description" "SMD Chip Resistor, 10 kohm, ± 1%, 62.5 mW, 0402 [1005 Metric], Thick Film, General Purpose"
			(at 0 0 90)
			(layer "F.Fab")
			(hide yes)
			(effects
				(font
					(size 1.27 1.27)
					(thickness 0.15)
				)
			)
		)
		(property "Author" "Antmicro"
			(at 278.334 -129.868 0)
			(layer "B.Fab")
			(hide yes)
			(effects
				(font
					(size 1 1)
					(thickness 0.15)
				)
				(justify mirror)
			)
		)
		(property "DNP" "DNP"
			(at 278.334 -129.868 0)
			(layer "B.Fab")
			(hide yes)
			(effects
				(font
					(size 1 1)
					(thickness 0.15)
				)
				(justify mirror)
			)
		)
		(property "License" "Apache-2.0"
			(at 278.334 -129.868 0)
			(layer "B.Fab")
			(hide yes)
			(effects
				(font
					(size 1 1)
					(thickness 0.15)
				)
				(justify mirror)
			)
		)
		(property "MPN" "CR0402-FX-1002GLF"
			(at 278.334 -129.868 0)
			(layer "B.Fab")
			(hide yes)
			(effects
				(font
					(size 1 1)
					(thickness 0.15)
				)
				(justify mirror)
			)
		)
		(property "Manufacturer" "Bourns"
			(at 278.334 -129.868 0)
			(layer "B.Fab")
			(hide yes)
			(effects
				(font
					(size 1 1)
					(thickness 0.15)
				)
				(justify mirror)
			)
		)
		(property "Tolerance" "1%"
			(at 278.334 -129.868 0)
			(layer "B.Fab")
			(hide yes)
			(effects
				(font
					(size 1 1)
					(thickness 0.15)
				)
				(justify mirror)
			)
		)
		(property "Val" "10k"
			(at 278.334 -129.868 0)
			(layer "B.Fab")
			(hide yes)
			(effects
				(font
					(size 1 1)
					(thickness 0.15)
				)
				(justify mirror)
			)
		)
		(property "dnp" ""
			(at 278.334 -129.868 0)
			(layer "B.Fab")
			(hide yes)
			(effects
				(font
					(size 1 1)
					(thickness 0.15)
				)
				(justify mirror)
			)
		)
		(property "exclude_from_bom" ""
			(at 278.334 -129.868 0)
			(layer "B.Fab")
			(hide yes)
			(effects
				(font
					(size 1 1)
					(thickness 0.15)
				)
				(justify mirror)
			)
		)
		(sheetname "FPGA Config")
		(sheetfile "fpga-config.kicad_sch")
		(attr smd exclude_from_bom)
		(fp_rect
			(start -0.925 0.47)
			(end 0.925 -0.47)
			(stroke
				(width 0.05)
				(type default)
			)
			(fill no)
			(layer "B.CrtYd")
		)
		(fp_rect
			(start -0.5 0.25)
			(end 0.5 -0.25)
			(stroke
				(width 0.15)
				(type solid)
			)
			(fill no)
			(layer "B.Fab")
		)
		(pad "1" smd roundrect
			(at -0.48 0 90)
			(size 0.59 0.64)
			(layers "B.Cu" "B.Mask" "B.Paste")
			(roundrect_rratio 0.25)
			(net 298 "/FPGA Config/MODE2")
			(pintype "passive")
		)
		(pad "2" smd roundrect
			(at 0.48 0 90)
			(size 0.59 0.64)
			(layers "B.Cu" "B.Mask" "B.Paste")
			(roundrect_rratio 0.25)
			(net 24 "+3V3")
			(pintype "passive")
		)
	)
	(footprint "antmicro-footprints:C_0402_1005Metric"
		(layer "B.Cu")
		(at 192.5 135)
		(descr "Capacitor SMD 0402")
		(tags "capacitor SMD 0402")
		(property "Reference" "C101"
			(at 22.925 -28.075 180)
			(layer "B.SilkS")
			(effects
				(font
					(size 0.7 0.7)
					(thickness 0.15)
				)
				(justify left bottom mirror)
			)
		)
		(property "Value" "C_100n_0402"
			(at 0 -1.169 180)
			(layer "B.Fab")
			(effects
				(font
					(size 0.7 0.7)
					(thickness 0.15)
				)
				(justify left bottom mirror)
			)
		)
		(property "Description" "SMD Multilayer Ceramic Capacitor, 0.1 µF, 50 V, 0402 [1005 Metric], ± 10%, X5R, GRM Series"
			(at 0 0 0)
			(layer "F.Fab")
			(hide yes)
			(effects
				(font
					(size 1.27 1.27)
					(thickness 0.15)
				)
			)
		)
		(property "Author" "Antmicro"
			(at 0 0 0)
			(layer "B.Fab")
			(hide yes)
			(effects
				(font
					(size 1 1)
					(thickness 0.15)
				)
				(justify mirror)
			)
		)
		(property "Dielectric" "X5R"
			(at 0 0 0)
			(layer "B.Fab")
			(hide yes)
			(effects
				(font
					(size 1 1)
					(thickness 0.15)
				)
				(justify mirror)
			)
		)
		(property "License" "Apache-2.0"
			(at 0 0 0)
			(layer "B.Fab")
			(hide yes)
			(effects
				(font
					(size 1 1)
					(thickness 0.15)
				)
				(justify mirror)
			)
		)
		(property "MPN" "GRM155R61H104KE14D"
			(at 0 0 0)
			(layer "B.Fab")
			(hide yes)
			(effects
				(font
					(size 1 1)
					(thickness 0.15)
				)
				(justify mirror)
			)
		)
		(property "Manufacturer" "Murata"
			(at 0 0 0)
			(layer "B.Fab")
			(hide yes)
			(effects
				(font
					(size 1 1)
					(thickness 0.15)
				)
				(justify mirror)
			)
		)
		(property "Val" "100n"
			(at 0 0 0)
			(layer "B.Fab")
			(hide yes)
			(effects
				(font
					(size 1 1)
					(thickness 0.15)
				)
				(justify mirror)
			)
		)
		(property "Voltage" "50V"
			(at 0 0 0)
			(layer "B.Fab")
			(hide yes)
			(effects
				(font
					(size 1 1)
					(thickness 0.15)
				)
				(justify mirror)
			)
		)
		(sheetname "FPGA Bank 33 & 34")
		(sheetfile "fpga-bank-33-34.kicad_sch")
		(attr smd)
		(fp_rect
			(start -0.925 0.47)
			(end 0.925 -0.47)
			(stroke
				(width 0.05)
				(type default)
			)
			(fill no)
			(layer "B.CrtYd")
		)
		(fp_line
			(start -0.494 -0.248)
			(end -0.494 0.25)
			(stroke
				(width 0.15)
				(type solid)
			)
			(layer "B.Fab")
		)
		(fp_line
			(start -0.494 0.25)
			(end 0.504 0.25)
			(stroke
				(width 0.15)
				(type solid)
			)
			(layer "B.Fab")
		)
		(fp_line
			(start 0.504 -0.248)
			(end -0.494 -0.248)
			(stroke
				(width 0.15)
				(type solid)
			)
			(layer "B.Fab")
		)
		(fp_line
			(start 0.504 0.25)
			(end 0.504 -0.248)
			(stroke
				(width 0.15)
				(type solid)
			)
			(layer "B.Fab")
		)
		(pad "1" smd roundrect
			(at -0.48 0)
			(size 0.59 0.64)
			(layers "B.Cu" "B.Mask" "B.Paste")
			(roundrect_rratio 0.25)
			(net 1 "GND")
			(pintype "passive")
		)
		(pad "2" smd roundrect
			(at 0.48 0)
			(size 0.59 0.64)
			(layers "B.Cu" "B.Mask" "B.Paste")
			(roundrect_rratio 0.25)
			(net 26 "+1V8")
			(pintype "passive")
		)
	)
	(footprint "antmicro-footprints:C_0402_1005Metric"
		(layer "B.Cu")
		(at 259.851 124.55 180)
		(descr "Capacitor SMD 0402")
		(tags "capacitor SMD 0402")
		(property "Reference" "C401"
			(at -1.349 -1.225 0)
			(layer "B.SilkS")
			(effects
				(font
					(size 0.7 0.7)
					(thickness 0.15)
				)
				(justify left bottom mirror)
			)
		)
		(property "Value" "C_100n_0402"
			(at 0 -1.169 0)
			(layer "B.Fab")
			(effects
				(font
					(size 0.7 0.7)
					(thickness 0.15)
				)
				(justify left bottom mirror)
			)
		)
		(property "Description" "SMD Multilayer Ceramic Capacitor, 0.1 µF, 50 V, 0402 [1005 Metric], ± 10%, X5R, GRM Series"
			(at 0 0 180)
			(layer "F.Fab")
			(hide yes)
			(effects
				(font
					(size 1.27 1.27)
					(thickness 0.15)
				)
			)
		)
		(property "Author" "Antmicro"
			(at 519.702 249.1 0)
			(layer "B.Fab")
			(hide yes)
			(effects
				(font
					(size 1 1)
					(thickness 0.15)
				)
				(justify mirror)
			)
		)
		(property "Dielectric" "X5R"
			(at 519.702 249.1 0)
			(layer "B.Fab")
			(hide yes)
			(effects
				(font
					(size 1 1)
					(thickness 0.15)
				)
				(justify mirror)
			)
		)
		(property "License" "Apache-2.0"
			(at 519.702 249.1 0)
			(layer "B.Fab")
			(hide yes)
			(effects
				(font
					(size 1 1)
					(thickness 0.15)
				)
				(justify mirror)
			)
		)
		(property "MPN" "GRM155R61H104KE14D"
			(at 519.702 249.1 0)
			(layer "B.Fab")
			(hide yes)
			(effects
				(font
					(size 1 1)
					(thickness 0.15)
				)
				(justify mirror)
			)
		)
		(property "Manufacturer" "Murata"
			(at 519.702 249.1 0)
			(layer "B.Fab")
			(hide yes)
			(effects
				(font
					(size 1 1)
					(thickness 0.15)
				)
				(justify mirror)
			)
		)
		(property "Val" "100n"
			(at 519.702 249.1 0)
			(layer "B.Fab")
			(hide yes)
			(effects
				(font
					(size 1 1)
					(thickness 0.15)
				)
				(justify mirror)
			)
		)
		(property "Voltage" "50V"
			(at 519.702 249.1 0)
			(layer "B.Fab")
			(hide yes)
			(effects
				(font
					(size 1 1)
					(thickness 0.15)
				)
				(justify mirror)
			)
		)
		(sheetname "USB PHY")
		(sheetfile "usb-phy.kicad_sch")
		(attr smd)
		(fp_rect
			(start -0.925 0.47)
			(end 0.925 -0.47)
			(stroke
				(width 0.05)
				(type default)
			)
			(fill no)
			(layer "B.CrtYd")
		)
		(fp_line
			(start 0.504 0.25)
			(end 0.504 -0.248)
			(stroke
				(width 0.15)
				(type solid)
			)
			(layer "B.Fab")
		)
		(fp_line
			(start 0.504 -0.248)
			(end -0.494 -0.248)
			(stroke
				(width 0.15)
				(type solid)
			)
			(layer "B.Fab")
		)
		(fp_line
			(start -0.494 0.25)
			(end 0.504 0.25)
			(stroke
				(width 0.15)
				(type solid)
			)
			(layer "B.Fab")
		)
		(fp_line
			(start -0.494 -0.248)
			(end -0.494 0.25)
			(stroke
				(width 0.15)
				(type solid)
			)
			(layer "B.Fab")
		)
		(pad "1" smd roundrect
			(at -0.48 0 180)
			(size 0.59 0.64)
			(layers "B.Cu" "B.Mask" "B.Paste")
			(roundrect_rratio 0.25)
			(net 1 "GND")
			(pintype "passive")
		)
		(pad "2" smd roundrect
			(at 0.48 0 180)
			(size 0.59 0.64)
			(layers "B.Cu" "B.Mask" "B.Paste")
			(roundrect_rratio 0.25)
			(net 707 "/USB PHY/FTDI_3V3")
			(pintype "passive")
		)
	)
	(footprint "antmicro-footprints:R_0402_1005Metric"
		(layer "B.Cu")
		(at 261.5 93.4)
		(descr "Resistor SMD 0402")
		(tags "resistor SMD 0402")
		(property "Reference" "R128"
			(at 1.325 1.25 180)
			(layer "B.SilkS")
			(effects
				(font
					(size 0.7 0.7)
					(thickness 0.15)
				)
				(justify left bottom mirror)
			)
		)
		(property "Value" "R_1k_0402"
			(at 0 -1.4 180)
			(layer "B.Fab")
			(effects
				(font
					(size 0.7 0.7)
					(thickness 0.15)
				)
				(justify left bottom mirror)
			)
		)
		(property "Description" "SMD Chip Resistor, 1 kohm, ± 1%, 63 mW, 0402 [1005 Metric], Thick Film, General Purpose"
			(at 0 0 0)
			(layer "F.Fab")
			(hide yes)
			(effects
				(font
					(size 1.27 1.27)
					(thickness 0.15)
				)
			)
		)
		(property "Author" "Antmicro"
			(at 0 0 0)
			(layer "B.Fab")
			(hide yes)
			(effects
				(font
					(size 1 1)
					(thickness 0.15)
				)
				(justify mirror)
			)
		)
		(property "License" "Apache-2.0"
			(at 0 0 0)
			(layer "B.Fab")
			(hide yes)
			(effects
				(font
					(size 1 1)
					(thickness 0.15)
				)
				(justify mirror)
			)
		)
		(property "MPN" "CR0402-FX-1001GLF"
			(at 0 0 0)
			(layer "B.Fab")
			(hide yes)
			(effects
				(font
					(size 1 1)
					(thickness 0.15)
				)
				(justify mirror)
			)
		)
		(property "Manufacturer" "Bourns"
			(at 0 0 0)
			(layer "B.Fab")
			(hide yes)
			(effects
				(font
					(size 1 1)
					(thickness 0.15)
				)
				(justify mirror)
			)
		)
		(property "Tolerance" "1%"
			(at 0 0 0)
			(layer "B.Fab")
			(hide yes)
			(effects
				(font
					(size 1 1)
					(thickness 0.15)
				)
				(justify mirror)
			)
		)
		(property "Val" "1k"
			(at 0 0 0)
			(layer "B.Fab")
			(hide yes)
			(effects
				(font
					(size 1 1)
					(thickness 0.15)
				)
				(justify mirror)
			)
		)
		(sheetname "User GPIO + LED + button + DIP switch")
		(sheetfile "user-gpio.kicad_sch")
		(attr smd)
		(fp_rect
			(start -0.925 0.47)
			(end 0.925 -0.47)
			(stroke
				(width 0.05)
				(type default)
			)
			(fill no)
			(layer "B.CrtYd")
		)
		(fp_rect
			(start -0.5 0.25)
			(end 0.5 -0.25)
			(stroke
				(width 0.15)
				(type solid)
			)
			(fill no)
			(layer "B.Fab")
		)
		(pad "1" smd roundrect
			(at -0.48 0)
			(size 0.59 0.64)
			(layers "B.Cu" "B.Mask" "B.Paste")
			(roundrect_rratio 0.25)
			(net 24 "+3V3")
			(pintype "passive")
		)
		(pad "2" smd roundrect
			(at 0.48 0)
			(size 0.59 0.64)
			(layers "B.Cu" "B.Mask" "B.Paste")
			(roundrect_rratio 0.25)
			(net 783 "Net-(D22-A)")
			(pintype "passive")
		)
	)
	(footprint "antmicro-footprints:C_0402_1005Metric"
		(layer "B.Cu")
		(at 201.5 141 90)
		(descr "Capacitor SMD 0402")
		(tags "capacitor SMD 0402")
		(property "Reference" "C83"
			(at 1.15 1.275 270)
			(layer "B.SilkS")
			(effects
				(font
					(size 0.7 0.7)
					(thickness 0.15)
				)
				(justify left bottom mirror)
			)
		)
		(property "Value" "C_100n_0402"
			(at 0 -1.169 270)
			(layer "B.Fab")
			(effects
				(font
					(size 0.7 0.7)
					(thickness 0.15)
				)
				(justify left bottom mirror)
			)
		)
		(property "Description" "SMD Multilayer Ceramic Capacitor, 0.1 µF, 50 V, 0402 [1005 Metric], ± 10%, X5R, GRM Series"
			(at 0 0 90)
			(layer "F.Fab")
			(hide yes)
			(effects
				(font
					(size 1.27 1.27)
					(thickness 0.15)
				)
			)
		)
		(property "Author" "Antmicro"
			(at 342.5 -60.5 0)
			(layer "B.Fab")
			(hide yes)
			(effects
				(font
					(size 1 1)
					(thickness 0.15)
				)
				(justify mirror)
			)
		)
		(property "Dielectric" "X5R"
			(at 342.5 -60.5 0)
			(layer "B.Fab")
			(hide yes)
			(effects
				(font
					(size 1 1)
					(thickness 0.15)
				)
				(justify mirror)
			)
		)
		(property "License" "Apache-2.0"
			(at 342.5 -60.5 0)
			(layer "B.Fab")
			(hide yes)
			(effects
				(font
					(size 1 1)
					(thickness 0.15)
				)
				(justify mirror)
			)
		)
		(property "MPN" "GRM155R61H104KE14D"
			(at 342.5 -60.5 0)
			(layer "B.Fab")
			(hide yes)
			(effects
				(font
					(size 1 1)
					(thickness 0.15)
				)
				(justify mirror)
			)
		)
		(property "Manufacturer" "Murata"
			(at 342.5 -60.5 0)
			(layer "B.Fab")
			(hide yes)
			(effects
				(font
					(size 1 1)
					(thickness 0.15)
				)
				(justify mirror)
			)
		)
		(property "Val" "100n"
			(at 342.5 -60.5 0)
			(layer "B.Fab")
			(hide yes)
			(effects
				(font
					(size 1 1)
					(thickness 0.15)
				)
				(justify mirror)
			)
		)
		(property "Voltage" "50V"
			(at 342.5 -60.5 0)
			(layer "B.Fab")
			(hide yes)
			(effects
				(font
					(size 1 1)
					(thickness 0.15)
				)
				(justify mirror)
			)
		)
		(sheetname "FPGA Bank 18 & 32")
		(sheetfile "fpga-bank-18-32.kicad_sch")
		(attr smd)
		(fp_rect
			(start -0.925 0.47)
			(end 0.925 -0.47)
			(stroke
				(width 0.05)
				(type default)
			)
			(fill no)
			(layer "B.CrtYd")
		)
		(fp_line
			(start 0.504 -0.248)
			(end -0.494 -0.248)
			(stroke
				(width 0.15)
				(type solid)
			)
			(layer "B.Fab")
		)
		(fp_line
			(start -0.494 -0.248)
			(end -0.494 0.25)
			(stroke
				(width 0.15)
				(type solid)
			)
			(layer "B.Fab")
		)
		(fp_line
			(start 0.504 0.25)
			(end 0.504 -0.248)
			(stroke
				(width 0.15)
				(type solid)
			)
			(layer "B.Fab")
		)
		(fp_line
			(start -0.494 0.25)
			(end 0.504 0.25)
			(stroke
				(width 0.15)
				(type solid)
			)
			(layer "B.Fab")
		)
		(pad "1" smd roundrect
			(at -0.48 0 90)
			(size 0.59 0.64)
			(layers "B.Cu" "B.Mask" "B.Paste")
			(roundrect_rratio 0.25)
			(net 1 "GND")
			(pintype "passive")
		)
		(pad "2" smd roundrect
			(at 0.48 0 90)
			(size 0.59 0.64)
			(layers "B.Cu" "B.Mask" "B.Paste")
			(roundrect_rratio 0.25)
			(net 26 "+1V8")
			(pintype "passive")
		)
	)
	(footprint "antmicro-footprints:R_0402_1005Metric"
		(layer "B.Cu")
		(at 190.6 79.8 90)
		(descr "Resistor SMD 0402")
		(tags "resistor SMD 0402")
		(property "Reference" "R145"
			(at -0.725 0.4 270)
			(layer "B.SilkS")
			(effects
				(font
					(size 0.7 0.7)
					(thickness 0.15)
				)
				(justify left bottom mirror)
			)
		)
		(property "Value" "R_100R_0402"
			(at 0 -1.4 270)
			(layer "B.Fab")
			(effects
				(font
					(size 0.7 0.7)
					(thickness 0.15)
				)
				(justify left bottom mirror)
			)
		)
		(property "Description" "SMD Chip Resistor, 100 ohm, ± 1%, 62.5 mW, 0402 [1005 Metric], Thick Film, General Purpose"
			(at 0 0 90)
			(layer "F.Fab")
			(hide yes)
			(effects
				(font
					(size 1.27 1.27)
					(thickness 0.15)
				)
			)
		)
		(property "Author" "Antmicro"
			(at 270.4 -110.8 0)
			(layer "B.Fab")
			(hide yes)
			(effects
				(font
					(size 1 1)
					(thickness 0.15)
				)
				(justify mirror)
			)
		)
		(property "License" "Apache-2.0"
			(at 270.4 -110.8 0)
			(layer "B.Fab")
			(hide yes)
			(effects
				(font
					(size 1 1)
					(thickness 0.15)
				)
				(justify mirror)
			)
		)
		(property "MPN" "CR0402-FX-1000GLF"
			(at 270.4 -110.8 0)
			(layer "B.Fab")
			(hide yes)
			(effects
				(font
					(size 1 1)
					(thickness 0.15)
				)
				(justify mirror)
			)
		)
		(property "Manufacturer" "Bourns"
			(at 270.4 -110.8 0)
			(layer "B.Fab")
			(hide yes)
			(effects
				(font
					(size 1 1)
					(thickness 0.15)
				)
				(justify mirror)
			)
		)
		(property "Tolerance" "1%"
			(at 270.4 -110.8 0)
			(layer "B.Fab")
			(hide yes)
			(effects
				(font
					(size 1 1)
					(thickness 0.15)
				)
				(justify mirror)
			)
		)
		(property "Val" "100R"
			(at 270.4 -110.8 0)
			(layer "B.Fab")
			(hide yes)
			(effects
				(font
					(size 1 1)
					(thickness 0.15)
				)
				(justify mirror)
			)
		)
		(sheetname "User GPIO + LED + button + DIP switch")
		(sheetfile "user-gpio.kicad_sch")
		(attr smd)
		(fp_rect
			(start -0.925 0.47)
			(end 0.925 -0.47)
			(stroke
				(width 0.05)
				(type default)
			)
			(fill no)
			(layer "B.CrtYd")
		)
		(fp_rect
			(start -0.5 0.25)
			(end 0.5 -0.25)
			(stroke
				(width 0.15)
				(type solid)
			)
			(fill no)
			(layer "B.Fab")
		)
		(pad "1" smd roundrect
			(at -0.48 0 90)
			(size 0.59 0.64)
			(layers "B.Cu" "B.Mask" "B.Paste")
			(roundrect_rratio 0.25)
			(net 491 "/FPGA Bank 12 & 13/CW_HEADER.IO2")
			(pintype "passive")
		)
		(pad "2" smd roundrect
			(at 0.48 0 90)
			(size 0.59 0.64)
			(layers "B.Cu" "B.Mask" "B.Paste")
			(roundrect_rratio 0.25)
			(net 829 "/User GPIO + LED + button + DIP switch/CW_20PIN_IO2")
			(pintype "passive")
		)
	)
	(footprint "antmicro-footprints:R_0402_1005Metric"
		(layer "B.Cu")
		(at 164.0625 168.6 -90)
		(descr "Resistor SMD 0402")
		(tags "resistor SMD 0402")
		(property "Reference" "R299"
			(at 0.75 -0.3875 90)
			(layer "B.SilkS")
			(effects
				(font
					(size 0.7 0.7)
					(thickness 0.15)
				)
				(justify left bottom mirror)
			)
		)
		(property "Value" "R_0R_0402"
			(at 0 -1.4 90)
			(layer "B.Fab")
			(effects
				(font
					(size 0.7 0.7)
					(thickness 0.15)
				)
				(justify left bottom mirror)
			)
		)
		(property "Description" "SMD Chip Resistor, Jumper, 0 ohm, 100 mW, 0402 [1005 Metric], Thick Film, General Purpose"
			(at 0 0 270)
			(layer "F.Fab")
			(hide yes)
			(effects
				(font
					(size 1.27 1.27)
					(thickness 0.15)
				)
			)
		)
		(property "Author" "Antmicro"
			(at -4.5375 332.6625 0)
			(layer "B.Fab")
			(hide yes)
			(effects
				(font
					(size 1 1)
					(thickness 0.15)
				)
				(justify mirror)
			)
		)
		(property "Current" "1A"
			(at -4.5375 332.6625 0)
			(layer "B.Fab")
			(hide yes)
			(effects
				(font
					(size 1 1)
					(thickness 0.15)
				)
				(justify mirror)
			)
		)
		(property "DNP" "DNP"
			(at -4.5375 332.6625 0)
			(layer "B.Fab")
			(hide yes)
			(effects
				(font
					(size 1 1)
					(thickness 0.15)
				)
				(justify mirror)
			)
		)
		(property "License" "Apache-2.0"
			(at -4.5375 332.6625 0)
			(layer "B.Fab")
			(hide yes)
			(effects
				(font
					(size 1 1)
					(thickness 0.15)
				)
				(justify mirror)
			)
		)
		(property "MPN" "ERJ2GE0R00X"
			(at -4.5375 332.6625 0)
			(layer "B.Fab")
			(hide yes)
			(effects
				(font
					(size 1 1)
					(thickness 0.15)
				)
				(justify mirror)
			)
		)
		(property "Manufacturer" "Panasonic"
			(at -4.5375 332.6625 0)
			(layer "B.Fab")
			(hide yes)
			(effects
				(font
					(size 1 1)
					(thickness 0.15)
				)
				(justify mirror)
			)
		)
		(property "Tolerance" ""
			(at -4.5375 332.6625 0)
			(layer "B.Fab")
			(hide yes)
			(effects
				(font
					(size 1 1)
					(thickness 0.15)
				)
				(justify mirror)
			)
		)
		(property "Val" "0R"
			(at -4.5375 332.6625 0)
			(layer "B.Fab")
			(hide yes)
			(effects
				(font
					(size 1 1)
					(thickness 0.15)
				)
				(justify mirror)
			)
		)
		(property "dnp" ""
			(at -4.5375 332.6625 0)
			(layer "B.Fab")
			(hide yes)
			(effects
				(font
					(size 1 1)
					(thickness 0.15)
				)
				(justify mirror)
			)
		)
		(property "exclude_from_bom" ""
			(at -4.5375 332.6625 0)
			(layer "B.Fab")
			(hide yes)
			(effects
				(font
					(size 1 1)
					(thickness 0.15)
				)
				(justify mirror)
			)
		)
		(sheetname "DC-DC Converters")
		(sheetfile "dc-dc.kicad_sch")
		(attr smd exclude_from_bom)
		(fp_rect
			(start -0.925 0.47)
			(end 0.925 -0.47)
			(stroke
				(width 0.05)
				(type default)
			)
			(fill no)
			(layer "B.CrtYd")
		)
		(fp_rect
			(start -0.5 0.25)
			(end 0.5 -0.25)
			(stroke
				(width 0.15)
				(type solid)
			)
			(fill no)
			(layer "B.Fab")
		)
		(pad "1" smd roundrect
			(at -0.48 0 270)
			(size 0.59 0.64)
			(layers "B.Cu" "B.Mask" "B.Paste")
			(roundrect_rratio 0.25)
			(net 1223 "/DC-DC Converters/SENSE_1V8_N")
			(pintype "passive")
		)
		(pad "2" smd roundrect
			(at 0.48 0 270)
			(size 0.59 0.64)
			(layers "B.Cu" "B.Mask" "B.Paste")
			(roundrect_rratio 0.25)
			(net 960 "/DC-DC Converters/FB2")
			(pintype "passive")
		)
	)
	(footprint "antmicro-footprints:NetTie-2_SMD_Pad0.127mm"
		(layer "B.Cu")
		(at 207.860001 147.257 -90)
		(descr "Net tie, 2 pin, 0.127mm  SMD pads")
		(tags "net tie")
		(property "Reference" "NT29"
			(at -0.128 1.345 90)
			(layer "B.SilkS")
			(hide yes)
			(effects
				(font
					(size 0.7 0.7)
					(thickness 0.15)
				)
				(justify left bottom mirror)
			)
		)
		(property "Value" "Net-Tie_2"
			(at 0 -1.199 90)
			(layer "B.Fab")
			(effects
				(font
					(size 0.7 0.7)
					(thickness 0.15)
				)
				(justify left bottom mirror)
			)
		)
		(property "Description" "Net tie, 2 pins"
			(at 0 0 270)
			(layer "F.Fab")
			(hide yes)
			(effects
				(font
					(size 1.27 1.27)
					(thickness 0.15)
				)
			)
		)
		(property "Author" "Antmicro"
			(at 60.603001 355.117001 0)
			(layer "B.Fab")
			(hide yes)
			(effects
				(font
					(size 1 1)
					(thickness 0.15)
				)
				(justify mirror)
			)
		)
		(property "License" "Apache-2.0"
			(at 60.603001 355.117001 0)
			(layer "B.Fab")
			(hide yes)
			(effects
				(font
					(size 1 1)
					(thickness 0.15)
				)
				(justify mirror)
			)
		)
		(property "MPN" ""
			(at 60.603001 355.117001 0)
			(layer "B.Fab")
			(hide yes)
			(effects
				(font
					(size 1 1)
					(thickness 0.15)
				)
				(justify mirror)
			)
		)
		(property "Manufacturer" ""
			(at 60.603001 355.117001 0)
			(layer "B.Fab")
			(hide yes)
			(effects
				(font
					(size 1 1)
					(thickness 0.15)
				)
				(justify mirror)
			)
		)
		(sheetname "DC-DC Converters")
		(sheetfile "dc-dc.kicad_sch")
		(attr exclude_from_pos_files)
		(net_tie_pad_groups "1, 2")
		(fp_poly
			(pts
				(xy -0.0635 0.0635) (xy 0.0625 0.0635) (xy 0.0625 -0.0635) (xy -0.0635 -0.0635)
			)
			(stroke
				(width 0)
				(type solid)
			)
			(fill yes)
			(layer "B.Cu")
		)
		(pad "1" smd roundrect
			(at -0.127 0 90)
			(size 0.127 0.127)
			(layers "B.Cu")
			(roundrect_rratio 0.5)
			(chamfer_ratio 0)
			(chamfer top_left bottom_left)
			(net 1 "GND")
			(pinfunction "1")
			(pintype "passive")
		)
		(pad "2" smd roundrect
			(at 0.126 0 270)
			(size 0.127 0.127)
			(layers "B.Cu")
			(roundrect_rratio 0.5)
			(chamfer_ratio 0)
			(chamfer top_left bottom_left)
			(net 1217 "/DC-DC Converters/SENSE_3V3_1_N")
			(pinfunction "2")
			(pintype "passive")
		)
	)
	(footprint "antmicro-footprints:R_0402_1005Metric"
		(layer "B.Cu")
		(at 175.424999 147.999999 -90)
		(descr "Resistor SMD 0402")
		(tags "resistor SMD 0402")
		(property "Reference" "R40"
			(at 0.775001 -0.425001 90)
			(layer "B.SilkS")
			(effects
				(font
					(size 0.7 0.7)
					(thickness 0.15)
				)
				(justify left bottom mirror)
			)
		)
		(property "Value" "R_40R2_0402"
			(at 0 -1.4 90)
			(layer "B.Fab")
			(effects
				(font
					(size 0.7 0.7)
					(thickness 0.15)
				)
				(justify left bottom mirror)
			)
		)
		(property "Description" "SMD Chip Resistor, Ceramic, 40.2 ohm, ± 1%, 62.5 mW, 0402 [1005 Metric], Thick Film"
			(at 0 0 270)
			(layer "F.Fab")
			(hide yes)
			(effects
				(font
					(size 1.27 1.27)
					(thickness 0.15)
				)
			)
		)
		(property "Author" "Antmicro"
			(at 27.425 323.424998 0)
			(layer "B.Fab")
			(hide yes)
			(effects
				(font
					(size 1 1)
					(thickness 0.15)
				)
				(justify mirror)
			)
		)
		(property "License" "Apache-2.0"
			(at 27.425 323.424998 0)
			(layer "B.Fab")
			(hide yes)
			(effects
				(font
					(size 1 1)
					(thickness 0.15)
				)
				(justify mirror)
			)
		)
		(property "MPN" "CR0402-FX-40R2GLF"
			(at 27.425 323.424998 0)
			(layer "B.Fab")
			(hide yes)
			(effects
				(font
					(size 1 1)
					(thickness 0.15)
				)
				(justify mirror)
			)
		)
		(property "Manufacturer" "Bourns"
			(at 27.425 323.424998 0)
			(layer "B.Fab")
			(hide yes)
			(effects
				(font
					(size 1 1)
					(thickness 0.15)
				)
				(justify mirror)
			)
		)
		(property "Tolerance" "1%"
			(at 27.425 323.424998 0)
			(layer "B.Fab")
			(hide yes)
			(effects
				(font
					(size 1 1)
					(thickness 0.15)
				)
				(justify mirror)
			)
		)
		(property "Val" "40R2"
			(at 27.425 323.424998 0)
			(layer "B.Fab")
			(hide yes)
			(effects
				(font
					(size 1 1)
					(thickness 0.15)
				)
				(justify mirror)
			)
		)
		(sheetname "DRAM + SRAM")
		(sheetfile "ram.kicad_sch")
		(attr smd)
		(fp_rect
			(start -0.925 0.47)
			(end 0.925 -0.47)
			(stroke
				(width 0.05)
				(type default)
			)
			(fill no)
			(layer "B.CrtYd")
		)
		(fp_rect
			(start -0.5 0.25)
			(end 0.5 -0.25)
			(stroke
				(width 0.15)
				(type solid)
			)
			(fill no)
			(layer "B.Fab")
		)
		(pad "1" smd roundrect
			(at -0.48 0 270)
			(size 0.59 0.64)
			(layers "B.Cu" "B.Mask" "B.Paste")
			(roundrect_rratio 0.25)
			(net 557 "/DRAM + SRAM/DDR.DM")
			(pintype "passive")
		)
		(pad "2" smd roundrect
			(at 0.48 0 270)
			(size 0.59 0.64)
			(layers "B.Cu" "B.Mask" "B.Paste")
			(roundrect_rratio 0.25)
			(net 7 "+0V675_VTT")
			(pintype "passive")
		)
	)
	(footprint "antmicro-footprints:R_0402_1005Metric"
		(layer "B.Cu")
		(at 154.3125 169.2 -90)
		(descr "Resistor SMD 0402")
		(tags "resistor SMD 0402")
		(property "Reference" "R297"
			(at 0.7 -0.3875 90)
			(layer "B.SilkS")
			(effects
				(font
					(size 0.7 0.7)
					(thickness 0.15)
				)
				(justify left bottom mirror)
			)
		)
		(property "Value" "R_0R_0402"
			(at 0 -1.4 90)
			(layer "B.Fab")
			(effects
				(font
					(size 0.7 0.7)
					(thickness 0.15)
				)
				(justify left bottom mirror)
			)
		)
		(property "Description" "SMD Chip Resistor, Jumper, 0 ohm, 100 mW, 0402 [1005 Metric], Thick Film, General Purpose"
			(at 0 0 270)
			(layer "F.Fab")
			(hide yes)
			(effects
				(font
					(size 1.27 1.27)
					(thickness 0.15)
				)
			)
		)
		(property "Author" "Antmicro"
			(at -14.8875 323.5125 0)
			(layer "B.Fab")
			(hide yes)
			(effects
				(font
					(size 1 1)
					(thickness 0.15)
				)
				(justify mirror)
			)
		)
		(property "Current" "1A"
			(at -14.8875 323.5125 0)
			(layer "B.Fab")
			(hide yes)
			(effects
				(font
					(size 1 1)
					(thickness 0.15)
				)
				(justify mirror)
			)
		)
		(property "DNP" "DNP"
			(at -14.8875 323.5125 0)
			(layer "B.Fab")
			(hide yes)
			(effects
				(font
					(size 1 1)
					(thickness 0.15)
				)
				(justify mirror)
			)
		)
		(property "License" "Apache-2.0"
			(at -14.8875 323.5125 0)
			(layer "B.Fab")
			(hide yes)
			(effects
				(font
					(size 1 1)
					(thickness 0.15)
				)
				(justify mirror)
			)
		)
		(property "MPN" "ERJ2GE0R00X"
			(at -14.8875 323.5125 0)
			(layer "B.Fab")
			(hide yes)
			(effects
				(font
					(size 1 1)
					(thickness 0.15)
				)
				(justify mirror)
			)
		)
		(property "Manufacturer" "Panasonic"
			(at -14.8875 323.5125 0)
			(layer "B.Fab")
			(hide yes)
			(effects
				(font
					(size 1 1)
					(thickness 0.15)
				)
				(justify mirror)
			)
		)
		(property "Tolerance" ""
			(at -14.8875 323.5125 0)
			(layer "B.Fab")
			(hide yes)
			(effects
				(font
					(size 1 1)
					(thickness 0.15)
				)
				(justify mirror)
			)
		)
		(property "Val" "0R"
			(at -14.8875 323.5125 0)
			(layer "B.Fab")
			(hide yes)
			(effects
				(font
					(size 1 1)
					(thickness 0.15)
				)
				(justify mirror)
			)
		)
		(property "dnp" ""
			(at -14.8875 323.5125 0)
			(layer "B.Fab")
			(hide yes)
			(effects
				(font
					(size 1 1)
					(thickness 0.15)
				)
				(justify mirror)
			)
		)
		(property "exclude_from_bom" ""
			(at -14.8875 323.5125 0)
			(layer "B.Fab")
			(hide yes)
			(effects
				(font
					(size 1 1)
					(thickness 0.15)
				)
				(justify mirror)
			)
		)
		(sheetname "DC-DC Converters")
		(sheetfile "dc-dc.kicad_sch")
		(attr smd exclude_from_bom)
		(fp_rect
			(start -0.925 0.47)
			(end 0.925 -0.47)
			(stroke
				(width 0.05)
				(type default)
			)
			(fill no)
			(layer "B.CrtYd")
		)
		(fp_rect
			(start -0.5 0.25)
			(end 0.5 -0.25)
			(stroke
				(width 0.15)
				(type solid)
			)
			(fill no)
			(layer "B.Fab")
		)
		(pad "1" smd roundrect
			(at -0.48 0 270)
			(size 0.59 0.64)
			(layers "B.Cu" "B.Mask" "B.Paste")
			(roundrect_rratio 0.25)
			(net 1222 "/DC-DC Converters/SENSE_1V0_N")
			(pintype "passive")
		)
		(pad "2" smd roundrect
			(at 0.48 0 270)
			(size 0.59 0.64)
			(layers "B.Cu" "B.Mask" "B.Paste")
			(roundrect_rratio 0.25)
			(net 959 "/DC-DC Converters/FB1")
			(pintype "passive")
		)
	)
	(footprint "antmicro-footprints:C_0402_1005Metric"
		(layer "B.Cu")
		(at 170.1 149.425)
		(descr "Capacitor SMD 0402")
		(tags "capacitor SMD 0402")
		(property "Reference" "C185"
			(at 1.35 1.25 180)
			(layer "B.SilkS")
			(effects
				(font
					(size 0.7 0.7)
					(thickness 0.15)
				)
				(justify left bottom mirror)
			)
		)
		(property "Value" "C_100n_0402"
			(at 0 -1.169 180)
			(layer "B.Fab")
			(effects
				(font
					(size 0.7 0.7)
					(thickness 0.15)
				)
				(justify left bottom mirror)
			)
		)
		(property "Description" "SMD Multilayer Ceramic Capacitor, 0.1 µF, 50 V, 0402 [1005 Metric], ± 10%, X5R, GRM Series"
			(at 0 0 0)
			(layer "F.Fab")
			(hide yes)
			(effects
				(font
					(size 1.27 1.27)
					(thickness 0.15)
				)
			)
		)
		(property "Author" "Antmicro"
			(at 0 0 0)
			(layer "B.Fab")
			(hide yes)
			(effects
				(font
					(size 1 1)
					(thickness 0.15)
				)
				(justify mirror)
			)
		)
		(property "Dielectric" "X5R"
			(at 0 0 0)
			(layer "B.Fab")
			(hide yes)
			(effects
				(font
					(size 1 1)
					(thickness 0.15)
				)
				(justify mirror)
			)
		)
		(property "License" "Apache-2.0"
			(at 0 0 0)
			(layer "B.Fab")
			(hide yes)
			(effects
				(font
					(size 1 1)
					(thickness 0.15)
				)
				(justify mirror)
			)
		)
		(property "MPN" "GRM155R61H104KE14D"
			(at 0 0 0)
			(layer "B.Fab")
			(hide yes)
			(effects
				(font
					(size 1 1)
					(thickness 0.15)
				)
				(justify mirror)
			)
		)
		(property "Manufacturer" "Murata"
			(at 0 0 0)
			(layer "B.Fab")
			(hide yes)
			(effects
				(font
					(size 1 1)
					(thickness 0.15)
				)
				(justify mirror)
			)
		)
		(property "Val" "100n"
			(at 0 0 0)
			(layer "B.Fab")
			(hide yes)
			(effects
				(font
					(size 1 1)
					(thickness 0.15)
				)
				(justify mirror)
			)
		)
		(property "Voltage" "50V"
			(at 0 0 0)
			(layer "B.Fab")
			(hide yes)
			(effects
				(font
					(size 1 1)
					(thickness 0.15)
				)
				(justify mirror)
			)
		)
		(sheetname "DRAM + SRAM")
		(sheetfile "ram.kicad_sch")
		(attr smd)
		(fp_rect
			(start -0.925 0.47)
			(end 0.925 -0.47)
			(stroke
				(width 0.05)
				(type default)
			)
			(fill no)
			(layer "B.CrtYd")
		)
		(fp_line
			(start -0.494 -0.248)
			(end -0.494 0.25)
			(stroke
				(width 0.15)
				(type solid)
			)
			(layer "B.Fab")
		)
		(fp_line
			(start -0.494 0.25)
			(end 0.504 0.25)
			(stroke
				(width 0.15)
				(type solid)
			)
			(layer "B.Fab")
		)
		(fp_line
			(start 0.504 -0.248)
			(end -0.494 -0.248)
			(stroke
				(width 0.15)
				(type solid)
			)
			(layer "B.Fab")
		)
		(fp_line
			(start 0.504 0.25)
			(end 0.504 -0.248)
			(stroke
				(width 0.15)
				(type solid)
			)
			(layer "B.Fab")
		)
		(pad "1" smd roundrect
			(at -0.48 0)
			(size 0.59 0.64)
			(layers "B.Cu" "B.Mask" "B.Paste")
			(roundrect_rratio 0.25)
			(net 1 "GND")
			(pintype "passive")
		)
		(pad "2" smd roundrect
			(at 0.48 0)
			(size 0.59 0.64)
			(layers "B.Cu" "B.Mask" "B.Paste")
			(roundrect_rratio 0.25)
			(net 25 "+1V35")
			(pintype "passive")
		)
	)
	(footprint "antmicro-footprints:C_0201"
		(layer "B.Cu")
		(at 201.5 133.65 180)
		(descr "Capacitor SMD 0201")
		(tags "capacitor SMD 0201")
		(property "Reference" "C56"
			(at -26.925 28.225 0)
			(layer "B.SilkS")
			(effects
				(font
					(size 0.7 0.7)
					(thickness 0.15)
				)
				(justify left bottom mirror)
			)
		)
		(property "Value" "C_100n_0201"
			(at 0 -1.4 0)
			(layer "B.Fab")
			(effects
				(font
					(size 0.7 0.7)
					(thickness 0.15)
				)
				(justify left bottom mirror)
			)
		)
		(property "Description" "SMD Multilayer Ceramic Capacitor, 0.1 µF, 6.3 V, 0201 [0603 Metric], ± 10%, X6S, CC Series"
			(at 0 0 180)
			(layer "F.Fab")
			(hide yes)
			(effects
				(font
					(size 1.27 1.27)
					(thickness 0.15)
				)
			)
		)
		(property "Author" "Antmicro"
			(at 403 267.3 0)
			(layer "B.Fab")
			(hide yes)
			(effects
				(font
					(size 1 1)
					(thickness 0.15)
				)
				(justify mirror)
			)
		)
		(property "Dielectric" ""
			(at 403 267.3 0)
			(layer "B.Fab")
			(hide yes)
			(effects
				(font
					(size 1 1)
					(thickness 0.15)
				)
				(justify mirror)
			)
		)
		(property "License" "Apache-2.0"
			(at 403 267.3 0)
			(layer "B.Fab")
			(hide yes)
			(effects
				(font
					(size 1 1)
					(thickness 0.15)
				)
				(justify mirror)
			)
		)
		(property "MPN" "CC0201KRX6S5BB104"
			(at 403 267.3 0)
			(layer "B.Fab")
			(hide yes)
			(effects
				(font
					(size 1 1)
					(thickness 0.15)
				)
				(justify mirror)
			)
		)
		(property "Manufacturer" "YAGEO"
			(at 403 267.3 0)
			(layer "B.Fab")
			(hide yes)
			(effects
				(font
					(size 1 1)
					(thickness 0.15)
				)
				(justify mirror)
			)
		)
		(property "Val" "100n"
			(at 403 267.3 0)
			(layer "B.Fab")
			(hide yes)
			(effects
				(font
					(size 1 1)
					(thickness 0.15)
				)
				(justify mirror)
			)
		)
		(property "Voltage" ""
			(at 403 267.3 0)
			(layer "B.Fab")
			(hide yes)
			(effects
				(font
					(size 1 1)
					(thickness 0.15)
				)
				(justify mirror)
			)
		)
		(sheetname "FPGA supply")
		(sheetfile "fpga-supply.kicad_sch")
		(attr smd)
		(fp_rect
			(start -0.7 0.35)
			(end 0.7 -0.35)
			(stroke
				(width 0.05)
				(type default)
			)
			(fill no)
			(layer "B.CrtYd")
		)
		(fp_rect
			(start 0.3 -0.15)
			(end -0.301 0.149)
			(stroke
				(width 0.15)
				(type solid)
			)
			(fill no)
			(layer "B.Fab")
		)
		(pad "" smd roundrect
			(at -0.349 0.002 180)
			(size 0.318 0.36)
			(layers "B.Paste")
			(roundrect_rratio 0.25)
		)
		(pad "" smd roundrect
			(at 0.341 0.002 180)
			(size 0.318 0.36)
			(layers "B.Paste")
			(roundrect_rratio 0.25)
		)
		(pad "1" smd roundrect
			(at -0.321 0.002 180)
			(size 0.46 0.4)
			(layers "B.Cu" "B.Mask")
			(roundrect_rratio 0.25)
			(net 1 "GND")
			(pintype "passive")
		)
		(pad "2" smd roundrect
			(at 0.32 0.002 180)
			(size 0.46 0.4)
			(layers "B.Cu" "B.Mask")
			(roundrect_rratio 0.25)
			(net 650 "+1V0")
			(pintype "passive")
		)
	)
	(footprint "antmicro-footprints:C_0402_1005Metric"
		(layer "B.Cu")
		(at 242.2 117.2 90)
		(descr "Capacitor SMD 0402")
		(tags "capacitor SMD 0402")
		(property "Reference" "C213"
			(at -1.45 1.35 90)
			(layer "B.SilkS")
			(effects
				(font
					(size 0.7 0.7)
					(thickness 0.15)
				)
				(justify right bottom mirror)
			)
		)
		(property "Value" "C_1u_0402"
			(at 0 -1.4 90)
			(layer "B.Fab")
			(effects
				(font
					(size 0.7 0.7)
					(thickness 0.15)
				)
				(justify right bottom mirror)
			)
		)
		(property "Description" "SMD Multilayer Ceramic Capacitor, 1 µF, 10 V, 0402 [1005 Metric], ± 10%, X6S, C"
			(at 0 0 90)
			(layer "F.Fab")
			(hide yes)
			(effects
				(font
					(size 1.27 1.27)
					(thickness 0.15)
				)
			)
		)
		(property "Author" "Antmicro"
			(at 359.4 -125 0)
			(layer "B.Fab")
			(hide yes)
			(effects
				(font
					(size 1 1)
					(thickness 0.15)
				)
				(justify mirror)
			)
		)
		(property "DNP" "DNP"
			(at 359.4 -125 0)
			(layer "B.Fab")
			(hide yes)
			(effects
				(font
					(size 1 1)
					(thickness 0.15)
				)
				(justify mirror)
			)
		)
		(property "Dielectric" ""
			(at 359.4 -125 0)
			(layer "B.Fab")
			(hide yes)
			(effects
				(font
					(size 1 1)
					(thickness 0.15)
				)
				(justify mirror)
			)
		)
		(property "License" "Apache-2.0"
			(at 359.4 -125 0)
			(layer "B.Fab")
			(hide yes)
			(effects
				(font
					(size 1 1)
					(thickness 0.15)
				)
				(justify mirror)
			)
		)
		(property "MPN" "C1005X6S1A105K050BC"
			(at 359.4 -125 0)
			(layer "B.Fab")
			(hide yes)
			(effects
				(font
					(size 1 1)
					(thickness 0.15)
				)
				(justify mirror)
			)
		)
		(property "Manufacturer" "TDK"
			(at 359.4 -125 0)
			(layer "B.Fab")
			(hide yes)
			(effects
				(font
					(size 1 1)
					(thickness 0.15)
				)
				(justify mirror)
			)
		)
		(property "Val" "1u"
			(at 359.4 -125 0)
			(layer "B.Fab")
			(hide yes)
			(effects
				(font
					(size 1 1)
					(thickness 0.15)
				)
				(justify mirror)
			)
		)
		(property "Voltage" ""
			(at 359.4 -125 0)
			(layer "B.Fab")
			(hide yes)
			(effects
				(font
					(size 1 1)
					(thickness 0.15)
				)
				(justify mirror)
			)
		)
		(property "dnp" ""
			(at 359.4 -125 0)
			(layer "B.Fab")
			(hide yes)
			(effects
				(font
					(size 1 1)
					(thickness 0.15)
				)
				(justify mirror)
			)
		)
		(property "exclude_from_bom" ""
			(at 359.4 -125 0)
			(layer "B.Fab")
			(hide yes)
			(effects
				(font
					(size 1 1)
					(thickness 0.15)
				)
				(justify mirror)
			)
		)
		(sheetname "User GPIO + LED + button + DIP switch")
		(sheetfile "user-gpio.kicad_sch")
		(attr smd exclude_from_bom)
		(fp_rect
			(start -0.925 0.47)
			(end 0.925 -0.47)
			(stroke
				(width 0.05)
				(type default)
			)
			(fill no)
			(layer "B.CrtYd")
		)
		(fp_line
			(start 0.504 -0.248)
			(end -0.494 -0.248)
			(stroke
				(width 0.15)
				(type solid)
			)
			(layer "B.Fab")
		)
		(fp_line
			(start -0.494 -0.248)
			(end -0.494 0.25)
			(stroke
				(width 0.15)
				(type solid)
			)
			(layer "B.Fab")
		)
		(fp_line
			(start 0.504 0.25)
			(end 0.504 -0.248)
			(stroke
				(width 0.15)
				(type solid)
			)
			(layer "B.Fab")
		)
		(fp_line
			(start -0.494 0.25)
			(end 0.504 0.25)
			(stroke
				(width 0.15)
				(type solid)
			)
			(layer "B.Fab")
		)
		(pad "1" smd roundrect
			(at -0.48 0 90)
			(size 0.59 0.64)
			(layers "B.Cu" "B.Mask" "B.Paste")
			(roundrect_rratio 0.25)
			(net 1 "GND")
			(pintype "passive")
		)
		(pad "2" smd roundrect
			(at 0.48 0 90)
			(size 0.59 0.64)
			(layers "B.Cu" "B.Mask" "B.Paste")
			(roundrect_rratio 0.25)
			(net 703 "+5V")
			(pintype "passive")
		)
	)
	(footprint "antmicro-footprints:R_0402_1005Metric"
		(layer "B.Cu")
		(at 248.801 174.4 90)
		(descr "Resistor SMD 0402")
		(tags "resistor SMD 0402")
		(property "Reference" "R55"
			(at 1.075 -0.551 270)
			(layer "B.SilkS")
			(effects
				(font
					(size 0.7 0.7)
					(thickness 0.15)
				)
				(justify left bottom mirror)
			)
		)
		(property "Value" "R_24k9_0402"
			(at 0 -1.4 270)
			(layer "B.Fab")
			(effects
				(font
					(size 0.7 0.7)
					(thickness 0.15)
				)
				(justify left bottom mirror)
			)
		)
		(property "Description" "SMD Chip Resistor, 24.9 kohm, ± 1%, 63 mW, 0402 [1005 Metric], Thick Film, General Purpose"
			(at 0 0 90)
			(layer "F.Fab")
			(hide yes)
			(effects
				(font
					(size 1.27 1.27)
					(thickness 0.15)
				)
			)
		)
		(property "Author" "Antmicro"
			(at 423.201 -74.401 0)
			(layer "B.Fab")
			(hide yes)
			(effects
				(font
					(size 1 1)
					(thickness 0.15)
				)
				(justify mirror)
			)
		)
		(property "License" "Apache-2.0"
			(at 423.201 -74.401 0)
			(layer "B.Fab")
			(hide yes)
			(effects
				(font
					(size 1 1)
					(thickness 0.15)
				)
				(justify mirror)
			)
		)
		(property "MPN" "CR0402-FX-2492GLF"
			(at 423.201 -74.401 0)
			(layer "B.Fab")
			(hide yes)
			(effects
				(font
					(size 1 1)
					(thickness 0.15)
				)
				(justify mirror)
			)
		)
		(property "Manufacturer" "Bourns"
			(at 423.201 -74.401 0)
			(layer "B.Fab")
			(hide yes)
			(effects
				(font
					(size 1 1)
					(thickness 0.15)
				)
				(justify mirror)
			)
		)
		(property "Tolerance" "1%"
			(at 423.201 -74.401 0)
			(layer "B.Fab")
			(hide yes)
			(effects
				(font
					(size 1 1)
					(thickness 0.15)
				)
				(justify mirror)
			)
		)
		(property "Val" "24k9"
			(at 423.201 -74.401 0)
			(layer "B.Fab")
			(hide yes)
			(effects
				(font
					(size 1 1)
					(thickness 0.15)
				)
				(justify mirror)
			)
		)
		(sheetname "Power supply")
		(sheetfile "power-supply.kicad_sch")
		(attr smd)
		(fp_rect
			(start -0.925 0.47)
			(end 0.925 -0.47)
			(stroke
				(width 0.05)
				(type default)
			)
			(fill no)
			(layer "B.CrtYd")
		)
		(fp_rect
			(start -0.5 0.25)
			(end 0.5 -0.25)
			(stroke
				(width 0.15)
				(type solid)
			)
			(fill no)
			(layer "B.Fab")
		)
		(pad "1" smd roundrect
			(at -0.48 0 90)
			(size 0.59 0.64)
			(layers "B.Cu" "B.Mask" "B.Paste")
			(roundrect_rratio 0.25)
			(net 887 "/Power supply/DEN")
			(pintype "passive")
		)
		(pad "2" smd roundrect
			(at 0.48 0 90)
			(size 0.59 0.64)
			(layers "B.Cu" "B.Mask" "B.Paste")
			(roundrect_rratio 0.25)
			(net 698 "/Power supply/VDD")
			(pintype "passive")
		)
	)
	(footprint "antmicro-footprints:R_0402_1005Metric"
		(layer "B.Cu")
		(at 172.75 175.7125)
		(descr "Resistor SMD 0402")
		(tags "resistor SMD 0402")
		(property "Reference" "R316"
			(at -0.75 0.4125 180)
			(layer "B.SilkS")
			(effects
				(font
					(size 0.7 0.7)
					(thickness 0.15)
				)
				(justify left bottom mirror)
			)
		)
		(property "Value" "R_0R_0402"
			(at 0 -1.4 180)
			(layer "B.Fab")
			(effects
				(font
					(size 0.7 0.7)
					(thickness 0.15)
				)
				(justify left bottom mirror)
			)
		)
		(property "Description" "SMD Chip Resistor, Jumper, 0 ohm, 100 mW, 0402 [1005 Metric], Thick Film, General Purpose"
			(at 0 0 0)
			(layer "F.Fab")
			(hide yes)
			(effects
				(font
					(size 1.27 1.27)
					(thickness 0.15)
				)
			)
		)
		(property "Author" "Antmicro"
			(at 0 0 0)
			(layer "B.Fab")
			(hide yes)
			(effects
				(font
					(size 1 1)
					(thickness 0.15)
				)
				(justify mirror)
			)
		)
		(property "Current" "1A"
			(at 0 0 0)
			(layer "B.Fab")
			(hide yes)
			(effects
				(font
					(size 1 1)
					(thickness 0.15)
				)
				(justify mirror)
			)
		)
		(property "DNP" "DNP"
			(at 0 0 0)
			(layer "B.Fab")
			(hide yes)
			(effects
				(font
					(size 1 1)
					(thickness 0.15)
				)
				(justify mirror)
			)
		)
		(property "License" "Apache-2.0"
			(at 0 0 0)
			(layer "B.Fab")
			(hide yes)
			(effects
				(font
					(size 1 1)
					(thickness 0.15)
				)
				(justify mirror)
			)
		)
		(property "MPN" "ERJ2GE0R00X"
			(at 0 0 0)
			(layer "B.Fab")
			(hide yes)
			(effects
				(font
					(size 1 1)
					(thickness 0.15)
				)
				(justify mirror)
			)
		)
		(property "Manufacturer" "Panasonic"
			(at 0 0 0)
			(layer "B.Fab")
			(hide yes)
			(effects
				(font
					(size 1 1)
					(thickness 0.15)
				)
				(justify mirror)
			)
		)
		(property "Tolerance" ""
			(at 0 0 0)
			(layer "B.Fab")
			(hide yes)
			(effects
				(font
					(size 1 1)
					(thickness 0.15)
				)
				(justify mirror)
			)
		)
		(property "Val" "0R"
			(at 0 0 0)
			(layer "B.Fab")
			(hide yes)
			(effects
				(font
					(size 1 1)
					(thickness 0.15)
				)
				(justify mirror)
			)
		)
		(property "dnp" ""
			(at 0 0 0)
			(layer "B.Fab")
			(hide yes)
			(effects
				(font
					(size 1 1)
					(thickness 0.15)
				)
				(justify mirror)
			)
		)
		(property "exclude_from_bom" ""
			(at 0 0 0)
			(layer "B.Fab")
			(hide yes)
			(effects
				(font
					(size 1 1)
					(thickness 0.15)
				)
				(justify mirror)
			)
		)
		(sheetname "DC-DC Converters")
		(sheetfile "dc-dc.kicad_sch")
		(attr smd exclude_from_bom)
		(fp_rect
			(start -0.925 0.47)
			(end 0.925 -0.47)
			(stroke
				(width 0.05)
				(type default)
			)
			(fill no)
			(layer "B.CrtYd")
		)
		(fp_rect
			(start -0.5 0.25)
			(end 0.5 -0.25)
			(stroke
				(width 0.15)
				(type solid)
			)
			(fill no)
			(layer "B.Fab")
		)
		(pad "1" smd roundrect
			(at -0.48 0)
			(size 0.59 0.64)
			(layers "B.Cu" "B.Mask" "B.Paste")
			(roundrect_rratio 0.25)
			(net 1215 "/DC-DC Converters/SENSE_1V35_N")
			(pintype "passive")
		)
		(pad "2" smd roundrect
			(at 0.48 0)
			(size 0.59 0.64)
			(layers "B.Cu" "B.Mask" "B.Paste")
			(roundrect_rratio 0.25)
			(net 965 "/DC-DC Converters/FB8")
			(pintype "passive")
		)
	)
	(footprint "antmicro-footprints:R_0402_1005Metric"
		(layer "B.Cu")
		(at 163.905001 79.930001 90)
		(descr "Resistor SMD 0402")
		(tags "resistor SMD 0402")
		(property "Reference" "R266"
			(at 1.355001 -0.505001 270)
			(layer "B.SilkS")
			(effects
				(font
					(size 0.7 0.7)
					(thickness 0.15)
				)
				(justify left bottom mirror)
			)
		)
		(property "Value" "R_10k_0402"
			(at 0 -1.4 270)
			(layer "B.Fab")
			(effects
				(font
					(size 0.7 0.7)
					(thickness 0.15)
				)
				(justify left bottom mirror)
			)
		)
		(property "Description" "SMD Chip Resistor, 10 kohm, ± 1%, 62.5 mW, 0402 [1005 Metric], Thick Film, General Purpose"
			(at 0 0 90)
			(layer "F.Fab")
			(hide yes)
			(effects
				(font
					(size 1.27 1.27)
					(thickness 0.15)
				)
			)
		)
		(property "Author" "Antmicro"
			(at 243.835002 -83.975 0)
			(layer "B.Fab")
			(hide yes)
			(effects
				(font
					(size 1 1)
					(thickness 0.15)
				)
				(justify mirror)
			)
		)
		(property "License" "Apache-2.0"
			(at 243.835002 -83.975 0)
			(layer "B.Fab")
			(hide yes)
			(effects
				(font
					(size 1 1)
					(thickness 0.15)
				)
				(justify mirror)
			)
		)
		(property "MPN" "CR0402-FX-1002GLF"
			(at 243.835002 -83.975 0)
			(layer "B.Fab")
			(hide yes)
			(effects
				(font
					(size 1 1)
					(thickness 0.15)
				)
				(justify mirror)
			)
		)
		(property "Manufacturer" "Bourns"
			(at 243.835002 -83.975 0)
			(layer "B.Fab")
			(hide yes)
			(effects
				(font
					(size 1 1)
					(thickness 0.15)
				)
				(justify mirror)
			)
		)
		(property "Tolerance" "1%"
			(at 243.835002 -83.975 0)
			(layer "B.Fab")
			(hide yes)
			(effects
				(font
					(size 1 1)
					(thickness 0.15)
				)
				(justify mirror)
			)
		)
		(property "Val" "10k"
			(at 243.835002 -83.975 0)
			(layer "B.Fab")
			(hide yes)
			(effects
				(font
					(size 1 1)
					(thickness 0.15)
				)
				(justify mirror)
			)
		)
		(sheetname "FMC+ HSPC")
		(sheetfile "fmc-hspc.kicad_sch")
		(attr smd)
		(fp_rect
			(start -0.925 0.47)
			(end 0.925 -0.47)
			(stroke
				(width 0.05)
				(type default)
			)
			(fill no)
			(layer "B.CrtYd")
		)
		(fp_rect
			(start -0.5 0.25)
			(end 0.5 -0.25)
			(stroke
				(width 0.15)
				(type solid)
			)
			(fill no)
			(layer "B.Fab")
		)
		(pad "1" smd roundrect
			(at -0.48 0 90)
			(size 0.59 0.64)
			(layers "B.Cu" "B.Mask" "B.Paste")
			(roundrect_rratio 0.25)
			(net 99 "Net-(J18B-PG_C2M)")
			(pintype "passive")
		)
		(pad "2" smd roundrect
			(at 0.48 0 90)
			(size 0.59 0.64)
			(layers "B.Cu" "B.Mask" "B.Paste")
			(roundrect_rratio 0.25)
			(net 24 "+3V3")
			(pintype "passive")
		)
	)
	(footprint "antmicro-footprints:C_0201"
		(layer "B.Cu")
		(at 188.000001 118.500001 180)
		(descr "Capacitor SMD 0201")
		(tags "capacitor SMD 0201")
		(property "Reference" "C146"
			(at 2.350001 -0.374999 0)
			(layer "B.SilkS")
			(effects
				(font
					(size 0.7 0.7)
					(thickness 0.15)
				)
				(justify left bottom mirror)
			)
		)
		(property "Value" "C_100n_0201"
			(at 0 -1.4 0)
			(layer "B.Fab")
			(effects
				(font
					(size 0.7 0.7)
					(thickness 0.15)
				)
				(justify left bottom mirror)
			)
		)
		(property "Description" "SMD Multilayer Ceramic Capacitor, 0.1 µF, 6.3 V, 0201 [0603 Metric], ± 10%, X6S, CC Series"
			(at 0 0 180)
			(layer "F.Fab")
			(hide yes)
			(effects
				(font
					(size 1.27 1.27)
					(thickness 0.15)
				)
			)
		)
		(property "Author" "Antmicro"
			(at 376.000002 237.000002 0)
			(layer "B.Fab")
			(hide yes)
			(effects
				(font
					(size 1 1)
					(thickness 0.15)
				)
				(justify mirror)
			)
		)
		(property "Dielectric" ""
			(at 376.000002 237.000002 0)
			(layer "B.Fab")
			(hide yes)
			(effects
				(font
					(size 1 1)
					(thickness 0.15)
				)
				(justify mirror)
			)
		)
		(property "License" "Apache-2.0"
			(at 376.000002 237.000002 0)
			(layer "B.Fab")
			(hide yes)
			(effects
				(font
					(size 1 1)
					(thickness 0.15)
				)
				(justify mirror)
			)
		)
		(property "MPN" "CC0201KRX6S5BB104"
			(at 376.000002 237.000002 0)
			(layer "B.Fab")
			(hide yes)
			(effects
				(font
					(size 1 1)
					(thickness 0.15)
				)
				(justify mirror)
			)
		)
		(property "Manufacturer" "YAGEO"
			(at 376.000002 237.000002 0)
			(layer "B.Fab")
			(hide yes)
			(effects
				(font
					(size 1 1)
					(thickness 0.15)
				)
				(justify mirror)
			)
		)
		(property "Val" "100n"
			(at 376.000002 237.000002 0)
			(layer "B.Fab")
			(hide yes)
			(effects
				(font
					(size 1 1)
					(thickness 0.15)
				)
				(justify mirror)
			)
		)
		(property "Voltage" ""
			(at 376.000002 237.000002 0)
			(layer "B.Fab")
			(hide yes)
			(effects
				(font
					(size 1 1)
					(thickness 0.15)
				)
				(justify mirror)
			)
		)
		(sheetname "FPGA supply")
		(sheetfile "fpga-supply.kicad_sch")
		(attr smd)
		(fp_rect
			(start -0.7 0.35)
			(end 0.7 -0.35)
			(stroke
				(width 0.05)
				(type default)
			)
			(fill no)
			(layer "B.CrtYd")
		)
		(fp_rect
			(start 0.3 -0.15)
			(end -0.301 0.149)
			(stroke
				(width 0.15)
				(type solid)
			)
			(fill no)
			(layer "B.Fab")
		)
		(pad "" smd roundrect
			(at -0.349 0.002 180)
			(size 0.318 0.36)
			(layers "B.Paste")
			(roundrect_rratio 0.25)
		)
		(pad "" smd roundrect
			(at 0.341 0.002 180)
			(size 0.318 0.36)
			(layers "B.Paste")
			(roundrect_rratio 0.25)
		)
		(pad "1" smd roundrect
			(at -0.321 0.002 180)
			(size 0.46 0.4)
			(layers "B.Cu" "B.Mask")
			(roundrect_rratio 0.25)
			(net 1 "GND")
			(pintype "passive")
		)
		(pad "2" smd roundrect
			(at 0.32 0.002 180)
			(size 0.46 0.4)
			(layers "B.Cu" "B.Mask")
			(roundrect_rratio 0.25)
			(net 8 "+1V2_MGTAVTT")
			(pintype "passive")
		)
	)
	(footprint "antmicro-footprints:C_0603_1608Metric"
		(layer "B.Cu")
		(at 183 138.26 135)
		(descr "Capacitor SMD 0603")
		(tags "capacitor 0603")
		(property "Reference" "C109"
			(at -1.52028 0.636396 315)
			(unlocked yes)
			(layer "B.SilkS")
			(effects
				(font
					(size 0.7 0.7)
					(thickness 0.15)
				)
				(justify left bottom mirror)
			)
		)
		(property "Value" "C_47u_0603"
			(at 0 -1.6 315)
			(layer "B.Fab")
			(effects
				(font
					(size 0.7 0.7)
					(thickness 0.15)
				)
				(justify left bottom mirror)
			)
		)
		(property "Description" "SMD Multilayer Ceramic Capacitor, 47 µF, 6.3 V, 0603 [1608 Metric], ± 20%, X5R, GRM Series"
			(at 0 0 135)
			(layer "F.Fab")
			(hide yes)
			(effects
				(font
					(size 1.27 1.27)
					(thickness 0.15)
				)
			)
		)
		(property "Author" "Antmicro"
			(at 410.165125 106.624043 0)
			(layer "B.Fab")
			(hide yes)
			(effects
				(font
					(size 1 1)
					(thickness 0.15)
				)
				(justify mirror)
			)
		)
		(property "Dielectric" ""
			(at 410.165125 106.624043 0)
			(layer "B.Fab")
			(hide yes)
			(effects
				(font
					(size 1 1)
					(thickness 0.15)
				)
				(justify mirror)
			)
		)
		(property "License" "Apache-2.0"
			(at 410.165125 106.624043 0)
			(layer "B.Fab")
			(hide yes)
			(effects
				(font
					(size 1 1)
					(thickness 0.15)
				)
				(justify mirror)
			)
		)
		(property "MPN" "GRM188R60J476ME15D"
			(at 410.165125 106.624043 0)
			(layer "B.Fab")
			(hide yes)
			(effects
				(font
					(size 1 1)
					(thickness 0.15)
				)
				(justify mirror)
			)
		)
		(property "Manufacturer" "Murata"
			(at 410.165125 106.624043 0)
			(layer "B.Fab")
			(hide yes)
			(effects
				(font
					(size 1 1)
					(thickness 0.15)
				)
				(justify mirror)
			)
		)
		(property "Val" "47u"
			(at 410.165125 106.624043 0)
			(layer "B.Fab")
			(hide yes)
			(effects
				(font
					(size 1 1)
					(thickness 0.15)
				)
				(justify mirror)
			)
		)
		(property "Voltage" ""
			(at 410.165125 106.624043 0)
			(layer "B.Fab")
			(hide yes)
			(effects
				(font
					(size 1 1)
					(thickness 0.15)
				)
				(justify mirror)
			)
		)
		(sheetname "FPGA Bank 33 & 34")
		(sheetfile "fpga-bank-33-34.kicad_sch")
		(attr smd)
		(fp_line
			(start -0.15 -0.4)
			(end 0.15 -0.4)
			(stroke
				(width 0.15)
				(type solid)
			)
			(layer "B.SilkS")
		)
		(fp_line
			(start -0.15 0.4)
			(end 0.15 0.4)
			(stroke
				(width 0.15)
				(type solid)
			)
			(layer "B.SilkS")
		)
		(fp_poly
			(pts
				(xy -1.25 0.65) (xy 1.25 0.65) (xy 1.25 -0.65) (xy -1.25 -0.65)
			)
			(stroke
				(width 0.05)
				(type solid)
			)
			(fill no)
			(layer "B.CrtYd")
		)
		(fp_poly
			(pts
				(xy -0.8 0.4) (xy 0.8 0.4) (xy 0.8 -0.4) (xy -0.8 -0.4)
			)
			(stroke
				(width 0.15)
				(type solid)
			)
			(fill no)
			(layer "B.Fab")
		)
		(pad "1" smd roundrect
			(at -0.7 0 135)
			(size 0.8 1)
			(layers "B.Cu" "B.Mask" "B.Paste")
			(roundrect_rratio 0.2)
			(net 25 "+1V35")
			(pintype "passive")
		)
		(pad "2" smd roundrect
			(at 0.7 0 135)
			(size 0.8 1)
			(layers "B.Cu" "B.Mask" "B.Paste")
			(roundrect_rratio 0.2)
			(net 1 "GND")
			(pintype "passive")
		)
	)
	(footprint "antmicro-footprints:R_0402_1005Metric"
		(layer "B.Cu")
		(at 188.100001 84.800001 90)
		(descr "Resistor SMD 0402")
		(tags "resistor SMD 0402")
		(property "Reference" "R135"
			(at -0.725 0.4 270)
			(layer "B.SilkS")
			(effects
				(font
					(size 0.7 0.7)
					(thickness 0.15)
				)
				(justify left bottom mirror)
			)
		)
		(property "Value" "R_100R_0402"
			(at 0 -1.4 270)
			(layer "B.Fab")
			(effects
				(font
					(size 0.7 0.7)
					(thickness 0.15)
				)
				(justify left bottom mirror)
			)
		)
		(property "Description" "SMD Chip Resistor, 100 ohm, ± 1%, 62.5 mW, 0402 [1005 Metric], Thick Film, General Purpose"
			(at 0 0 90)
			(layer "F.Fab")
			(hide yes)
			(effects
				(font
					(size 1.27 1.27)
					(thickness 0.15)
				)
			)
		)
		(property "Author" "Antmicro"
			(at 272.900002 -103.3 0)
			(layer "B.Fab")
			(hide yes)
			(effects
				(font
					(size 1 1)
					(thickness 0.15)
				)
				(justify mirror)
			)
		)
		(property "License" "Apache-2.0"
			(at 272.900002 -103.3 0)
			(layer "B.Fab")
			(hide yes)
			(effects
				(font
					(size 1 1)
					(thickness 0.15)
				)
				(justify mirror)
			)
		)
		(property "MPN" "CR0402-FX-1000GLF"
			(at 272.900002 -103.3 0)
			(layer "B.Fab")
			(hide yes)
			(effects
				(font
					(size 1 1)
					(thickness 0.15)
				)
				(justify mirror)
			)
		)
		(property "Manufacturer" "Bourns"
			(at 272.900002 -103.3 0)
			(layer "B.Fab")
			(hide yes)
			(effects
				(font
					(size 1 1)
					(thickness 0.15)
				)
				(justify mirror)
			)
		)
		(property "Tolerance" "1%"
			(at 272.900002 -103.3 0)
			(layer "B.Fab")
			(hide yes)
			(effects
				(font
					(size 1 1)
					(thickness 0.15)
				)
				(justify mirror)
			)
		)
		(property "Val" "100R"
			(at 272.900002 -103.3 0)
			(layer "B.Fab")
			(hide yes)
			(effects
				(font
					(size 1 1)
					(thickness 0.15)
				)
				(justify mirror)
			)
		)
		(sheetname "User GPIO + LED + button + DIP switch")
		(sheetfile "user-gpio.kicad_sch")
		(attr smd)
		(fp_rect
			(start -0.925 0.47)
			(end 0.925 -0.47)
			(stroke
				(width 0.05)
				(type default)
			)
			(fill no)
			(layer "B.CrtYd")
		)
		(fp_rect
			(start -0.5 0.25)
			(end 0.5 -0.25)
			(stroke
				(width 0.15)
				(type solid)
			)
			(fill no)
			(layer "B.Fab")
		)
		(pad "1" smd roundrect
			(at -0.48 0 90)
			(size 0.59 0.64)
			(layers "B.Cu" "B.Mask" "B.Paste")
			(roundrect_rratio 0.25)
			(net 825 "/User GPIO + LED + button + DIP switch/CW_20PIN_MISO")
			(pintype "passive")
		)
		(pad "2" smd roundrect
			(at 0.48 0 90)
			(size 0.59 0.64)
			(layers "B.Cu" "B.Mask" "B.Paste")
			(roundrect_rratio 0.25)
			(net 475 "/FPGA Bank 12 & 13/CW_HEADER.MISO")
			(pintype "passive")
		)
	)
	(footprint "antmicro-footprints:R_0603_1608Metric"
		(layer "B.Cu")
		(at 256.801 152.5)
		(descr "Resistor SMD 0603")
		(tags "resistor SMD 0603")
		(property "Reference" "R263"
			(at 1.374 -0.55 180)
			(layer "B.SilkS")
			(effects
				(font
					(size 0.7 0.7)
					(thickness 0.15)
				)
				(justify left bottom mirror)
			)
		)
		(property "Value" "R_220R_0603"
			(at 0 -1.6 180)
			(layer "B.Fab")
			(effects
				(font
					(size 0.7 0.7)
					(thickness 0.15)
				)
				(justify left bottom mirror)
			)
		)
		(property "Description" "SMD Chip Resistor, 220 ohm, ± 1%, 100 mW, 0603 [1608 Metric], Thick Film, General Purpose"
			(at 0 0 0)
			(layer "F.Fab")
			(hide yes)
			(effects
				(font
					(size 1.27 1.27)
					(thickness 0.15)
				)
			)
		)
		(property "Author" "Antmicro"
			(at 0 0 0)
			(layer "B.Fab")
			(hide yes)
			(effects
				(font
					(size 1 1)
					(thickness 0.15)
				)
				(justify mirror)
			)
		)
		(property "License" "Apache-2.0"
			(at 0 0 0)
			(layer "B.Fab")
			(hide yes)
			(effects
				(font
					(size 1 1)
					(thickness 0.15)
				)
				(justify mirror)
			)
		)
		(property "MPN" "CR0603-FX-2200ELF"
			(at 0 0 0)
			(layer "B.Fab")
			(hide yes)
			(effects
				(font
					(size 1 1)
					(thickness 0.15)
				)
				(justify mirror)
			)
		)
		(property "Manufacturer" "Bourns"
			(at 0 0 0)
			(layer "B.Fab")
			(hide yes)
			(effects
				(font
					(size 1 1)
					(thickness 0.15)
				)
				(justify mirror)
			)
		)
		(property "Tolerance" "1%"
			(at 0 0 0)
			(layer "B.Fab")
			(hide yes)
			(effects
				(font
					(size 1 1)
					(thickness 0.15)
				)
				(justify mirror)
			)
		)
		(property "Val" "220R"
			(at 0 0 0)
			(layer "B.Fab")
			(hide yes)
			(effects
				(font
					(size 1 1)
					(thickness 0.15)
				)
				(justify mirror)
			)
		)
		(sheetname "HDMI + Ethernet")
		(sheetfile "hdmi-ethernet.kicad_sch")
		(attr smd)
		(fp_line
			(start -0.15 -0.4)
			(end 0.15 -0.4)
			(stroke
				(width 0.15)
				(type solid)
			)
			(layer "B.SilkS")
		)
		(fp_line
			(start -0.15 0.4)
			(end 0.15 0.4)
			(stroke
				(width 0.15)
				(type solid)
			)
			(layer "B.SilkS")
		)
		(fp_rect
			(start -1.25 0.65)
			(end 1.25 -0.65)
			(stroke
				(width 0.05)
				(type solid)
			)
			(fill no)
			(layer "B.CrtYd")
		)
		(fp_rect
			(start -0.8 0.4)
			(end 0.8 -0.4)
			(stroke
				(width 0.15)
				(type solid)
			)
			(fill no)
			(layer "B.Fab")
		)
		(pad "1" smd roundrect
			(at -0.7 0)
			(size 0.8 1)
			(layers "B.Cu" "B.Mask" "B.Paste")
			(roundrect_rratio 0.2)
			(net 852 "/HDMI + Ethernet/GBE_LED_SPD+")
			(pintype "passive")
		)
		(pad "2" smd roundrect
			(at 0.7 0)
			(size 0.8 1)
			(layers "B.Cu" "B.Mask" "B.Paste")
			(roundrect_rratio 0.2)
			(net 24 "+3V3")
			(pintype "passive")
		)
	)
	(footprint "antmicro-footprints:C_0402_1005Metric"
		(layer "B.Cu")
		(at 167.1 188.6 180)
		(descr "Capacitor SMD 0402")
		(tags "capacitor SMD 0402")
		(property "Reference" "C338"
			(at -1.125 0.5 0)
			(layer "B.SilkS")
			(effects
				(font
					(size 0.7 0.7)
					(thickness 0.15)
				)
				(justify left bottom mirror)
			)
		)
		(property "Value" "C_100n_0402"
			(at 0 -1.4 0)
			(layer "B.Fab")
			(effects
				(font
					(size 0.7 0.7)
					(thickness 0.15)
				)
				(justify left bottom mirror)
			)
		)
		(property "Description" "SMD Multilayer Ceramic Capacitor, 0.1 µF, 50 V, 0402 [1005 Metric], ± 10%, X5R, GRM Series"
			(at 0 0 180)
			(layer "F.Fab")
			(hide yes)
			(effects
				(font
					(size 1.27 1.27)
					(thickness 0.15)
				)
			)
		)
		(property "Author" "Antmicro"
			(at 334.2 377.2 0)
			(layer "B.Fab")
			(hide yes)
			(effects
				(font
					(size 1 1)
					(thickness 0.15)
				)
				(justify mirror)
			)
		)
		(property "Dielectric" "X5R"
			(at 334.2 377.2 0)
			(layer "B.Fab")
			(hide yes)
			(effects
				(font
					(size 1 1)
					(thickness 0.15)
				)
				(justify mirror)
			)
		)
		(property "License" "Apache-2.0"
			(at 334.2 377.2 0)
			(layer "B.Fab")
			(hide yes)
			(effects
				(font
					(size 1 1)
					(thickness 0.15)
				)
				(justify mirror)
			)
		)
		(property "MPN" "GRM155R61H104KE14D"
			(at 334.2 377.2 0)
			(layer "B.Fab")
			(hide yes)
			(effects
				(font
					(size 1 1)
					(thickness 0.15)
				)
				(justify mirror)
			)
		)
		(property "Manufacturer" "Murata"
			(at 334.2 377.2 0)
			(layer "B.Fab")
			(hide yes)
			(effects
				(font
					(size 1 1)
					(thickness 0.15)
				)
				(justify mirror)
			)
		)
		(property "Val" "100n"
			(at 334.2 377.2 0)
			(layer "B.Fab")
			(hide yes)
			(effects
				(font
					(size 1 1)
					(thickness 0.15)
				)
				(justify mirror)
			)
		)
		(property "Voltage" "50V"
			(at 334.2 377.2 0)
			(layer "B.Fab")
			(hide yes)
			(effects
				(font
					(size 1 1)
					(thickness 0.15)
				)
				(justify mirror)
			)
		)
		(sheetname "DC-DC Converters")
		(sheetfile "dc-dc.kicad_sch")
		(attr smd)
		(fp_rect
			(start -0.925 0.47)
			(end 0.925 -0.47)
			(stroke
				(width 0.05)
				(type default)
			)
			(fill no)
			(layer "B.CrtYd")
		)
		(fp_line
			(start 0.504 0.25)
			(end 0.504 -0.248)
			(stroke
				(width 0.15)
				(type solid)
			)
			(layer "B.Fab")
		)
		(fp_line
			(start 0.504 -0.248)
			(end -0.494 -0.248)
			(stroke
				(width 0.15)
				(type solid)
			)
			(layer "B.Fab")
		)
		(fp_line
			(start -0.494 0.25)
			(end 0.504 0.25)
			(stroke
				(width 0.15)
				(type solid)
			)
			(layer "B.Fab")
		)
		(fp_line
			(start -0.494 -0.248)
			(end -0.494 0.25)
			(stroke
				(width 0.15)
				(type solid)
			)
			(layer "B.Fab")
		)
		(pad "1" smd roundrect
			(at -0.48 0 180)
			(size 0.59 0.64)
			(layers "B.Cu" "B.Mask" "B.Paste")
			(roundrect_rratio 0.25)
			(net 1 "GND")
			(pintype "passive")
		)
		(pad "2" smd roundrect
			(at 0.48 0 180)
			(size 0.59 0.64)
			(layers "B.Cu" "B.Mask" "B.Paste")
			(roundrect_rratio 0.25)
			(net 37 "+3V3_AON")
			(pintype "passive")
		)
	)
	(footprint "antmicro-footprints:C_0201"
		(layer "B.Cu")
		(at 203 129.65)
		(descr "Capacitor SMD 0201")
		(tags "capacitor SMD 0201")
		(property "Reference" "C48"
			(at 26.825 -28.625 0)
			(layer "B.SilkS")
			(effects
				(font
					(size 0.7 0.7)
					(thickness 0.15)
				)
				(justify right bottom mirror)
			)
		)
		(property "Value" "C_4u7_0201"
			(at 0 -1.4 0)
			(layer "B.Fab")
			(effects
				(font
					(size 0.7 0.7)
					(thickness 0.15)
				)
				(justify right bottom mirror)
			)
		)
		(property "Description" "SMD Multilayer Ceramic Capacitor, 4.7 µF, 6.3 V, 0201 [0603 Metric], ± 20%, X5R, GRM Series"
			(at 0 0 0)
			(layer "F.Fab")
			(hide yes)
			(effects
				(font
					(size 1.27 1.27)
					(thickness 0.15)
				)
			)
		)
		(property "Author" "Antmicro"
			(at 0 0 0)
			(layer "B.Fab")
			(hide yes)
			(effects
				(font
					(size 1 1)
					(thickness 0.15)
				)
				(justify mirror)
			)
		)
		(property "Dielectric" ""
			(at 0 0 0)
			(layer "B.Fab")
			(hide yes)
			(effects
				(font
					(size 1 1)
					(thickness 0.15)
				)
				(justify mirror)
			)
		)
		(property "License" "Apache-2.0"
			(at 0 0 0)
			(layer "B.Fab")
			(hide yes)
			(effects
				(font
					(size 1 1)
					(thickness 0.15)
				)
				(justify mirror)
			)
		)
		(property "MPN" "GRM035R60J475ME15D"
			(at 0 0 0)
			(layer "B.Fab")
			(hide yes)
			(effects
				(font
					(size 1 1)
					(thickness 0.15)
				)
				(justify mirror)
			)
		)
		(property "Manufacturer" "Murata"
			(at 0 0 0)
			(layer "B.Fab")
			(hide yes)
			(effects
				(font
					(size 1 1)
					(thickness 0.15)
				)
				(justify mirror)
			)
		)
		(property "Val" "4u7"
			(at 0 0 0)
			(layer "B.Fab")
			(hide yes)
			(effects
				(font
					(size 1 1)
					(thickness 0.15)
				)
				(justify mirror)
			)
		)
		(property "Voltage" ""
			(at 0 0 0)
			(layer "B.Fab")
			(hide yes)
			(effects
				(font
					(size 1 1)
					(thickness 0.15)
				)
				(justify mirror)
			)
		)
		(sheetname "FPGA supply")
		(sheetfile "fpga-supply.kicad_sch")
		(attr smd)
		(fp_rect
			(start -0.7 0.35)
			(end 0.7 -0.35)
			(stroke
				(width 0.05)
				(type default)
			)
			(fill no)
			(layer "B.CrtYd")
		)
		(fp_rect
			(start 0.3 -0.15)
			(end -0.301 0.149)
			(stroke
				(width 0.15)
				(type solid)
			)
			(fill no)
			(layer "B.Fab")
		)
		(pad "" smd roundrect
			(at -0.349 0.002)
			(size 0.318 0.36)
			(layers "B.Paste")
			(roundrect_rratio 0.25)
		)
		(pad "" smd roundrect
			(at 0.341 0.002)
			(size 0.318 0.36)
			(layers "B.Paste")
			(roundrect_rratio 0.25)
		)
		(pad "1" smd roundrect
			(at -0.321 0.002)
			(size 0.46 0.4)
			(layers "B.Cu" "B.Mask")
			(roundrect_rratio 0.25)
			(net 1 "GND")
			(pintype "passive")
		)
		(pad "2" smd roundrect
			(at 0.32 0.002)
			(size 0.46 0.4)
			(layers "B.Cu" "B.Mask")
			(roundrect_rratio 0.25)
			(net 650 "+1V0")
			(pintype "passive")
		)
	)
	(footprint "antmicro-footprints:R_0402_1005Metric"
		(layer "B.Cu")
		(at 266.8 88.6 -90)
		(descr "Resistor SMD 0402")
		(tags "resistor SMD 0402")
		(property "Reference" "R148"
			(at -1.4 -1.325 90)
			(layer "B.SilkS")
			(effects
				(font
					(size 0.7 0.7)
					(thickness 0.15)
				)
				(justify left bottom mirror)
			)
		)
		(property "Value" "R_10k_0402"
			(at 0 -1.4 90)
			(layer "B.Fab")
			(effects
				(font
					(size 0.7 0.7)
					(thickness 0.15)
				)
				(justify left bottom mirror)
			)
		)
		(property "Description" "SMD Chip Resistor, 10 kohm, ± 1%, 62.5 mW, 0402 [1005 Metric], Thick Film, General Purpose"
			(at 0 0 270)
			(layer "F.Fab")
			(hide yes)
			(effects
				(font
					(size 1.27 1.27)
					(thickness 0.15)
				)
			)
		)
		(property "Author" "Antmicro"
			(at 178.2 355.4 0)
			(layer "B.Fab")
			(hide yes)
			(effects
				(font
					(size 1 1)
					(thickness 0.15)
				)
				(justify mirror)
			)
		)
		(property "License" "Apache-2.0"
			(at 178.2 355.4 0)
			(layer "B.Fab")
			(hide yes)
			(effects
				(font
					(size 1 1)
					(thickness 0.15)
				)
				(justify mirror)
			)
		)
		(property "MPN" "CR0402-FX-1002GLF"
			(at 178.2 355.4 0)
			(layer "B.Fab")
			(hide yes)
			(effects
				(font
					(size 1 1)
					(thickness 0.15)
				)
				(justify mirror)
			)
		)
		(property "Manufacturer" "Bourns"
			(at 178.2 355.4 0)
			(layer "B.Fab")
			(hide yes)
			(effects
				(font
					(size 1 1)
					(thickness 0.15)
				)
				(justify mirror)
			)
		)
		(property "Tolerance" "1%"
			(at 178.2 355.4 0)
			(layer "B.Fab")
			(hide yes)
			(effects
				(font
					(size 1 1)
					(thickness 0.15)
				)
				(justify mirror)
			)
		)
		(property "Val" "10k"
			(at 178.2 355.4 0)
			(layer "B.Fab")
			(hide yes)
			(effects
				(font
					(size 1 1)
					(thickness 0.15)
				)
				(justify mirror)
			)
		)
		(sheetname "User GPIO + LED + button + DIP switch")
		(sheetfile "user-gpio.kicad_sch")
		(attr smd)
		(fp_rect
			(start -0.925 0.47)
			(end 0.925 -0.47)
			(stroke
				(width 0.05)
				(type default)
			)
			(fill no)
			(layer "B.CrtYd")
		)
		(fp_rect
			(start -0.5 0.25)
			(end 0.5 -0.25)
			(stroke
				(width 0.15)
				(type solid)
			)
			(fill no)
			(layer "B.Fab")
		)
		(pad "1" smd roundrect
			(at -0.48 0 270)
			(size 0.59 0.64)
			(layers "B.Cu" "B.Mask" "B.Paste")
			(roundrect_rratio 0.25)
			(net 26 "+1V8")
			(pintype "passive")
		)
		(pad "2" smd roundrect
			(at 0.48 0 270)
			(size 0.59 0.64)
			(layers "B.Cu" "B.Mask" "B.Paste")
			(roundrect_rratio 0.25)
			(net 1233 "/USER_IO.BUTTON2")
			(pintype "passive")
		)
	)
	(footprint "antmicro-footprints:R_0402_1005Metric"
		(layer "B.Cu")
		(at 261.5 79)
		(descr "Resistor SMD 0402")
		(tags "resistor SMD 0402")
		(property "Reference" "R130"
			(at 1.45 1.25 180)
			(layer "B.SilkS")
			(effects
				(font
					(size 0.7 0.7)
					(thickness 0.15)
				)
				(justify left bottom mirror)
			)
		)
		(property "Value" "R_1k_0402"
			(at 0 -1.4 180)
			(layer "B.Fab")
			(effects
				(font
					(size 0.7 0.7)
					(thickness 0.15)
				)
				(justify left bottom mirror)
			)
		)
		(property "Description" "SMD Chip Resistor, 1 kohm, ± 1%, 63 mW, 0402 [1005 Metric], Thick Film, General Purpose"
			(at 0 0 0)
			(layer "F.Fab")
			(hide yes)
			(effects
				(font
					(size 1.27 1.27)
					(thickness 0.15)
				)
			)
		)
		(property "Author" "Antmicro"
			(at 0 0 0)
			(layer "B.Fab")
			(hide yes)
			(effects
				(font
					(size 1 1)
					(thickness 0.15)
				)
				(justify mirror)
			)
		)
		(property "License" "Apache-2.0"
			(at 0 0 0)
			(layer "B.Fab")
			(hide yes)
			(effects
				(font
					(size 1 1)
					(thickness 0.15)
				)
				(justify mirror)
			)
		)
		(property "MPN" "CR0402-FX-1001GLF"
			(at 0 0 0)
			(layer "B.Fab")
			(hide yes)
			(effects
				(font
					(size 1 1)
					(thickness 0.15)
				)
				(justify mirror)
			)
		)
		(property "Manufacturer" "Bourns"
			(at 0 0 0)
			(layer "B.Fab")
			(hide yes)
			(effects
				(font
					(size 1 1)
					(thickness 0.15)
				)
				(justify mirror)
			)
		)
		(property "Tolerance" "1%"
			(at 0 0 0)
			(layer "B.Fab")
			(hide yes)
			(effects
				(font
					(size 1 1)
					(thickness 0.15)
				)
				(justify mirror)
			)
		)
		(property "Val" "1k"
			(at 0 0 0)
			(layer "B.Fab")
			(hide yes)
			(effects
				(font
					(size 1 1)
					(thickness 0.15)
				)
				(justify mirror)
			)
		)
		(sheetname "User GPIO + LED + button + DIP switch")
		(sheetfile "user-gpio.kicad_sch")
		(attr smd)
		(fp_rect
			(start -0.925 0.47)
			(end 0.925 -0.47)
			(stroke
				(width 0.05)
				(type default)
			)
			(fill no)
			(layer "B.CrtYd")
		)
		(fp_rect
			(start -0.5 0.25)
			(end 0.5 -0.25)
			(stroke
				(width 0.15)
				(type solid)
			)
			(fill no)
			(layer "B.Fab")
		)
		(pad "1" smd roundrect
			(at -0.48 0)
			(size 0.59 0.64)
			(layers "B.Cu" "B.Mask" "B.Paste")
			(roundrect_rratio 0.25)
			(net 24 "+3V3")
			(pintype "passive")
		)
		(pad "2" smd roundrect
			(at 0.48 0)
			(size 0.59 0.64)
			(layers "B.Cu" "B.Mask" "B.Paste")
			(roundrect_rratio 0.25)
			(net 773 "Net-(D24-A)")
			(pintype "passive")
		)
	)
	(footprint "antmicro-footprints:C_0402_1005Metric"
		(layer "B.Cu")
		(at 174.499999 147.999999 -90)
		(descr "Capacitor SMD 0402")
		(tags "capacitor SMD 0402")
		(property "Reference" "C183"
			(at 0.775001 -0.400001 90)
			(layer "B.SilkS")
			(effects
				(font
					(size 0.7 0.7)
					(thickness 0.15)
				)
				(justify left bottom mirror)
			)
		)
		(property "Value" "C_100n_0402"
			(at 0 -1.169 90)
			(layer "B.Fab")
			(effects
				(font
					(size 0.7 0.7)
					(thickness 0.15)
				)
				(justify left bottom mirror)
			)
		)
		(property "Description" "SMD Multilayer Ceramic Capacitor, 0.1 µF, 50 V, 0402 [1005 Metric], ± 10%, X5R, GRM Series"
			(at 0 0 270)
			(layer "F.Fab")
			(hide yes)
			(effects
				(font
					(size 1.27 1.27)
					(thickness 0.15)
				)
			)
		)
		(property "Author" "Antmicro"
			(at 26.5 322.499998 0)
			(layer "B.Fab")
			(hide yes)
			(effects
				(font
					(size 1 1)
					(thickness 0.15)
				)
				(justify mirror)
			)
		)
		(property "Dielectric" "X5R"
			(at 26.5 322.499998 0)
			(layer "B.Fab")
			(hide yes)
			(effects
				(font
					(size 1 1)
					(thickness 0.15)
				)
				(justify mirror)
			)
		)
		(property "License" "Apache-2.0"
			(at 26.5 322.499998 0)
			(layer "B.Fab")
			(hide yes)
			(effects
				(font
					(size 1 1)
					(thickness 0.15)
				)
				(justify mirror)
			)
		)
		(property "MPN" "GRM155R61H104KE14D"
			(at 26.5 322.499998 0)
			(layer "B.Fab")
			(hide yes)
			(effects
				(font
					(size 1 1)
					(thickness 0.15)
				)
				(justify mirror)
			)
		)
		(property "Manufacturer" "Murata"
			(at 26.5 322.499998 0)
			(layer "B.Fab")
			(hide yes)
			(effects
				(font
					(size 1 1)
					(thickness 0.15)
				)
				(justify mirror)
			)
		)
		(property "Val" "100n"
			(at 26.5 322.499998 0)
			(layer "B.Fab")
			(hide yes)
			(effects
				(font
					(size 1 1)
					(thickness 0.15)
				)
				(justify mirror)
			)
		)
		(property "Voltage" "50V"
			(at 26.5 322.499998 0)
			(layer "B.Fab")
			(hide yes)
			(effects
				(font
					(size 1 1)
					(thickness 0.15)
				)
				(justify mirror)
			)
		)
		(sheetname "DRAM + SRAM")
		(sheetfile "ram.kicad_sch")
		(attr smd)
		(fp_rect
			(start -0.925 0.47)
			(end 0.925 -0.47)
			(stroke
				(width 0.05)
				(type default)
			)
			(fill no)
			(layer "B.CrtYd")
		)
		(fp_line
			(start -0.494 0.25)
			(end 0.504 0.25)
			(stroke
				(width 0.15)
				(type solid)
			)
			(layer "B.Fab")
		)
		(fp_line
			(start 0.504 0.25)
			(end 0.504 -0.248)
			(stroke
				(width 0.15)
				(type solid)
			)
			(layer "B.Fab")
		)
		(fp_line
			(start -0.494 -0.248)
			(end -0.494 0.25)
			(stroke
				(width 0.15)
				(type solid)
			)
			(layer "B.Fab")
		)
		(fp_line
			(start 0.504 -0.248)
			(end -0.494 -0.248)
			(stroke
				(width 0.15)
				(type solid)
			)
			(layer "B.Fab")
		)
		(pad "1" smd roundrect
			(at -0.48 0 270)
			(size 0.59 0.64)
			(layers "B.Cu" "B.Mask" "B.Paste")
			(roundrect_rratio 0.25)
			(net 1 "GND")
			(pintype "passive")
		)
		(pad "2" smd roundrect
			(at 0.48 0 270)
			(size 0.59 0.64)
			(layers "B.Cu" "B.Mask" "B.Paste")
			(roundrect_rratio 0.25)
			(net 25 "+1V35")
			(pintype "passive")
		)
	)
	(footprint "antmicro-footprints:C_0402_1005Metric"
		(layer "B.Cu")
		(at 228.1 165.4 90)
		(descr "Capacitor SMD 0402")
		(tags "capacitor SMD 0402")
		(property "Reference" "C192"
			(at 3.675 0.375 270)
			(layer "B.SilkS")
			(effects
				(font
					(size 0.7 0.7)
					(thickness 0.15)
				)
				(justify left bottom mirror)
			)
		)
		(property "Value" "C_1u_0402"
			(at 0 -1.4 270)
			(layer "B.Fab")
			(effects
				(font
					(size 0.7 0.7)
					(thickness 0.15)
				)
				(justify left bottom mirror)
			)
		)
		(property "Description" "SMD Multilayer Ceramic Capacitor, 1 µF, 10 V, 0402 [1005 Metric], ± 10%, X6S, C"
			(at 0 0 90)
			(layer "F.Fab")
			(hide yes)
			(effects
				(font
					(size 1.27 1.27)
					(thickness 0.15)
				)
			)
		)
		(property "Author" "Antmicro"
			(at 393.5 -62.7 0)
			(layer "B.Fab")
			(hide yes)
			(effects
				(font
					(size 1 1)
					(thickness 0.15)
				)
				(justify mirror)
			)
		)
		(property "Dielectric" ""
			(at 393.5 -62.7 0)
			(layer "B.Fab")
			(hide yes)
			(effects
				(font
					(size 1 1)
					(thickness 0.15)
				)
				(justify mirror)
			)
		)
		(property "License" "Apache-2.0"
			(at 393.5 -62.7 0)
			(layer "B.Fab")
			(hide yes)
			(effects
				(font
					(size 1 1)
					(thickness 0.15)
				)
				(justify mirror)
			)
		)
		(property "MPN" "C1005X6S1A105K050BC"
			(at 393.5 -62.7 0)
			(layer "B.Fab")
			(hide yes)
			(effects
				(font
					(size 1 1)
					(thickness 0.15)
				)
				(justify mirror)
			)
		)
		(property "Manufacturer" "TDK"
			(at 393.5 -62.7 0)
			(layer "B.Fab")
			(hide yes)
			(effects
				(font
					(size 1 1)
					(thickness 0.15)
				)
				(justify mirror)
			)
		)
		(property "Val" "1u"
			(at 393.5 -62.7 0)
			(layer "B.Fab")
			(hide yes)
			(effects
				(font
					(size 1 1)
					(thickness 0.15)
				)
				(justify mirror)
			)
		)
		(property "Voltage" ""
			(at 393.5 -62.7 0)
			(layer "B.Fab")
			(hide yes)
			(effects
				(font
					(size 1 1)
					(thickness 0.15)
				)
				(justify mirror)
			)
		)
		(sheetname "Power supply")
		(sheetfile "power-supply.kicad_sch")
		(attr smd)
		(fp_rect
			(start -0.925 0.47)
			(end 0.925 -0.47)
			(stroke
				(width 0.05)
				(type default)
			)
			(fill no)
			(layer "B.CrtYd")
		)
		(fp_line
			(start 0.504 -0.248)
			(end -0.494 -0.248)
			(stroke
				(width 0.15)
				(type solid)
			)
			(layer "B.Fab")
		)
		(fp_line
			(start -0.494 -0.248)
			(end -0.494 0.25)
			(stroke
				(width 0.15)
				(type solid)
			)
			(layer "B.Fab")
		)
		(fp_line
			(start 0.504 0.25)
			(end 0.504 -0.248)
			(stroke
				(width 0.15)
				(type solid)
			)
			(layer "B.Fab")
		)
		(fp_line
			(start -0.494 0.25)
			(end 0.504 0.25)
			(stroke
				(width 0.15)
				(type solid)
			)
			(layer "B.Fab")
		)
		(pad "1" smd roundrect
			(at -0.48 0 90)
			(size 0.59 0.64)
			(layers "B.Cu" "B.Mask" "B.Paste")
			(roundrect_rratio 0.25)
			(net 143 "/Power supply/VREG_1V2")
			(pintype "passive")
		)
		(pad "2" smd roundrect
			(at 0.48 0 90)
			(size 0.59 0.64)
			(layers "B.Cu" "B.Mask" "B.Paste")
			(roundrect_rratio 0.25)
			(net 1 "GND")
			(pintype "passive")
		)
	)
	(footprint "antmicro-footprints:C_0402_1005Metric"
		(layer "B.Cu")
		(at 205.5 127 -90)
		(descr "Capacitor SMD 0402")
		(tags "capacitor SMD 0402")
		(property "Reference" "C14"
			(at -31.025 -28.65 90)
			(layer "B.SilkS")
			(effects
				(font
					(size 0.7 0.7)
					(thickness 0.15)
				)
				(justify left bottom mirror)
			)
		)
		(property "Value" "C_100n_0402"
			(at 0 -1.169 90)
			(layer "B.Fab")
			(effects
				(font
					(size 0.7 0.7)
					(thickness 0.15)
				)
				(justify left bottom mirror)
			)
		)
		(property "Description" "SMD Multilayer Ceramic Capacitor, 0.1 µF, 50 V, 0402 [1005 Metric], ± 10%, X5R, GRM Series"
			(at 0 0 270)
			(layer "F.Fab")
			(hide yes)
			(effects
				(font
					(size 1.27 1.27)
					(thickness 0.15)
				)
			)
		)
		(property "Author" "Antmicro"
			(at 78.5 332.5 0)
			(layer "B.Fab")
			(hide yes)
			(effects
				(font
					(size 1 1)
					(thickness 0.15)
				)
				(justify mirror)
			)
		)
		(property "Dielectric" "X5R"
			(at 78.5 332.5 0)
			(layer "B.Fab")
			(hide yes)
			(effects
				(font
					(size 1 1)
					(thickness 0.15)
				)
				(justify mirror)
			)
		)
		(property "License" "Apache-2.0"
			(at 78.5 332.5 0)
			(layer "B.Fab")
			(hide yes)
			(effects
				(font
					(size 1 1)
					(thickness 0.15)
				)
				(justify mirror)
			)
		)
		(property "MPN" "GRM155R61H104KE14D"
			(at 78.5 332.5 0)
			(layer "B.Fab")
			(hide yes)
			(effects
				(font
					(size 1 1)
					(thickness 0.15)
				)
				(justify mirror)
			)
		)
		(property "Manufacturer" "Murata"
			(at 78.5 332.5 0)
			(layer "B.Fab")
			(hide yes)
			(effects
				(font
					(size 1 1)
					(thickness 0.15)
				)
				(justify mirror)
			)
		)
		(property "Val" "100n"
			(at 78.5 332.5 0)
			(layer "B.Fab")
			(hide yes)
			(effects
				(font
					(size 1 1)
					(thickness 0.15)
				)
				(justify mirror)
			)
		)
		(property "Voltage" "50V"
			(at 78.5 332.5 0)
			(layer "B.Fab")
			(hide yes)
			(effects
				(font
					(size 1 1)
					(thickness 0.15)
				)
				(justify mirror)
			)
		)
		(sheetname "FPGA Bank 14 & 15")
		(sheetfile "fpga-bank-14-15.kicad_sch")
		(attr smd)
		(fp_rect
			(start -0.925 0.47)
			(end 0.925 -0.47)
			(stroke
				(width 0.05)
				(type default)
			)
			(fill no)
			(layer "B.CrtYd")
		)
		(fp_line
			(start -0.494 0.25)
			(end 0.504 0.25)
			(stroke
				(width 0.15)
				(type solid)
			)
			(layer "B.Fab")
		)
		(fp_line
			(start 0.504 0.25)
			(end 0.504 -0.248)
			(stroke
				(width 0.15)
				(type solid)
			)
			(layer "B.Fab")
		)
		(fp_line
			(start -0.494 -0.248)
			(end -0.494 0.25)
			(stroke
				(width 0.15)
				(type solid)
			)
			(layer "B.Fab")
		)
		(fp_line
			(start 0.504 -0.248)
			(end -0.494 -0.248)
			(stroke
				(width 0.15)
				(type solid)
			)
			(layer "B.Fab")
		)
		(pad "1" smd roundrect
			(at -0.48 0 270)
			(size 0.59 0.64)
			(layers "B.Cu" "B.Mask" "B.Paste")
			(roundrect_rratio 0.25)
			(net 1 "GND")
			(pintype "passive")
		)
		(pad "2" smd roundrect
			(at 0.48 0 270)
			(size 0.59 0.64)
			(layers "B.Cu" "B.Mask" "B.Paste")
			(roundrect_rratio 0.25)
			(net 2 "VCC_USR_A")
			(pintype "passive")
		)
	)
	(footprint "antmicro-footprints:C_0402_1005Metric"
		(layer "B.Cu")
		(at 174.649999 142.199999 -90)
		(descr "Capacitor SMD 0402")
		(tags "capacitor SMD 0402")
		(property "Reference" "C389"
			(at -1.424999 -1.300001 90)
			(layer "B.SilkS")
			(effects
				(font
					(size 0.7 0.7)
					(thickness 0.15)
				)
				(justify left bottom mirror)
			)
		)
		(property "Value" "C_100n_0402"
			(at 0 -1.169 90)
			(layer "B.Fab")
			(effects
				(font
					(size 0.7 0.7)
					(thickness 0.15)
				)
				(justify left bottom mirror)
			)
		)
		(property "Description" "SMD Multilayer Ceramic Capacitor, 0.1 µF, 50 V, 0402 [1005 Metric], ± 10%, X5R, GRM Series"
			(at 0 0 270)
			(layer "F.Fab")
			(hide yes)
			(effects
				(font
					(size 1.27 1.27)
					(thickness 0.15)
				)
			)
		)
		(property "Author" "Antmicro"
			(at 32.45 316.849998 0)
			(layer "B.Fab")
			(hide yes)
			(effects
				(font
					(size 1 1)
					(thickness 0.15)
				)
				(justify mirror)
			)
		)
		(property "Dielectric" "X5R"
			(at 32.45 316.849998 0)
			(layer "B.Fab")
			(hide yes)
			(effects
				(font
					(size 1 1)
					(thickness 0.15)
				)
				(justify mirror)
			)
		)
		(property "License" "Apache-2.0"
			(at 32.45 316.849998 0)
			(layer "B.Fab")
			(hide yes)
			(effects
				(font
					(size 1 1)
					(thickness 0.15)
				)
				(justify mirror)
			)
		)
		(property "MPN" "GRM155R61H104KE14D"
			(at 32.45 316.849998 0)
			(layer "B.Fab")
			(hide yes)
			(effects
				(font
					(size 1 1)
					(thickness 0.15)
				)
				(justify mirror)
			)
		)
		(property "Manufacturer" "Murata"
			(at 32.45 316.849998 0)
			(layer "B.Fab")
			(hide yes)
			(effects
				(font
					(size 1 1)
					(thickness 0.15)
				)
				(justify mirror)
			)
		)
		(property "Val" "100n"
			(at 32.45 316.849998 0)
			(layer "B.Fab")
			(hide yes)
			(effects
				(font
					(size 1 1)
					(thickness 0.15)
				)
				(justify mirror)
			)
		)
		(property "Voltage" "50V"
			(at 32.45 316.849998 0)
			(layer "B.Fab")
			(hide yes)
			(effects
				(font
					(size 1 1)
					(thickness 0.15)
				)
				(justify mirror)
			)
		)
		(sheetname "DRAM + SRAM")
		(sheetfile "ram.kicad_sch")
		(attr smd)
		(fp_rect
			(start -0.925 0.47)
			(end 0.925 -0.47)
			(stroke
				(width 0.05)
				(type default)
			)
			(fill no)
			(layer "B.CrtYd")
		)
		(fp_line
			(start -0.494 0.25)
			(end 0.504 0.25)
			(stroke
				(width 0.15)
				(type solid)
			)
			(layer "B.Fab")
		)
		(fp_line
			(start 0.504 0.25)
			(end 0.504 -0.248)
			(stroke
				(width 0.15)
				(type solid)
			)
			(layer "B.Fab")
		)
		(fp_line
			(start -0.494 -0.248)
			(end -0.494 0.25)
			(stroke
				(width 0.15)
				(type solid)
			)
			(layer "B.Fab")
		)
		(fp_line
			(start 0.504 -0.248)
			(end -0.494 -0.248)
			(stroke
				(width 0.15)
				(type solid)
			)
			(layer "B.Fab")
		)
		(pad "1" smd roundrect
			(at -0.48 0 270)
			(size 0.59 0.64)
			(layers "B.Cu" "B.Mask" "B.Paste")
			(roundrect_rratio 0.25)
			(net 1 "GND")
			(pintype "passive")
		)
		(pad "2" smd roundrect
			(at 0.48 0 270)
			(size 0.59 0.64)
			(layers "B.Cu" "B.Mask" "B.Paste")
			(roundrect_rratio 0.25)
			(net 25 "+1V35")
			(pintype "passive")
		)
	)
	(footprint "antmicro-footprints:C_0402_1005Metric"
		(layer "B.Cu")
		(at 157.5125 173.685 -90)
		(descr "Capacitor SMD 0402")
		(tags "capacitor SMD 0402")
		(property "Reference" "C316"
			(at 0.751 -0.3875 90)
			(layer "B.SilkS")
			(effects
				(font
					(size 0.7 0.7)
					(thickness 0.15)
				)
				(justify left bottom mirror)
			)
		)
		(property "Value" "C_1u_0402"
			(at 0 -1.4 90)
			(layer "B.Fab")
			(effects
				(font
					(size 0.7 0.7)
					(thickness 0.15)
				)
				(justify left bottom mirror)
			)
		)
		(property "Description" "SMD Multilayer Ceramic Capacitor, 1 µF, 10 V, 0402 [1005 Metric], ± 10%, X6S, C"
			(at 0 0 270)
			(layer "F.Fab")
			(hide yes)
			(effects
				(font
					(size 1.27 1.27)
					(thickness 0.15)
				)
			)
		)
		(property "Author" "Antmicro"
			(at -16.1725 331.1975 0)
			(layer "B.Fab")
			(hide yes)
			(effects
				(font
					(size 1 1)
					(thickness 0.15)
				)
				(justify mirror)
			)
		)
		(property "Dielectric" ""
			(at -16.1725 331.1975 0)
			(layer "B.Fab")
			(hide yes)
			(effects
				(font
					(size 1 1)
					(thickness 0.15)
				)
				(justify mirror)
			)
		)
		(property "License" "Apache-2.0"
			(at -16.1725 331.1975 0)
			(layer "B.Fab")
			(hide yes)
			(effects
				(font
					(size 1 1)
					(thickness 0.15)
				)
				(justify mirror)
			)
		)
		(property "MPN" "C1005X6S1A105K050BC"
			(at -16.1725 331.1975 0)
			(layer "B.Fab")
			(hide yes)
			(effects
				(font
					(size 1 1)
					(thickness 0.15)
				)
				(justify mirror)
			)
		)
		(property "Manufacturer" "TDK"
			(at -16.1725 331.1975 0)
			(layer "B.Fab")
			(hide yes)
			(effects
				(font
					(size 1 1)
					(thickness 0.15)
				)
				(justify mirror)
			)
		)
		(property "Val" "1u"
			(at -16.1725 331.1975 0)
			(layer "B.Fab")
			(hide yes)
			(effects
				(font
					(size 1 1)
					(thickness 0.15)
				)
				(justify mirror)
			)
		)
		(property "Voltage" ""
			(at -16.1725 331.1975 0)
			(layer "B.Fab")
			(hide yes)
			(effects
				(font
					(size 1 1)
					(thickness 0.15)
				)
				(justify mirror)
			)
		)
		(sheetname "DC-DC Converters")
		(sheetfile "dc-dc.kicad_sch")
		(attr smd)
		(fp_rect
			(start -0.925 0.47)
			(end 0.925 -0.47)
			(stroke
				(width 0.05)
				(type default)
			)
			(fill no)
			(layer "B.CrtYd")
		)
		(fp_line
			(start -0.494 0.25)
			(end 0.504 0.25)
			(stroke
				(width 0.15)
				(type solid)
			)
			(layer "B.Fab")
		)
		(fp_line
			(start 0.504 0.25)
			(end 0.504 -0.248)
			(stroke
				(width 0.15)
				(type solid)
			)
			(layer "B.Fab")
		)
		(fp_line
			(start -0.494 -0.248)
			(end -0.494 0.25)
			(stroke
				(width 0.15)
				(type solid)
			)
			(layer "B.Fab")
		)
		(fp_line
			(start 0.504 -0.248)
			(end -0.494 -0.248)
			(stroke
				(width 0.15)
				(type solid)
			)
			(layer "B.Fab")
		)
		(pad "1" smd roundrect
			(at -0.48 0 270)
			(size 0.59 0.64)
			(layers "B.Cu" "B.Mask" "B.Paste")
			(roundrect_rratio 0.25)
			(net 1 "GND")
			(pintype "passive")
		)
		(pad "2" smd roundrect
			(at 0.48 0 270)
			(size 0.59 0.64)
			(layers "B.Cu" "B.Mask" "B.Paste")
			(roundrect_rratio 0.25)
			(net 731 "/DC-DC Converters/QDCDC1_VCC")
			(pintype "passive")
		)
	)
	(footprint "antmicro-footprints:R_0402_1005Metric"
		(layer "B.Cu")
		(at 242.501 139.1 180)
		(descr "Resistor SMD 0402")
		(tags "resistor SMD 0402")
		(property "Reference" "R163"
			(at 0.726 -0.4 0)
			(layer "B.SilkS")
			(effects
				(font
					(size 0.7 0.7)
					(thickness 0.15)
				)
				(justify left bottom mirror)
			)
		)
		(property "Value" "R_33R_0402"
			(at 0 -1.4 0)
			(layer "B.Fab")
			(effects
				(font
					(size 0.7 0.7)
					(thickness 0.15)
				)
				(justify left bottom mirror)
			)
		)
		(property "Description" "SMD Chip Resistor, 33 ohm, ± 1%, 62.5 mW, 0402 [1005 Metric], Thick Film, General Purpose"
			(at 0 0 180)
			(layer "F.Fab")
			(hide yes)
			(effects
				(font
					(size 1.27 1.27)
					(thickness 0.15)
				)
			)
		)
		(property "Author" "Antmicro"
			(at 485.002 278.2 0)
			(layer "B.Fab")
			(hide yes)
			(effects
				(font
					(size 1 1)
					(thickness 0.15)
				)
				(justify mirror)
			)
		)
		(property "License" "Apache-2.0"
			(at 485.002 278.2 0)
			(layer "B.Fab")
			(hide yes)
			(effects
				(font
					(size 1 1)
					(thickness 0.15)
				)
				(justify mirror)
			)
		)
		(property "MPN" "CR0402-FX-33R0GLF"
			(at 485.002 278.2 0)
			(layer "B.Fab")
			(hide yes)
			(effects
				(font
					(size 1 1)
					(thickness 0.15)
				)
				(justify mirror)
			)
		)
		(property "Manufacturer" "Bourns"
			(at 485.002 278.2 0)
			(layer "B.Fab")
			(hide yes)
			(effects
				(font
					(size 1 1)
					(thickness 0.15)
				)
				(justify mirror)
			)
		)
		(property "Tolerance" "1%"
			(at 485.002 278.2 0)
			(layer "B.Fab")
			(hide yes)
			(effects
				(font
					(size 1 1)
					(thickness 0.15)
				)
				(justify mirror)
			)
		)
		(property "Val" "33R"
			(at 485.002 278.2 0)
			(layer "B.Fab")
			(hide yes)
			(effects
				(font
					(size 1 1)
					(thickness 0.15)
				)
				(justify mirror)
			)
		)
		(sheetname "USB PHY")
		(sheetfile "usb-phy.kicad_sch")
		(attr smd)
		(fp_rect
			(start -0.925 0.47)
			(end 0.925 -0.47)
			(stroke
				(width 0.05)
				(type default)
			)
			(fill no)
			(layer "B.CrtYd")
		)
		(fp_rect
			(start -0.5 0.25)
			(end 0.5 -0.25)
			(stroke
				(width 0.15)
				(type solid)
			)
			(fill no)
			(layer "B.Fab")
		)
		(pad "1" smd roundrect
			(at -0.48 0 180)
			(size 0.59 0.64)
			(layers "B.Cu" "B.Mask" "B.Paste")
			(roundrect_rratio 0.25)
			(net 923 "/USB PHY/FTDI_UART1_TX")
			(pintype "passive")
		)
		(pad "2" smd roundrect
			(at 0.48 0 180)
			(size 0.59 0.64)
			(layers "B.Cu" "B.Mask" "B.Paste")
			(roundrect_rratio 0.25)
			(net 45 "/FPGA Bank 12 & 13/UART1.RX")
			(pintype "passive")
		)
	)
	(footprint "antmicro-footprints:C_0402_1005Metric"
		(layer "B.Cu")
		(at 207 137.52)
		(descr "Capacitor SMD 0402")
		(tags "capacitor SMD 0402")
		(property "Reference" "C35"
			(at 1.45 -0.475 180)
			(layer "B.SilkS")
			(effects
				(font
					(size 0.7 0.7)
					(thickness 0.15)
				)
				(justify left bottom mirror)
			)
		)
		(property "Value" "C_100n_0402"
			(at 0 -1.169 180)
			(layer "B.Fab")
			(effects
				(font
					(size 0.7 0.7)
					(thickness 0.15)
				)
				(justify left bottom mirror)
			)
		)
		(property "Description" "SMD Multilayer Ceramic Capacitor, 0.1 µF, 50 V, 0402 [1005 Metric], ± 10%, X5R, GRM Series"
			(at 0 0 0)
			(layer "F.Fab")
			(hide yes)
			(effects
				(font
					(size 1.27 1.27)
					(thickness 0.15)
				)
			)
		)
		(property "Author" "Antmicro"
			(at 0 0 0)
			(layer "B.Fab")
			(hide yes)
			(effects
				(font
					(size 1 1)
					(thickness 0.15)
				)
				(justify mirror)
			)
		)
		(property "Dielectric" "X5R"
			(at 0 0 0)
			(layer "B.Fab")
			(hide yes)
			(effects
				(font
					(size 1 1)
					(thickness 0.15)
				)
				(justify mirror)
			)
		)
		(property "License" "Apache-2.0"
			(at 0 0 0)
			(layer "B.Fab")
			(hide yes)
			(effects
				(font
					(size 1 1)
					(thickness 0.15)
				)
				(justify mirror)
			)
		)
		(property "MPN" "GRM155R61H104KE14D"
			(at 0 0 0)
			(layer "B.Fab")
			(hide yes)
			(effects
				(font
					(size 1 1)
					(thickness 0.15)
				)
				(justify mirror)
			)
		)
		(property "Manufacturer" "Murata"
			(at 0 0 0)
			(layer "B.Fab")
			(hide yes)
			(effects
				(font
					(size 1 1)
					(thickness 0.15)
				)
				(justify mirror)
			)
		)
		(property "Val" "100n"
			(at 0 0 0)
			(layer "B.Fab")
			(hide yes)
			(effects
				(font
					(size 1 1)
					(thickness 0.15)
				)
				(justify mirror)
			)
		)
		(property "Voltage" "50V"
			(at 0 0 0)
			(layer "B.Fab")
			(hide yes)
			(effects
				(font
					(size 1 1)
					(thickness 0.15)
				)
				(justify mirror)
			)
		)
		(sheetname "FPGA Bank 12 & 13")
		(sheetfile "fpga-bank-12-13.kicad_sch")
		(attr smd)
		(fp_rect
			(start -0.925 0.47)
			(end 0.925 -0.47)
			(stroke
				(width 0.05)
				(type default)
			)
			(fill no)
			(layer "B.CrtYd")
		)
		(fp_line
			(start -0.494 -0.248)
			(end -0.494 0.25)
			(stroke
				(width 0.15)
				(type solid)
			)
			(layer "B.Fab")
		)
		(fp_line
			(start -0.494 0.25)
			(end 0.504 0.25)
			(stroke
				(width 0.15)
				(type solid)
			)
			(layer "B.Fab")
		)
		(fp_line
			(start 0.504 -0.248)
			(end -0.494 -0.248)
			(stroke
				(width 0.15)
				(type solid)
			)
			(layer "B.Fab")
		)
		(fp_line
			(start 0.504 0.25)
			(end 0.504 -0.248)
			(stroke
				(width 0.15)
				(type solid)
			)
			(layer "B.Fab")
		)
		(pad "1" smd roundrect
			(at -0.48 0)
			(size 0.59 0.64)
			(layers "B.Cu" "B.Mask" "B.Paste")
			(roundrect_rratio 0.25)
			(net 1 "GND")
			(pintype "passive")
		)
		(pad "2" smd roundrect
			(at 0.48 0)
			(size 0.59 0.64)
			(layers "B.Cu" "B.Mask" "B.Paste")
			(roundrect_rratio 0.25)
			(net 24 "+3V3")
			(pintype "passive")
		)
	)
	(footprint "antmicro-footprints:R_0402_1005Metric"
		(layer "B.Cu")
		(at 223.586 149.2 180)
		(descr "Resistor SMD 0402")
		(tags "resistor SMD 0402")
		(property "Reference" "R227"
			(at -1.839 -2.35 0)
			(layer "B.SilkS")
			(effects
				(font
					(size 0.7 0.7)
					(thickness 0.15)
				)
				(justify left bottom mirror)
			)
		)
		(property "Value" "R_2k2_0402"
			(at 0 -1.4 0)
			(layer "B.Fab")
			(effects
				(font
					(size 0.7 0.7)
					(thickness 0.15)
				)
				(justify left bottom mirror)
			)
		)
		(property "Description" "SMD Chip Resistor, 2.2 kohm, ± 1%, 62.5 mW, 0402 [1005 Metric], Thick Film, General Purpose"
			(at 0 0 180)
			(layer "F.Fab")
			(hide yes)
			(effects
				(font
					(size 1.27 1.27)
					(thickness 0.15)
				)
			)
		)
		(property "Author" "Antmicro"
			(at 447.172 298.4 0)
			(layer "B.Fab")
			(hide yes)
			(effects
				(font
					(size 1 1)
					(thickness 0.15)
				)
				(justify mirror)
			)
		)
		(property "DNP" "DNP"
			(at 447.172 298.4 0)
			(layer "B.Fab")
			(hide yes)
			(effects
				(font
					(size 1 1)
					(thickness 0.15)
				)
				(justify mirror)
			)
		)
		(property "License" "Apache-2.0"
			(at 447.172 298.4 0)
			(layer "B.Fab")
			(hide yes)
			(effects
				(font
					(size 1 1)
					(thickness 0.15)
				)
				(justify mirror)
			)
		)
		(property "MPN" "CR0402-FX-2201GLF"
			(at 447.172 298.4 0)
			(layer "B.Fab")
			(hide yes)
			(effects
				(font
					(size 1 1)
					(thickness 0.15)
				)
				(justify mirror)
			)
		)
		(property "Manufacturer" "Bourns"
			(at 447.172 298.4 0)
			(layer "B.Fab")
			(hide yes)
			(effects
				(font
					(size 1 1)
					(thickness 0.15)
				)
				(justify mirror)
			)
		)
		(property "Tolerance" "1%"
			(at 447.172 298.4 0)
			(layer "B.Fab")
			(hide yes)
			(effects
				(font
					(size 1 1)
					(thickness 0.15)
				)
				(justify mirror)
			)
		)
		(property "Val" "2k2"
			(at 447.172 298.4 0)
			(layer "B.Fab")
			(hide yes)
			(effects
				(font
					(size 1 1)
					(thickness 0.15)
				)
				(justify mirror)
			)
		)
		(property "dnp" ""
			(at 447.172 298.4 0)
			(layer "B.Fab")
			(hide yes)
			(effects
				(font
					(size 1 1)
					(thickness 0.15)
				)
				(justify mirror)
			)
		)
		(property "exclude_from_bom" ""
			(at 447.172 298.4 0)
			(layer "B.Fab")
			(hide yes)
			(effects
				(font
					(size 1 1)
					(thickness 0.15)
				)
				(justify mirror)
			)
		)
		(sheetname "HDMI + Ethernet")
		(sheetfile "hdmi-ethernet.kicad_sch")
		(attr smd exclude_from_bom)
		(fp_rect
			(start -0.925 0.47)
			(end 0.925 -0.47)
			(stroke
				(width 0.05)
				(type default)
			)
			(fill no)
			(layer "B.CrtYd")
		)
		(fp_rect
			(start -0.5 0.25)
			(end 0.5 -0.25)
			(stroke
				(width 0.15)
				(type solid)
			)
			(fill no)
			(layer "B.Fab")
		)
		(pad "1" smd roundrect
			(at -0.48 0 180)
			(size 0.59 0.64)
			(layers "B.Cu" "B.Mask" "B.Paste")
			(roundrect_rratio 0.25)
			(net 946 "/HDMI + Ethernet/ETH_PHY_RXDO")
			(pintype "passive")
		)
		(pad "2" smd roundrect
			(at 0.48 0 180)
			(size 0.59 0.64)
			(layers "B.Cu" "B.Mask" "B.Paste")
			(roundrect_rratio 0.25)
			(net 1 "GND")
			(pintype "passive")
		)
	)
	(footprint "antmicro-footprints:C_0201"
		(layer "B.Cu")
		(at 189.8 121.5 180)
		(descr "Capacitor SMD 0201")
		(tags "capacitor SMD 0201")
		(property "Reference" "C148"
			(at -22.625 29.63 0)
			(layer "B.SilkS")
			(effects
				(font
					(size 0.7 0.7)
					(thickness 0.15)
				)
				(justify left bottom mirror)
			)
		)
		(property "Value" "C_100n_0201"
			(at 0 -1.4 0)
			(layer "B.Fab")
			(effects
				(font
					(size 0.7 0.7)
					(thickness 0.15)
				)
				(justify left bottom mirror)
			)
		)
		(property "Description" "SMD Multilayer Ceramic Capacitor, 0.1 µF, 6.3 V, 0201 [0603 Metric], ± 10%, X6S, CC Series"
			(at 0 0 180)
			(layer "F.Fab")
			(hide yes)
			(effects
				(font
					(size 1.27 1.27)
					(thickness 0.15)
				)
			)
		)
		(property "Author" "Antmicro"
			(at 379.6 243 0)
			(layer "B.Fab")
			(hide yes)
			(effects
				(font
					(size 1 1)
					(thickness 0.15)
				)
				(justify mirror)
			)
		)
		(property "Dielectric" ""
			(at 379.6 243 0)
			(layer "B.Fab")
			(hide yes)
			(effects
				(font
					(size 1 1)
					(thickness 0.15)
				)
				(justify mirror)
			)
		)
		(property "License" "Apache-2.0"
			(at 379.6 243 0)
			(layer "B.Fab")
			(hide yes)
			(effects
				(font
					(size 1 1)
					(thickness 0.15)
				)
				(justify mirror)
			)
		)
		(property "MPN" "CC0201KRX6S5BB104"
			(at 379.6 243 0)
			(layer "B.Fab")
			(hide yes)
			(effects
				(font
					(size 1 1)
					(thickness 0.15)
				)
				(justify mirror)
			)
		)
		(property "Manufacturer" "YAGEO"
			(at 379.6 243 0)
			(layer "B.Fab")
			(hide yes)
			(effects
				(font
					(size 1 1)
					(thickness 0.15)
				)
				(justify mirror)
			)
		)
		(property "Val" "100n"
			(at 379.6 243 0)
			(layer "B.Fab")
			(hide yes)
			(effects
				(font
					(size 1 1)
					(thickness 0.15)
				)
				(justify mirror)
			)
		)
		(property "Voltage" ""
			(at 379.6 243 0)
			(layer "B.Fab")
			(hide yes)
			(effects
				(font
					(size 1 1)
					(thickness 0.15)
				)
				(justify mirror)
			)
		)
		(sheetname "FPGA supply")
		(sheetfile "fpga-supply.kicad_sch")
		(attr smd)
		(fp_rect
			(start -0.7 0.35)
			(end 0.7 -0.35)
			(stroke
				(width 0.05)
				(type default)
			)
			(fill no)
			(layer "B.CrtYd")
		)
		(fp_rect
			(start 0.3 -0.15)
			(end -0.301 0.149)
			(stroke
				(width 0.15)
				(type solid)
			)
			(fill no)
			(layer "B.Fab")
		)
		(pad "" smd roundrect
			(at -0.349 0.002 180)
			(size 0.318 0.36)
			(layers "B.Paste")
			(roundrect_rratio 0.25)
		)
		(pad "" smd roundrect
			(at 0.341 0.002 180)
			(size 0.318 0.36)
			(layers "B.Paste")
			(roundrect_rratio 0.25)
		)
		(pad "1" smd roundrect
			(at -0.321 0.002 180)
			(size 0.46 0.4)
			(layers "B.Cu" "B.Mask")
			(roundrect_rratio 0.25)
			(net 1 "GND")
			(pintype "passive")
		)
		(pad "2" smd roundrect
			(at 0.32 0.002 180)
			(size 0.46 0.4)
			(layers "B.Cu" "B.Mask")
			(roundrect_rratio 0.25)
			(net 8 "+1V2_MGTAVTT")
			(pintype "passive")
		)
	)
	(footprint "antmicro-footprints:R_0402_1005Metric"
		(layer "B.Cu")
		(at 198.491252 92.55)
		(descr "Resistor SMD 0402")
		(tags "resistor SMD 0402")
		(property "Reference" "R210"
			(at 1.483748 -4.6 180)
			(layer "B.SilkS")
			(effects
				(font
					(size 0.7 0.7)
					(thickness 0.15)
				)
				(justify left bottom mirror)
			)
		)
		(property "Value" "R_2k2_0402"
			(at 0 -1.4 180)
			(layer "B.Fab")
			(effects
				(font
					(size 0.7 0.7)
					(thickness 0.15)
				)
				(justify left bottom mirror)
			)
		)
		(property "Description" "SMD Chip Resistor, 2.2 kohm, ± 1%, 62.5 mW, 0402 [1005 Metric], Thick Film, General Purpose"
			(at 0 0 0)
			(layer "F.Fab")
			(hide yes)
			(effects
				(font
					(size 1.27 1.27)
					(thickness 0.15)
				)
			)
		)
		(property "Author" "Antmicro"
			(at 0 0 0)
			(layer "B.Fab")
			(hide yes)
			(effects
				(font
					(size 1 1)
					(thickness 0.15)
				)
				(justify mirror)
			)
		)
		(property "DNP" "DNP"
			(at 0 0 0)
			(layer "B.Fab")
			(hide yes)
			(effects
				(font
					(size 1 1)
					(thickness 0.15)
				)
				(justify mirror)
			)
		)
		(property "License" "Apache-2.0"
			(at 0 0 0)
			(layer "B.Fab")
			(hide yes)
			(effects
				(font
					(size 1 1)
					(thickness 0.15)
				)
				(justify mirror)
			)
		)
		(property "MPN" "CR0402-FX-2201GLF"
			(at 0 0 0)
			(layer "B.Fab")
			(hide yes)
			(effects
				(font
					(size 1 1)
					(thickness 0.15)
				)
				(justify mirror)
			)
		)
		(property "Manufacturer" "Bourns"
			(at 0 0 0)
			(layer "B.Fab")
			(hide yes)
			(effects
				(font
					(size 1 1)
					(thickness 0.15)
				)
				(justify mirror)
			)
		)
		(property "Tolerance" "1%"
			(at 0 0 0)
			(layer "B.Fab")
			(hide yes)
			(effects
				(font
					(size 1 1)
					(thickness 0.15)
				)
				(justify mirror)
			)
		)
		(property "Val" "2k2"
			(at 0 0 0)
			(layer "B.Fab")
			(hide yes)
			(effects
				(font
					(size 1 1)
					(thickness 0.15)
				)
				(justify mirror)
			)
		)
		(property "dnp" ""
			(at 0 0 0)
			(layer "B.Fab")
			(hide yes)
			(effects
				(font
					(size 1 1)
					(thickness 0.15)
				)
				(justify mirror)
			)
		)
		(property "exclude_from_bom" ""
			(at 0 0 0)
			(layer "B.Fab")
			(hide yes)
			(effects
				(font
					(size 1 1)
					(thickness 0.15)
				)
				(justify mirror)
			)
		)
		(sheetname "HDMI + Ethernet")
		(sheetfile "hdmi-ethernet.kicad_sch")
		(attr smd exclude_from_bom)
		(fp_rect
			(start -0.925 0.47)
			(end 0.925 -0.47)
			(stroke
				(width 0.05)
				(type default)
			)
			(fill no)
			(layer "B.CrtYd")
		)
		(fp_rect
			(start -0.5 0.25)
			(end 0.5 -0.25)
			(stroke
				(width 0.15)
				(type solid)
			)
			(fill no)
			(layer "B.Fab")
		)
		(pad "1" smd roundrect
			(at -0.48 0)
			(size 0.59 0.64)
			(layers "B.Cu" "B.Mask" "B.Paste")
			(roundrect_rratio 0.25)
			(net 504 "/FPGA Bank 16 & 17/GBE_RGMII.RXD2")
			(pintype "passive")
		)
		(pad "2" smd roundrect
			(at 0.48 0)
			(size 0.59 0.64)
			(layers "B.Cu" "B.Mask" "B.Paste")
			(roundrect_rratio 0.25)
			(net 1 "GND")
			(pintype "passive")
		)
	)
	(footprint "antmicro-footprints:C_0603_1608Metric"
		(layer "B.Cu")
		(at 200 126.1 -90)
		(descr "Capacitor SMD 0603")
		(tags "capacitor 0603")
		(property "Reference" "C377"
			(at -31.3 -25.75 90)
			(layer "B.SilkS")
			(effects
				(font
					(size 0.7 0.7)
					(thickness 0.15)
				)
				(justify left bottom mirror)
			)
		)
		(property "Value" "C_47u_0603"
			(at 0 -1.6 90)
			(layer "B.Fab")
			(effects
				(font
					(size 0.7 0.7)
					(thickness 0.15)
				)
				(justify left bottom mirror)
			)
		)
		(property "Description" "SMD Multilayer Ceramic Capacitor, 47 µF, 6.3 V, 0603 [1608 Metric], ± 20%, X5R, GRM Series"
			(at 0 0 270)
			(layer "F.Fab")
			(hide yes)
			(effects
				(font
					(size 1.27 1.27)
					(thickness 0.15)
				)
			)
		)
		(property "Author" "Antmicro"
			(at 73.9 326.1 0)
			(layer "B.Fab")
			(hide yes)
			(effects
				(font
					(size 1 1)
					(thickness 0.15)
				)
				(justify mirror)
			)
		)
		(property "Dielectric" ""
			(at 73.9 326.1 0)
			(layer "B.Fab")
			(hide yes)
			(effects
				(font
					(size 1 1)
					(thickness 0.15)
				)
				(justify mirror)
			)
		)
		(property "License" "Apache-2.0"
			(at 73.9 326.1 0)
			(layer "B.Fab")
			(hide yes)
			(effects
				(font
					(size 1 1)
					(thickness 0.15)
				)
				(justify mirror)
			)
		)
		(property "MPN" "GRM188R60J476ME15D"
			(at 73.9 326.1 0)
			(layer "B.Fab")
			(hide yes)
			(effects
				(font
					(size 1 1)
					(thickness 0.15)
				)
				(justify mirror)
			)
		)
		(property "Manufacturer" "Murata"
			(at 73.9 326.1 0)
			(layer "B.Fab")
			(hide yes)
			(effects
				(font
					(size 1 1)
					(thickness 0.15)
				)
				(justify mirror)
			)
		)
		(property "Val" "47u"
			(at 73.9 326.1 0)
			(layer "B.Fab")
			(hide yes)
			(effects
				(font
					(size 1 1)
					(thickness 0.15)
				)
				(justify mirror)
			)
		)
		(property "Voltage" ""
			(at 73.9 326.1 0)
			(layer "B.Fab")
			(hide yes)
			(effects
				(font
					(size 1 1)
					(thickness 0.15)
				)
				(justify mirror)
			)
		)
		(sheetname "FPGA supply")
		(sheetfile "fpga-supply.kicad_sch")
		(attr smd)
		(fp_line
			(start -0.15 0.4)
			(end 0.15 0.4)
			(stroke
				(width 0.15)
				(type solid)
			)
			(layer "B.SilkS")
		)
		(fp_line
			(start -0.15 -0.4)
			(end 0.15 -0.4)
			(stroke
				(width 0.15)
				(type solid)
			)
			(layer "B.SilkS")
		)
		(fp_rect
			(start -1.25 0.65)
			(end 1.25 -0.65)
			(stroke
				(width 0.05)
				(type solid)
			)
			(fill no)
			(layer "B.CrtYd")
		)
		(fp_rect
			(start -0.8 0.4)
			(end 0.8 -0.4)
			(stroke
				(width 0.15)
				(type solid)
			)
			(fill no)
			(layer "B.Fab")
		)
		(pad "1" smd roundrect
			(at -0.7 0 270)
			(size 0.8 1)
			(layers "B.Cu" "B.Mask" "B.Paste")
			(roundrect_rratio 0.2)
			(net 1 "GND")
			(pintype "passive")
		)
		(pad "2" smd roundrect
			(at 0.7 0 270)
			(size 0.8 1)
			(layers "B.Cu" "B.Mask" "B.Paste")
			(roundrect_rratio 0.2)
			(net 650 "+1V0")
			(pintype "passive")
		)
	)
	(footprint "antmicro-footprints:C_0201"
		(layer "B.Cu")
		(at 192.3 128.2 -45)
		(descr "Capacitor SMD 0201")
		(tags "capacitor SMD 0201")
		(property "Reference" "C97"
			(at -4.224963 -35.72657 315)
			(unlocked yes)
			(layer "B.SilkS")
			(effects
				(font
					(size 0.7 0.7)
					(thickness 0.15)
				)
				(justify left bottom mirror)
			)
		)
		(property "Value" "C_100n_0201"
			(at 0 -1.399999 135)
			(layer "B.Fab")
			(effects
				(font
					(size 0.7 0.7)
					(thickness 0.15)
				)
				(justify left bottom mirror)
			)
		)
		(property "Description" "SMD Multilayer Ceramic Capacitor, 0.1 µF, 6.3 V, 0201 [0603 Metric], ± 10%, X6S, CC Series"
			(at 0 0 315)
			(layer "F.Fab")
			(hide yes)
			(effects
				(font
					(size 1.27 1.27)
					(thickness 0.15)
				)
			)
		)
		(property "Author" "Antmicro"
			(at -34.327723 173.525544 0)
			(layer "B.Fab")
			(hide yes)
			(effects
				(font
					(size 1 1)
					(thickness 0.15)
				)
				(justify mirror)
			)
		)
		(property "Dielectric" ""
			(at -34.327723 173.525544 0)
			(layer "B.Fab")
			(hide yes)
			(effects
				(font
					(size 1 1)
					(thickness 0.15)
				)
				(justify mirror)
			)
		)
		(property "License" "Apache-2.0"
			(at -34.327723 173.525544 0)
			(layer "B.Fab")
			(hide yes)
			(effects
				(font
					(size 1 1)
					(thickness 0.15)
				)
				(justify mirror)
			)
		)
		(property "MPN" "CC0201KRX6S5BB104"
			(at -34.327723 173.525544 0)
			(layer "B.Fab")
			(hide yes)
			(effects
				(font
					(size 1 1)
					(thickness 0.15)
				)
				(justify mirror)
			)
		)
		(property "Manufacturer" "YAGEO"
			(at -34.327723 173.525544 0)
			(layer "B.Fab")
			(hide yes)
			(effects
				(font
					(size 1 1)
					(thickness 0.15)
				)
				(justify mirror)
			)
		)
		(property "Val" "100n"
			(at -34.327723 173.525544 0)
			(layer "B.Fab")
			(hide yes)
			(effects
				(font
					(size 1 1)
					(thickness 0.15)
				)
				(justify mirror)
			)
		)
		(property "Voltage" ""
			(at -34.327723 173.525544 0)
			(layer "B.Fab")
			(hide yes)
			(effects
				(font
					(size 1 1)
					(thickness 0.15)
				)
				(justify mirror)
			)
		)
		(sheetname "FPGA supply")
		(sheetfile "fpga-supply.kicad_sch")
		(attr smd)
		(fp_poly
			(pts
				(xy -0.7 0.35) (xy 0.7 0.35) (xy 0.7 -0.35) (xy -0.7 -0.35)
			)
			(stroke
				(width 0.05)
				(type default)
			)
			(fill no)
			(layer "B.CrtYd")
		)
		(fp_poly
			(pts
				(xy 0.3 -0.15) (xy -0.301 -0.15) (xy -0.301 0.149) (xy 0.3 0.149)
			)
			(stroke
				(width 0.15)
				(type solid)
			)
			(fill no)
			(layer "B.Fab")
		)
		(pad "" smd roundrect
			(at -0.349 0.002 315)
			(size 0.318 0.36)
			(layers "B.Paste")
			(roundrect_rratio 0.25)
		)
		(pad "" smd roundrect
			(at 0.341 0.002 315)
			(size 0.318 0.36)
			(layers "B.Paste")
			(roundrect_rratio 0.25)
		)
		(pad "1" smd roundrect
			(at -0.321 0.002 315)
			(size 0.46 0.4)
			(layers "B.Cu" "B.Mask")
			(roundrect_rratio 0.25)
			(net 6 "+1V0_MGTAVCC")
			(pintype "passive")
		)
		(pad "2" smd roundrect
			(at 0.32 0.002 315)
			(size 0.46 0.4)
			(layers "B.Cu" "B.Mask")
			(roundrect_rratio 0.25)
			(net 1 "GND")
			(pintype "passive")
		)
	)
	(footprint "antmicro-footprints:R_0402_1005Metric"
		(layer "B.Cu")
		(at 251.101 179.05 90)
		(descr "Resistor SMD 0402")
		(tags "resistor SMD 0402")
		(property "Reference" "R53"
			(at -0.775 0.374 270)
			(layer "B.SilkS")
			(effects
				(font
					(size 0.7 0.7)
					(thickness 0.15)
				)
				(justify left bottom mirror)
			)
		)
		(property "Value" "R_1k2_0402"
			(at 0 -1.4 270)
			(layer "B.Fab")
			(effects
				(font
					(size 0.7 0.7)
					(thickness 0.15)
				)
				(justify left bottom mirror)
			)
		)
		(property "Description" "SMD Chip Resistor, 1.2 kohm, ± 1%, 62.5 mW, 0402 [1005 Metric], Thick Film, General Purpose"
			(at 0 0 90)
			(layer "F.Fab")
			(hide yes)
			(effects
				(font
					(size 1.27 1.27)
					(thickness 0.15)
				)
			)
		)
		(property "Author" "Antmicro"
			(at 430.151 -72.051 0)
			(layer "B.Fab")
			(hide yes)
			(effects
				(font
					(size 1 1)
					(thickness 0.15)
				)
				(justify mirror)
			)
		)
		(property "License" "Apache-2.0"
			(at 430.151 -72.051 0)
			(layer "B.Fab")
			(hide yes)
			(effects
				(font
					(size 1 1)
					(thickness 0.15)
				)
				(justify mirror)
			)
		)
		(property "MPN" "CR0402-FX-1201GLF"
			(at 430.151 -72.051 0)
			(layer "B.Fab")
			(hide yes)
			(effects
				(font
					(size 1 1)
					(thickness 0.15)
				)
				(justify mirror)
			)
		)
		(property "Manufacturer" "Bourns"
			(at 430.151 -72.051 0)
			(layer "B.Fab")
			(hide yes)
			(effects
				(font
					(size 1 1)
					(thickness 0.15)
				)
				(justify mirror)
			)
		)
		(property "Tolerance" "1%"
			(at 430.151 -72.051 0)
			(layer "B.Fab")
			(hide yes)
			(effects
				(font
					(size 1 1)
					(thickness 0.15)
				)
				(justify mirror)
			)
		)
		(property "Val" "1k2"
			(at 430.151 -72.051 0)
			(layer "B.Fab")
			(hide yes)
			(effects
				(font
					(size 1 1)
					(thickness 0.15)
				)
				(justify mirror)
			)
		)
		(sheetname "Power supply")
		(sheetfile "power-supply.kicad_sch")
		(attr smd)
		(fp_rect
			(start -0.925 0.47)
			(end 0.925 -0.47)
			(stroke
				(width 0.05)
				(type default)
			)
			(fill no)
			(layer "B.CrtYd")
		)
		(fp_rect
			(start -0.5 0.25)
			(end 0.5 -0.25)
			(stroke
				(width 0.15)
				(type solid)
			)
			(fill no)
			(layer "B.Fab")
		)
		(pad "1" smd roundrect
			(at -0.48 0 90)
			(size 0.59 0.64)
			(layers "B.Cu" "B.Mask" "B.Paste")
			(roundrect_rratio 0.25)
			(net 697 "/Power supply/VSS")
			(pintype "passive")
		)
		(pad "2" smd roundrect
			(at 0.48 0 90)
			(size 0.59 0.64)
			(layers "B.Cu" "B.Mask" "B.Paste")
			(roundrect_rratio 0.25)
			(net 886 "/Power supply/CLSB")
			(pintype "passive")
		)
	)
	(footprint "antmicro-footprints:R_Array_4x0201_Panasonic_EXB18V"
		(layer "B.Cu")
		(at 259.195 73.4 180)
		(property "Reference" "R133"
			(at 1.295 0.75 0)
			(layer "B.SilkS")
			(effects
				(font
					(size 0.7 0.7)
					(thickness 0.15)
				)
				(justify right bottom mirror)
			)
		)
		(property "Value" "4x10k_0201_array"
			(at -1.1 -1.8 0)
			(layer "B.Fab")
			(effects
				(font
					(size 0.7 0.7)
					(thickness 0.15)
				)
				(justify left bottom mirror)
			)
		)
		(property "Description" "Fixed Network Resistor, 10 kohm, Isolated, 4 Resistors, 0502 [1406 Metric], Flat, ± 5%"
			(at 0 0 180)
			(layer "F.Fab")
			(hide yes)
			(effects
				(font
					(size 1.27 1.27)
					(thickness 0.15)
				)
			)
		)
		(property "Author" "Antmicro"
			(at 518.39 146.8 0)
			(layer "B.Fab")
			(hide yes)
			(effects
				(font
					(size 1 1)
					(thickness 0.15)
				)
				(justify mirror)
			)
		)
		(property "License" "Apache-2.0"
			(at 518.39 146.8 0)
			(layer "B.Fab")
			(hide yes)
			(effects
				(font
					(size 1 1)
					(thickness 0.15)
				)
				(justify mirror)
			)
		)
		(property "MPN" "EXB-18V103JX"
			(at 518.39 146.8 0)
			(layer "B.Fab")
			(hide yes)
			(effects
				(font
					(size 1 1)
					(thickness 0.15)
				)
				(justify mirror)
			)
		)
		(property "Manufacturer" "Panasonic"
			(at 518.39 146.8 0)
			(layer "B.Fab")
			(hide yes)
			(effects
				(font
					(size 1 1)
					(thickness 0.15)
				)
				(justify mirror)
			)
		)
		(property "Val" "4x10k_0201"
			(at 518.39 146.8 0)
			(layer "B.Fab")
			(hide yes)
			(effects
				(font
					(size 1 1)
					(thickness 0.15)
				)
				(justify mirror)
			)
		)
		(sheetname "User GPIO + LED + button + DIP switch")
		(sheetfile "user-gpio.kicad_sch")
		(attr smd)
		(fp_line
			(start 0.8 0.45)
			(end 0.8 -0.45)
			(stroke
				(width 0.12)
				(type solid)
			)
			(layer "B.SilkS")
		)
		(fp_line
			(start -0.8 0.45)
			(end -0.8 -0.45)
			(stroke
				(width 0.12)
				(type solid)
			)
			(layer "B.SilkS")
		)
		(fp_rect
			(start -0.898 0.66)
			(end 0.898 -0.65)
			(stroke
				(width 0.05)
				(type solid)
			)
			(fill no)
			(layer "B.CrtYd")
		)
		(pad "1" smd roundrect
			(at -0.6 -0.298 180)
			(size 0.2 0.4)
			(layers "B.Cu" "B.Mask" "B.Paste")
			(roundrect_rratio 0.25)
			(net 1318 "/USER_IO.DIP_SW7")
			(pinfunction "R1.1")
			(pintype "passive")
		)
		(pad "2" smd roundrect
			(at -0.202 -0.298 180)
			(size 0.2 0.4)
			(layers "B.Cu" "B.Mask" "B.Paste")
			(roundrect_rratio 0.25)
			(net 1320 "/USER_IO.DIP_SW6")
			(pinfunction "R2.1")
			(pintype "passive")
		)
		(pad "3" smd roundrect
			(at 0.2 -0.298 180)
			(size 0.2 0.4)
			(layers "B.Cu" "B.Mask" "B.Paste")
			(roundrect_rratio 0.25)
			(net 1322 "/USER_IO.DIP_SW5")
			(pinfunction "R3.1")
			(pintype "passive")
		)
		(pad "4" smd roundrect
			(at 0.598 -0.298 180)
			(size 0.2 0.4)
			(layers "B.Cu" "B.Mask" "B.Paste")
			(roundrect_rratio 0.25)
			(net 1324 "/USER_IO.DIP_SW4")
			(pinfunction "R4.1")
			(pintype "passive")
		)
		(pad "5" smd roundrect
			(at 0.598 0.3 180)
			(size 0.2 0.4)
			(layers "B.Cu" "B.Mask" "B.Paste")
			(roundrect_rratio 0.25)
			(net 26 "+1V8")
			(pinfunction "R4.2")
			(pintype "passive")
		)
		(pad "6" smd roundrect
			(at 0.2 0.3 180)
			(size 0.2 0.4)
			(layers "B.Cu" "B.Mask" "B.Paste")
			(roundrect_rratio 0.25)
			(net 26 "+1V8")
			(pinfunction "R3.2")
			(pintype "passive")
		)
		(pad "7" smd roundrect
			(at -0.202 0.3 180)
			(size 0.2 0.4)
			(layers "B.Cu" "B.Mask" "B.Paste")
			(roundrect_rratio 0.25)
			(net 26 "+1V8")
			(pinfunction "R2.2")
			(pintype "passive")
		)
		(pad "8" smd roundrect
			(at -0.6 0.3 180)
			(size 0.2 0.4)
			(layers "B.Cu" "B.Mask" "B.Paste")
			(roundrect_rratio 0.25)
			(net 26 "+1V8")
			(pinfunction "R1.2")
			(pintype "passive")
		)
	)
	(footprint "antmicro-footprints:C_0603_1608Metric"
		(layer "B.Cu")
		(at 200.6 121.25)
		(descr "Capacitor SMD 0603")
		(tags "capacitor 0603")
		(property "Reference" "C105"
			(at 27.175 -29.65 180)
			(layer "B.SilkS")
			(effects
				(font
					(size 0.7 0.7)
					(thickness 0.15)
				)
				(justify left bottom mirror)
			)
		)
		(property "Value" "C_47u_0603"
			(at 0 -1.6 180)
			(layer "B.Fab")
			(effects
				(font
					(size 0.7 0.7)
					(thickness 0.15)
				)
				(justify left bottom mirror)
			)
		)
		(property "Description" "SMD Multilayer Ceramic Capacitor, 47 µF, 6.3 V, 0603 [1608 Metric], ± 20%, X5R, GRM Series"
			(at 0 0 0)
			(layer "F.Fab")
			(hide yes)
			(effects
				(font
					(size 1.27 1.27)
					(thickness 0.15)
				)
			)
		)
		(property "Author" "Antmicro"
			(at 0 0 0)
			(layer "B.Fab")
			(hide yes)
			(effects
				(font
					(size 1 1)
					(thickness 0.15)
				)
				(justify mirror)
			)
		)
		(property "Dielectric" ""
			(at 0 0 0)
			(layer "B.Fab")
			(hide yes)
			(effects
				(font
					(size 1 1)
					(thickness 0.15)
				)
				(justify mirror)
			)
		)
		(property "License" "Apache-2.0"
			(at 0 0 0)
			(layer "B.Fab")
			(hide yes)
			(effects
				(font
					(size 1 1)
					(thickness 0.15)
				)
				(justify mirror)
			)
		)
		(property "MPN" "GRM188R60J476ME15D"
			(at 0 0 0)
			(layer "B.Fab")
			(hide yes)
			(effects
				(font
					(size 1 1)
					(thickness 0.15)
				)
				(justify mirror)
			)
		)
		(property "Manufacturer" "Murata"
			(at 0 0 0)
			(layer "B.Fab")
			(hide yes)
			(effects
				(font
					(size 1 1)
					(thickness 0.15)
				)
				(justify mirror)
			)
		)
		(property "Val" "47u"
			(at 0 0 0)
			(layer "B.Fab")
			(hide yes)
			(effects
				(font
					(size 1 1)
					(thickness 0.15)
				)
				(justify mirror)
			)
		)
		(property "Voltage" ""
			(at 0 0 0)
			(layer "B.Fab")
			(hide yes)
			(effects
				(font
					(size 1 1)
					(thickness 0.15)
				)
				(justify mirror)
			)
		)
		(sheetname "FPGA Bank 16 & 17")
		(sheetfile "fpga-bank-16-17.kicad_sch")
		(attr smd)
		(fp_line
			(start -0.15 -0.4)
			(end 0.15 -0.4)
			(stroke
				(width 0.15)
				(type solid)
			)
			(layer "B.SilkS")
		)
		(fp_line
			(start -0.15 0.4)
			(end 0.15 0.4)
			(stroke
				(width 0.15)
				(type solid)
			)
			(layer "B.SilkS")
		)
		(fp_rect
			(start -1.25 0.65)
			(end 1.25 -0.65)
			(stroke
				(width 0.05)
				(type solid)
			)
			(fill no)
			(layer "B.CrtYd")
		)
		(fp_rect
			(start -0.8 0.4)
			(end 0.8 -0.4)
			(stroke
				(width 0.15)
				(type solid)
			)
			(fill no)
			(layer "B.Fab")
		)
		(pad "1" smd roundrect
			(at -0.7 0)
			(size 0.8 1)
			(layers "B.Cu" "B.Mask" "B.Paste")
			(roundrect_rratio 0.2)
			(net 24 "+3V3")
			(pintype "passive")
		)
		(pad "2" smd roundrect
			(at 0.7 0)
			(size 0.8 1)
			(layers "B.Cu" "B.Mask" "B.Paste")
			(roundrect_rratio 0.2)
			(net 1 "GND")
			(pintype "passive")
		)
	)
	(footprint "antmicro-footprints:R_0402_1005Metric"
		(layer "B.Cu")
		(at 220.6 125.8)
		(descr "Resistor SMD 0402")
		(tags "resistor SMD 0402")
		(property "Reference" "R105"
			(at 1.325 -2.5 180)
			(layer "B.SilkS")
			(effects
				(font
					(size 0.7 0.7)
					(thickness 0.15)
				)
				(justify left bottom mirror)
			)
		)
		(property "Value" "R_0R_0402"
			(at 0 -1.4 180)
			(layer "B.Fab")
			(effects
				(font
					(size 0.7 0.7)
					(thickness 0.15)
				)
				(justify left bottom mirror)
			)
		)
		(property "Description" "SMD Chip Resistor, Jumper, 0 ohm, 100 mW, 0402 [1005 Metric], Thick Film, General Purpose"
			(at 0 0 0)
			(layer "F.Fab")
			(hide yes)
			(effects
				(font
					(size 1.27 1.27)
					(thickness 0.15)
				)
			)
		)
		(property "Author" "Antmicro"
			(at 0 0 0)
			(layer "B.Fab")
			(hide yes)
			(effects
				(font
					(size 1 1)
					(thickness 0.15)
				)
				(justify mirror)
			)
		)
		(property "Current" "1A"
			(at 0 0 0)
			(layer "B.Fab")
			(hide yes)
			(effects
				(font
					(size 1 1)
					(thickness 0.15)
				)
				(justify mirror)
			)
		)
		(property "License" "Apache-2.0"
			(at 0 0 0)
			(layer "B.Fab")
			(hide yes)
			(effects
				(font
					(size 1 1)
					(thickness 0.15)
				)
				(justify mirror)
			)
		)
		(property "MPN" "ERJ2GE0R00X"
			(at 0 0 0)
			(layer "B.Fab")
			(hide yes)
			(effects
				(font
					(size 1 1)
					(thickness 0.15)
				)
				(justify mirror)
			)
		)
		(property "Manufacturer" "Panasonic"
			(at 0 0 0)
			(layer "B.Fab")
			(hide yes)
			(effects
				(font
					(size 1 1)
					(thickness 0.15)
				)
				(justify mirror)
			)
		)
		(property "Tolerance" ""
			(at 0 0 0)
			(layer "B.Fab")
			(hide yes)
			(effects
				(font
					(size 1 1)
					(thickness 0.15)
				)
				(justify mirror)
			)
		)
		(property "Val" "0R"
			(at 0 0 0)
			(layer "B.Fab")
			(hide yes)
			(effects
				(font
					(size 1 1)
					(thickness 0.15)
				)
				(justify mirror)
			)
		)
		(sheetname "User GPIO + LED + button + DIP switch")
		(sheetfile "user-gpio.kicad_sch")
		(attr smd)
		(fp_rect
			(start -0.925 0.47)
			(end 0.925 -0.47)
			(stroke
				(width 0.05)
				(type default)
			)
			(fill no)
			(layer "B.CrtYd")
		)
		(fp_rect
			(start -0.5 0.25)
			(end 0.5 -0.25)
			(stroke
				(width 0.15)
				(type solid)
			)
			(fill no)
			(layer "B.Fab")
		)
		(pad "1" smd roundrect
			(at -0.48 0)
			(size 0.59 0.64)
			(layers "B.Cu" "B.Mask" "B.Paste")
			(roundrect_rratio 0.25)
			(net 432 "/FPGA Bank 12 & 13/FAN_PWM_CTRL")
			(pintype "passive")
		)
		(pad "2" smd roundrect
			(at 0.48 0)
			(size 0.59 0.64)
			(layers "B.Cu" "B.Mask" "B.Paste")
			(roundrect_rratio 0.25)
			(net 876 "/User GPIO + LED + button + DIP switch/FAN_PWM_CTRL_AON")
			(pintype "passive")
		)
	)
	(footprint "antmicro-footprints:C_0201"
		(layer "B.Cu")
		(at 191.2 124.2 -45)
		(descr "Capacitor SMD 0201")
		(tags "capacitor SMD 0201")
		(property "Reference" "C80"
			(at -4.507806 -35.797281 315)
			(unlocked yes)
			(layer "B.SilkS")
			(effects
				(font
					(size 0.7 0.7)
					(thickness 0.15)
				)
				(justify left bottom mirror)
			)
		)
		(property "Value" "C_4u7_0201"
			(at 0 -1.399999 135)
			(layer "B.Fab")
			(effects
				(font
					(size 0.7 0.7)
					(thickness 0.15)
				)
				(justify left bottom mirror)
			)
		)
		(property "Description" "SMD Multilayer Ceramic Capacitor, 4.7 µF, 6.3 V, 0201 [0603 Metric], ± 20%, X5R, GRM Series"
			(at 0 0 315)
			(layer "F.Fab")
			(hide yes)
			(effects
				(font
					(size 1.27 1.27)
					(thickness 0.15)
				)
			)
		)
		(property "Author" "Antmicro"
			(at -31.821479 171.576155 0)
			(layer "B.Fab")
			(hide yes)
			(effects
				(font
					(size 1 1)
					(thickness 0.15)
				)
				(justify mirror)
			)
		)
		(property "Dielectric" ""
			(at -31.821479 171.576155 0)
			(layer "B.Fab")
			(hide yes)
			(effects
				(font
					(size 1 1)
					(thickness 0.15)
				)
				(justify mirror)
			)
		)
		(property "License" "Apache-2.0"
			(at -31.821479 171.576155 0)
			(layer "B.Fab")
			(hide yes)
			(effects
				(font
					(size 1 1)
					(thickness 0.15)
				)
				(justify mirror)
			)
		)
		(property "MPN" "GRM035R60J475ME15D"
			(at -31.821479 171.576155 0)
			(layer "B.Fab")
			(hide yes)
			(effects
				(font
					(size 1 1)
					(thickness 0.15)
				)
				(justify mirror)
			)
		)
		(property "Manufacturer" "Murata"
			(at -31.821479 171.576155 0)
			(layer "B.Fab")
			(hide yes)
			(effects
				(font
					(size 1 1)
					(thickness 0.15)
				)
				(justify mirror)
			)
		)
		(property "Val" "4u7"
			(at -31.821479 171.576155 0)
			(layer "B.Fab")
			(hide yes)
			(effects
				(font
					(size 1 1)
					(thickness 0.15)
				)
				(justify mirror)
			)
		)
		(property "Voltage" ""
			(at -31.821479 171.576155 0)
			(layer "B.Fab")
			(hide yes)
			(effects
				(font
					(size 1 1)
					(thickness 0.15)
				)
				(justify mirror)
			)
		)
		(sheetname "FPGA supply")
		(sheetfile "fpga-supply.kicad_sch")
		(attr smd)
		(fp_poly
			(pts
				(xy -0.7 0.35) (xy 0.7 0.35) (xy 0.7 -0.35) (xy -0.7 -0.35)
			)
			(stroke
				(width 0.05)
				(type default)
			)
			(fill no)
			(layer "B.CrtYd")
		)
		(fp_poly
			(pts
				(xy 0.3 -0.15) (xy -0.301 -0.15) (xy -0.301 0.149) (xy 0.3 0.149)
			)
			(stroke
				(width 0.15)
				(type solid)
			)
			(fill no)
			(layer "B.Fab")
		)
		(pad "" smd roundrect
			(at -0.349 0.002 315)
			(size 0.318 0.36)
			(layers "B.Paste")
			(roundrect_rratio 0.25)
		)
		(pad "" smd roundrect
			(at 0.341 0.002 315)
			(size 0.318 0.36)
			(layers "B.Paste")
			(roundrect_rratio 0.25)
		)
		(pad "1" smd roundrect
			(at -0.321 0.002 315)
			(size 0.46 0.4)
			(layers "B.Cu" "B.Mask")
			(roundrect_rratio 0.25)
			(net 1 "GND")
			(pintype "passive")
		)
		(pad "2" smd roundrect
			(at 0.32 0.002 315)
			(size 0.46 0.4)
			(layers "B.Cu" "B.Mask")
			(roundrect_rratio 0.25)
			(net 6 "+1V0_MGTAVCC")
			(pintype "passive")
		)
	)
	(footprint "antmicro-footprints:R_Array_4x0201_Panasonic_EXB18V"
		(layer "B.Cu")
		(at 167.799999 146.199999 180)
		(property "Reference" "R17"
			(at 6.199999 -6.125001 0)
			(layer "B.SilkS")
			(effects
				(font
					(size 0.7 0.7)
					(thickness 0.15)
				)
				(justify right bottom mirror)
			)
		)
		(property "Value" "4x39R_0201_array"
			(at -1.1 -1.8 0)
			(layer "B.Fab")
			(effects
				(font
					(size 0.7 0.7)
					(thickness 0.15)
				)
				(justify left bottom mirror)
			)
		)
		(property "Description" "Fixed Network Resistor, 39 ohm, Isolated, 4 Resistors, 0502 [1406 Metric], Flat, ± 5%"
			(at 0 0 180)
			(layer "F.Fab")
			(hide yes)
			(effects
				(font
					(size 1.27 1.27)
					(thickness 0.15)
				)
			)
		)
		(property "Author" "Antmicro"
			(at 335.599998 292.399998 0)
			(layer "B.Fab")
			(hide yes)
			(effects
				(font
					(size 1 1)
					(thickness 0.15)
				)
				(justify mirror)
			)
		)
		(property "License" "Apache-2.0"
			(at 335.599998 292.399998 0)
			(layer "B.Fab")
			(hide yes)
			(effects
				(font
					(size 1 1)
					(thickness 0.15)
				)
				(justify mirror)
			)
		)
		(property "MPN" "EXB-18V390JX"
			(at 335.599998 292.399998 0)
			(layer "B.Fab")
			(hide yes)
			(effects
				(font
					(size 1 1)
					(thickness 0.15)
				)
				(justify mirror)
			)
		)
		(property "Manufacturer" "Panasonic"
			(at 335.599998 292.399998 0)
			(layer "B.Fab")
			(hide yes)
			(effects
				(font
					(size 1 1)
					(thickness 0.15)
				)
				(justify mirror)
			)
		)
		(property "Val" "4x39R_0201"
			(at 335.599998 292.399998 0)
			(layer "B.Fab")
			(hide yes)
			(effects
				(font
					(size 1 1)
					(thickness 0.15)
				)
				(justify mirror)
			)
		)
		(sheetname "DRAM + SRAM")
		(sheetfile "ram.kicad_sch")
		(attr smd)
		(fp_line
			(start 0.8 0.45)
			(end 0.8 -0.45)
			(stroke
				(width 0.12)
				(type solid)
			)
			(layer "B.SilkS")
		)
		(fp_line
			(start -0.8 0.45)
			(end -0.8 -0.45)
			(stroke
				(width 0.12)
				(type solid)
			)
			(layer "B.SilkS")
		)
		(fp_rect
			(start -0.898 0.66)
			(end 0.898 -0.65)
			(stroke
				(width 0.05)
				(type solid)
			)
			(fill no)
			(layer "B.CrtYd")
		)
		(pad "1" smd roundrect
			(at -0.6 -0.298 180)
			(size 0.2 0.4)
			(layers "B.Cu" "B.Mask" "B.Paste")
			(roundrect_rratio 0.25)
			(net 559 "/DRAM + SRAM/DDR.~{CAS}")
			(pinfunction "R1.1")
			(pintype "passive")
		)
		(pad "2" smd roundrect
			(at -0.202 -0.298 180)
			(size 0.2 0.4)
			(layers "B.Cu" "B.Mask" "B.Paste")
			(roundrect_rratio 0.25)
			(net 550 "/DRAM + SRAM/DDR.CKE")
			(pinfunction "R2.1")
			(pintype "passive")
		)
		(pad "3" smd roundrect
			(at 0.2 -0.298 180)
			(size 0.2 0.4)
			(layers "B.Cu" "B.Mask" "B.Paste")
			(roundrect_rratio 0.25)
			(net 541 "/DRAM + SRAM/DDR.A10")
			(pinfunction "R3.1")
			(pintype "passive")
		)
		(pad "4" smd roundrect
			(at 0.598 -0.298 180)
			(size 0.2 0.4)
			(layers "B.Cu" "B.Mask" "B.Paste")
			(roundrect_rratio 0.25)
			(net 546 "/DRAM + SRAM/DDR.A15")
			(pinfunction "R4.1")
			(pintype "passive")
		)
		(pad "5" smd roundrect
			(at 0.598 0.3 180)
			(size 0.2 0.4)
			(layers "B.Cu" "B.Mask" "B.Paste")
			(roundrect_rratio 0.25)
			(net 7 "+0V675_VTT")
			(pinfunction "R4.2")
			(pintype "passive")
		)
		(pad "6" smd roundrect
			(at 0.2 0.3 180)
			(size 0.2 0.4)
			(layers "B.Cu" "B.Mask" "B.Paste")
			(roundrect_rratio 0.25)
			(net 7 "+0V675_VTT")
			(pinfunction "R3.2")
			(pintype "passive")
		)
		(pad "7" smd roundrect
			(at -0.202 0.3 180)
			(size 0.2 0.4)
			(layers "B.Cu" "B.Mask" "B.Paste")
			(roundrect_rratio 0.25)
			(net 7 "+0V675_VTT")
			(pinfunction "R2.2")
			(pintype "passive")
		)
		(pad "8" smd roundrect
			(at -0.6 0.3 180)
			(size 0.2 0.4)
			(layers "B.Cu" "B.Mask" "B.Paste")
			(roundrect_rratio 0.25)
			(net 7 "+0V675_VTT")
			(pinfunction "R1.2")
			(pintype "passive")
		)
	)
	(footprint "antmicro-footprints:R_0402_1005Metric"
		(layer "B.Cu")
		(at 219.753 148.216 180)
		(descr "Resistor SMD 0402")
		(tags "resistor SMD 0402")
		(property "Reference" "R219"
			(at 0.753 -0.409 0)
			(layer "B.SilkS")
			(effects
				(font
					(size 0.7 0.7)
					(thickness 0.15)
				)
				(justify left bottom mirror)
			)
		)
		(property "Value" "R_10k_0402"
			(at 0 -1.4 0)
			(layer "B.Fab")
			(effects
				(font
					(size 0.7 0.7)
					(thickness 0.15)
				)
				(justify left bottom mirror)
			)
		)
		(property "Description" "SMD Chip Resistor, 10 kohm, ± 1%, 62.5 mW, 0402 [1005 Metric], Thick Film, General Purpose"
			(at 0 0 180)
			(layer "F.Fab")
			(hide yes)
			(effects
				(font
					(size 1.27 1.27)
					(thickness 0.15)
				)
			)
		)
		(property "Author" "Antmicro"
			(at 439.506 296.432 0)
			(layer "B.Fab")
			(hide yes)
			(effects
				(font
					(size 1 1)
					(thickness 0.15)
				)
				(justify mirror)
			)
		)
		(property "License" "Apache-2.0"
			(at 439.506 296.432 0)
			(layer "B.Fab")
			(hide yes)
			(effects
				(font
					(size 1 1)
					(thickness 0.15)
				)
				(justify mirror)
			)
		)
		(property "MPN" "CR0402-FX-1002GLF"
			(at 439.506 296.432 0)
			(layer "B.Fab")
			(hide yes)
			(effects
				(font
					(size 1 1)
					(thickness 0.15)
				)
				(justify mirror)
			)
		)
		(property "Manufacturer" "Bourns"
			(at 439.506 296.432 0)
			(layer "B.Fab")
			(hide yes)
			(effects
				(font
					(size 1 1)
					(thickness 0.15)
				)
				(justify mirror)
			)
		)
		(property "Tolerance" "1%"
			(at 439.506 296.432 0)
			(layer "B.Fab")
			(hide yes)
			(effects
				(font
					(size 1 1)
					(thickness 0.15)
				)
				(justify mirror)
			)
		)
		(property "Val" "10k"
			(at 439.506 296.432 0)
			(layer "B.Fab")
			(hide yes)
			(effects
				(font
					(size 1 1)
					(thickness 0.15)
				)
				(justify mirror)
			)
		)
		(sheetname "HDMI + Ethernet")
		(sheetfile "hdmi-ethernet.kicad_sch")
		(attr smd)
		(fp_rect
			(start -0.925 0.47)
			(end 0.925 -0.47)
			(stroke
				(width 0.05)
				(type default)
			)
			(fill no)
			(layer "B.CrtYd")
		)
		(fp_rect
			(start -0.5 0.25)
			(end 0.5 -0.25)
			(stroke
				(width 0.15)
				(type solid)
			)
			(fill no)
			(layer "B.Fab")
		)
		(pad "1" smd roundrect
			(at -0.48 0 180)
			(size 0.59 0.64)
			(layers "B.Cu" "B.Mask" "B.Paste")
			(roundrect_rratio 0.25)
			(net 944 "/HDMI + Ethernet/ETH_PHY_RX_DV")
			(pintype "passive")
		)
		(pad "2" smd roundrect
			(at 0.48 0 180)
			(size 0.59 0.64)
			(layers "B.Cu" "B.Mask" "B.Paste")
			(roundrect_rratio 0.25)
			(net 26 "+1V8")
			(pintype "passive")
		)
	)
	(footprint "antmicro-footprints:C_0402_1005Metric"
		(layer "B.Cu")
		(at 208.5 142 90)
		(descr "Capacitor SMD 0402")
		(tags "capacitor SMD 0402")
		(property "Reference" "C23"
			(at 1.125 1.2 270)
			(layer "B.SilkS")
			(effects
				(font
					(size 0.7 0.7)
					(thickness 0.15)
				)
				(justify left bottom mirror)
			)
		)
		(property "Value" "C_100n_0402"
			(at 0 -1.169 270)
			(layer "B.Fab")
			(effects
				(font
					(size 0.7 0.7)
					(thickness 0.15)
				)
				(justify left bottom mirror)
			)
		)
		(property "Description" "SMD Multilayer Ceramic Capacitor, 0.1 µF, 50 V, 0402 [1005 Metric], ± 10%, X5R, GRM Series"
			(at 0 0 90)
			(layer "F.Fab")
			(hide yes)
			(effects
				(font
					(size 1.27 1.27)
					(thickness 0.15)
				)
			)
		)
		(property "Author" "Antmicro"
			(at 350.5 -66.5 0)
			(layer "B.Fab")
			(hide yes)
			(effects
				(font
					(size 1 1)
					(thickness 0.15)
				)
				(justify mirror)
			)
		)
		(property "Dielectric" "X5R"
			(at 350.5 -66.5 0)
			(layer "B.Fab")
			(hide yes)
			(effects
				(font
					(size 1 1)
					(thickness 0.15)
				)
				(justify mirror)
			)
		)
		(property "License" "Apache-2.0"
			(at 350.5 -66.5 0)
			(layer "B.Fab")
			(hide yes)
			(effects
				(font
					(size 1 1)
					(thickness 0.15)
				)
				(justify mirror)
			)
		)
		(property "MPN" "GRM155R61H104KE14D"
			(at 350.5 -66.5 0)
			(layer "B.Fab")
			(hide yes)
			(effects
				(font
					(size 1 1)
					(thickness 0.15)
				)
				(justify mirror)
			)
		)
		(property "Manufacturer" "Murata"
			(at 350.5 -66.5 0)
			(layer "B.Fab")
			(hide yes)
			(effects
				(font
					(size 1 1)
					(thickness 0.15)
				)
				(justify mirror)
			)
		)
		(property "Val" "100n"
			(at 350.5 -66.5 0)
			(layer "B.Fab")
			(hide yes)
			(effects
				(font
					(size 1 1)
					(thickness 0.15)
				)
				(justify mirror)
			)
		)
		(property "Voltage" "50V"
			(at 350.5 -66.5 0)
			(layer "B.Fab")
			(hide yes)
			(effects
				(font
					(size 1 1)
					(thickness 0.15)
				)
				(justify mirror)
			)
		)
		(sheetname "FPGA Bank 12 & 13")
		(sheetfile "fpga-bank-12-13.kicad_sch")
		(attr smd)
		(fp_rect
			(start -0.925 0.47)
			(end 0.925 -0.47)
			(stroke
				(width 0.05)
				(type default)
			)
			(fill no)
			(layer "B.CrtYd")
		)
		(fp_line
			(start 0.504 -0.248)
			(end -0.494 -0.248)
			(stroke
				(width 0.15)
				(type solid)
			)
			(layer "B.Fab")
		)
		(fp_line
			(start -0.494 -0.248)
			(end -0.494 0.25)
			(stroke
				(width 0.15)
				(type solid)
			)
			(layer "B.Fab")
		)
		(fp_line
			(start 0.504 0.25)
			(end 0.504 -0.248)
			(stroke
				(width 0.15)
				(type solid)
			)
			(layer "B.Fab")
		)
		(fp_line
			(start -0.494 0.25)
			(end 0.504 0.25)
			(stroke
				(width 0.15)
				(type solid)
			)
			(layer "B.Fab")
		)
		(pad "1" smd roundrect
			(at -0.48 0 90)
			(size 0.59 0.64)
			(layers "B.Cu" "B.Mask" "B.Paste")
			(roundrect_rratio 0.25)
			(net 1 "GND")
			(pintype "passive")
		)
		(pad "2" smd roundrect
			(at 0.48 0 90)
			(size 0.59 0.64)
			(layers "B.Cu" "B.Mask" "B.Paste")
			(roundrect_rratio 0.25)
			(net 24 "+3V3")
			(pintype "passive")
		)
	)
	(footprint "antmicro-footprints:R_0402_1005Metric"
		(layer "B.Cu")
		(at 216.799999 77.899999 -90)
		(descr "Resistor SMD 0402")
		(tags "resistor SMD 0402")
		(property "Reference" "R121"
			(at -3.599999 -0.400001 90)
			(layer "B.SilkS")
			(effects
				(font
					(size 0.7 0.7)
					(thickness 0.15)
				)
				(justify left bottom mirror)
			)
		)
		(property "Value" "R_100R_0402"
			(at 0 -1.4 90)
			(layer "B.Fab")
			(effects
				(font
					(size 0.7 0.7)
					(thickness 0.15)
				)
				(justify left bottom mirror)
			)
		)
		(property "Description" "SMD Chip Resistor, 100 ohm, ± 1%, 62.5 mW, 0402 [1005 Metric], Thick Film, General Purpose"
			(at 0 0 270)
			(layer "F.Fab")
			(hide yes)
			(effects
				(font
					(size 1.27 1.27)
					(thickness 0.15)
				)
			)
		)
		(property "Author" "Antmicro"
			(at 138.9 294.699998 0)
			(layer "B.Fab")
			(hide yes)
			(effects
				(font
					(size 1 1)
					(thickness 0.15)
				)
				(justify mirror)
			)
		)
		(property "License" "Apache-2.0"
			(at 138.9 294.699998 0)
			(layer "B.Fab")
			(hide yes)
			(effects
				(font
					(size 1 1)
					(thickness 0.15)
				)
				(justify mirror)
			)
		)
		(property "MPN" "CR0402-FX-1000GLF"
			(at 138.9 294.699998 0)
			(layer "B.Fab")
			(hide yes)
			(effects
				(font
					(size 1 1)
					(thickness 0.15)
				)
				(justify mirror)
			)
		)
		(property "Manufacturer" "Bourns"
			(at 138.9 294.699998 0)
			(layer "B.Fab")
			(hide yes)
			(effects
				(font
					(size 1 1)
					(thickness 0.15)
				)
				(justify mirror)
			)
		)
		(property "Tolerance" "1%"
			(at 138.9 294.699998 0)
			(layer "B.Fab")
			(hide yes)
			(effects
				(font
					(size 1 1)
					(thickness 0.15)
				)
				(justify mirror)
			)
		)
		(property "Val" "100R"
			(at 138.9 294.699998 0)
			(layer "B.Fab")
			(hide yes)
			(effects
				(font
					(size 1 1)
					(thickness 0.15)
				)
				(justify mirror)
			)
		)
		(sheetname "User GPIO + LED + button + DIP switch")
		(sheetfile "user-gpio.kicad_sch")
		(attr smd)
		(fp_rect
			(start -0.925 0.47)
			(end 0.925 -0.47)
			(stroke
				(width 0.05)
				(type default)
			)
			(fill no)
			(layer "B.CrtYd")
		)
		(fp_rect
			(start -0.5 0.25)
			(end 0.5 -0.25)
			(stroke
				(width 0.15)
				(type solid)
			)
			(fill no)
			(layer "B.Fab")
		)
		(pad "1" smd roundrect
			(at -0.48 0 270)
			(size 0.59 0.64)
			(layers "B.Cu" "B.Mask" "B.Paste")
			(roundrect_rratio 0.25)
			(net 457 "/FPGA Bank 12 & 13/PMOD_A.IO2")
			(pintype "passive")
		)
		(pad "2" smd roundrect
			(at 0.48 0 270)
			(size 0.59 0.64)
			(layers "B.Cu" "B.Mask" "B.Paste")
			(roundrect_rratio 0.25)
			(net 807 "/User GPIO + LED + button + DIP switch/PMOD_A_2")
			(pintype "passive")
		)
	)
	(footprint "antmicro-footprints:C_0603_1608Metric"
		(layer "B.Cu")
		(at 192.19 136.14 180)
		(descr "Capacitor SMD 0603")
		(tags "capacitor 0603")
		(property "Reference" "C108"
			(at -23.375 28.075 0)
			(layer "B.SilkS")
			(effects
				(font
					(size 0.7 0.7)
					(thickness 0.15)
				)
				(justify left bottom mirror)
			)
		)
		(property "Value" "C_47u_0603"
			(at 0 -1.6 0)
			(layer "B.Fab")
			(effects
				(font
					(size 0.7 0.7)
					(thickness 0.15)
				)
				(justify left bottom mirror)
			)
		)
		(property "Description" "SMD Multilayer Ceramic Capacitor, 47 µF, 6.3 V, 0603 [1608 Metric], ± 20%, X5R, GRM Series"
			(at 0 0 180)
			(layer "F.Fab")
			(hide yes)
			(effects
				(font
					(size 1.27 1.27)
					(thickness 0.15)
				)
			)
		)
		(property "Author" "Antmicro"
			(at 384.38 272.28 0)
			(layer "B.Fab")
			(hide yes)
			(effects
				(font
					(size 1 1)
					(thickness 0.15)
				)
				(justify mirror)
			)
		)
		(property "Dielectric" ""
			(at 384.38 272.28 0)
			(layer "B.Fab")
			(hide yes)
			(effects
				(font
					(size 1 1)
					(thickness 0.15)
				)
				(justify mirror)
			)
		)
		(property "License" "Apache-2.0"
			(at 384.38 272.28 0)
			(layer "B.Fab")
			(hide yes)
			(effects
				(font
					(size 1 1)
					(thickness 0.15)
				)
				(justify mirror)
			)
		)
		(property "MPN" "GRM188R60J476ME15D"
			(at 384.38 272.28 0)
			(layer "B.Fab")
			(hide yes)
			(effects
				(font
					(size 1 1)
					(thickness 0.15)
				)
				(justify mirror)
			)
		)
		(property "Manufacturer" "Murata"
			(at 384.38 272.28 0)
			(layer "B.Fab")
			(hide yes)
			(effects
				(font
					(size 1 1)
					(thickness 0.15)
				)
				(justify mirror)
			)
		)
		(property "Val" "47u"
			(at 384.38 272.28 0)
			(layer "B.Fab")
			(hide yes)
			(effects
				(font
					(size 1 1)
					(thickness 0.15)
				)
				(justify mirror)
			)
		)
		(property "Voltage" ""
			(at 384.38 272.28 0)
			(layer "B.Fab")
			(hide yes)
			(effects
				(font
					(size 1 1)
					(thickness 0.15)
				)
				(justify mirror)
			)
		)
		(sheetname "FPGA Bank 33 & 34")
		(sheetfile "fpga-bank-33-34.kicad_sch")
		(attr smd)
		(fp_line
			(start -0.15 0.4)
			(end 0.15 0.4)
			(stroke
				(width 0.15)
				(type solid)
			)
			(layer "B.SilkS")
		)
		(fp_line
			(start -0.15 -0.4)
			(end 0.15 -0.4)
			(stroke
				(width 0.15)
				(type solid)
			)
			(layer "B.SilkS")
		)
		(fp_rect
			(start -1.25 0.65)
			(end 1.25 -0.65)
			(stroke
				(width 0.05)
				(type solid)
			)
			(fill no)
			(layer "B.CrtYd")
		)
		(fp_rect
			(start -0.8 0.4)
			(end 0.8 -0.4)
			(stroke
				(width 0.15)
				(type solid)
			)
			(fill no)
			(layer "B.Fab")
		)
		(pad "1" smd roundrect
			(at -0.7 0 180)
			(size 0.8 1)
			(layers "B.Cu" "B.Mask" "B.Paste")
			(roundrect_rratio 0.2)
			(net 26 "+1V8")
			(pintype "passive")
		)
		(pad "2" smd roundrect
			(at 0.7 0 180)
			(size 0.8 1)
			(layers "B.Cu" "B.Mask" "B.Paste")
			(roundrect_rratio 0.2)
			(net 1 "GND")
			(pintype "passive")
		)
	)
	(footprint "antmicro-footprints:R_Array_4x0201_Panasonic_EXB18V"
		(layer "B.Cu")
		(at 249.901 127.9)
		(property "Reference" "R21"
			(at 1.049 -0.725 0)
			(layer "B.SilkS")
			(effects
				(font
					(size 0.7 0.7)
					(thickness 0.15)
				)
				(justify left bottom mirror)
			)
		)
		(property "Value" "R_4x33R_0201_array"
			(at -1.1 -1.8 0)
			(layer "B.Fab")
			(effects
				(font
					(size 0.7 0.7)
					(thickness 0.15)
				)
				(justify right bottom mirror)
			)
		)
		(property "Description" "Fixed Network Resistor, 33 ohm, Isolated, 4 Resistors, 0502 [1406 Metric], Flat, ± 5%"
			(at 0 0 0)
			(layer "F.Fab")
			(hide yes)
			(effects
				(font
					(size 1.27 1.27)
					(thickness 0.15)
				)
			)
		)
		(property "Author" "Antmicro"
			(at 0 0 0)
			(layer "B.Fab")
			(hide yes)
			(effects
				(font
					(size 1 1)
					(thickness 0.15)
				)
				(justify mirror)
			)
		)
		(property "License" "Apache-2.0"
			(at 0 0 0)
			(layer "B.Fab")
			(hide yes)
			(effects
				(font
					(size 1 1)
					(thickness 0.15)
				)
				(justify mirror)
			)
		)
		(property "MPN" "EXB-18V330JX"
			(at 0 0 0)
			(layer "B.Fab")
			(hide yes)
			(effects
				(font
					(size 1 1)
					(thickness 0.15)
				)
				(justify mirror)
			)
		)
		(property "Manufacturer" "Panasonic"
			(at 0 0 0)
			(layer "B.Fab")
			(hide yes)
			(effects
				(font
					(size 1 1)
					(thickness 0.15)
				)
				(justify mirror)
			)
		)
		(property "Val" "R_4x33R_0201"
			(at 0 0 0)
			(layer "B.Fab")
			(hide yes)
			(effects
				(font
					(size 1 1)
					(thickness 0.15)
				)
				(justify mirror)
			)
		)
		(sheetname "Supervisior MCU")
		(sheetfile "supervisor-mcu.kicad_sch")
		(attr smd)
		(fp_line
			(start -0.8 0.45)
			(end -0.8 -0.45)
			(stroke
				(width 0.12)
				(type solid)
			)
			(layer "B.SilkS")
		)
		(fp_line
			(start 0.8 0.45)
			(end 0.8 -0.45)
			(stroke
				(width 0.12)
				(type solid)
			)
			(layer "B.SilkS")
		)
		(fp_rect
			(start -0.898 0.66)
			(end 0.898 -0.65)
			(stroke
				(width 0.05)
				(type solid)
			)
			(fill no)
			(layer "B.CrtYd")
		)
		(pad "1" smd roundrect
			(at -0.6 -0.298)
			(size 0.2 0.4)
			(layers "B.Cu" "B.Mask" "B.Paste")
			(roundrect_rratio 0.25)
			(net 1353 "/SUP_MCU.A1")
			(pinfunction "R1.1")
			(pintype "passive")
		)
		(pad "2" smd roundrect
			(at -0.202 -0.298)
			(size 0.2 0.4)
			(layers "B.Cu" "B.Mask" "B.Paste")
			(roundrect_rratio 0.25)
			(net 1354 "/SUP_MCU.A7")
			(pinfunction "R2.1")
			(pintype "passive")
		)
		(pad "3" smd roundrect
			(at 0.2 -0.298)
			(size 0.2 0.4)
			(layers "B.Cu" "B.Mask" "B.Paste")
			(roundrect_rratio 0.25)
			(net 1355 "/SUP_MCU.A16")
			(pinfunction "R3.1")
			(pintype "passive")
		)
		(pad "4" smd roundrect
			(at 0.598 -0.298)
			(size 0.2 0.4)
			(layers "B.Cu" "B.Mask" "B.Paste")
			(roundrect_rratio 0.25)
			(net 1356 "/SUP_MCU.A18")
			(pinfunction "R4.1")
			(pintype "passive")
		)
		(pad "5" smd roundrect
			(at 0.598 0.3)
			(size 0.2 0.4)
			(layers "B.Cu" "B.Mask" "B.Paste")
			(roundrect_rratio 0.25)
			(net 1079 "/Supervisior MCU/USB_A18")
			(pinfunction "R4.2")
			(pintype "passive")
		)
		(pad "6" smd roundrect
			(at 0.2 0.3)
			(size 0.2 0.4)
			(layers "B.Cu" "B.Mask" "B.Paste")
			(roundrect_rratio 0.25)
			(net 1077 "/Supervisior MCU/USB_A16")
			(pinfunction "R3.2")
			(pintype "passive")
		)
		(pad "7" smd roundrect
			(at -0.202 0.3)
			(size 0.2 0.4)
			(layers "B.Cu" "B.Mask" "B.Paste")
			(roundrect_rratio 0.25)
			(net 1068 "/Supervisior MCU/USB_A7")
			(pinfunction "R2.2")
			(pintype "passive")
		)
		(pad "8" smd roundrect
			(at -0.6 0.3)
			(size 0.2 0.4)
			(layers "B.Cu" "B.Mask" "B.Paste")
			(roundrect_rratio 0.25)
			(net 1062 "/Supervisior MCU/USB_A1")
			(pinfunction "R1.2")
			(pintype "passive")
		)
	)
	(footprint "antmicro-footprints:C_0402_1005Metric"
		(layer "B.Cu")
		(at 171.999999 147.999999 90)
		(descr "Capacitor SMD 0402")
		(tags "capacitor SMD 0402")
		(property "Reference" "C182"
			(at -0.725001 0.400001 270)
			(layer "B.SilkS")
			(effects
				(font
					(size 0.7 0.7)
					(thickness 0.15)
				)
				(justify left bottom mirror)
			)
		)
		(property "Value" "C_100n_0402"
			(at 0 -1.169 270)
			(layer "B.Fab")
			(effects
				(font
					(size 0.7 0.7)
					(thickness 0.15)
				)
				(justify left bottom mirror)
			)
		)
		(property "Description" "SMD Multilayer Ceramic Capacitor, 0.1 µF, 50 V, 0402 [1005 Metric], ± 10%, X5R, GRM Series"
			(at 0 0 90)
			(layer "F.Fab")
			(hide yes)
			(effects
				(font
					(size 1.27 1.27)
					(thickness 0.15)
				)
			)
		)
		(property "Author" "Antmicro"
			(at 319.999998 -24 0)
			(layer "B.Fab")
			(hide yes)
			(effects
				(font
					(size 1 1)
					(thickness 0.15)
				)
				(justify mirror)
			)
		)
		(property "Dielectric" "X5R"
			(at 319.999998 -24 0)
			(layer "B.Fab")
			(hide yes)
			(effects
				(font
					(size 1 1)
					(thickness 0.15)
				)
				(justify mirror)
			)
		)
		(property "License" "Apache-2.0"
			(at 319.999998 -24 0)
			(layer "B.Fab")
			(hide yes)
			(effects
				(font
					(size 1 1)
					(thickness 0.15)
				)
				(justify mirror)
			)
		)
		(property "MPN" "GRM155R61H104KE14D"
			(at 319.999998 -24 0)
			(layer "B.Fab")
			(hide yes)
			(effects
				(font
					(size 1 1)
					(thickness 0.15)
				)
				(justify mirror)
			)
		)
		(property "Manufacturer" "Murata"
			(at 319.999998 -24 0)
			(layer "B.Fab")
			(hide yes)
			(effects
				(font
					(size 1 1)
					(thickness 0.15)
				)
				(justify mirror)
			)
		)
		(property "Val" "100n"
			(at 319.999998 -24 0)
			(layer "B.Fab")
			(hide yes)
			(effects
				(font
					(size 1 1)
					(thickness 0.15)
				)
				(justify mirror)
			)
		)
		(property "Voltage" "50V"
			(at 319.999998 -24 0)
			(layer "B.Fab")
			(hide yes)
			(effects
				(font
					(size 1 1)
					(thickness 0.15)
				)
				(justify mirror)
			)
		)
		(sheetname "DRAM + SRAM")
		(sheetfile "ram.kicad_sch")
		(attr smd)
		(fp_rect
			(start -0.925 0.47)
			(end 0.925 -0.47)
			(stroke
				(width 0.05)
				(type default)
			)
			(fill no)
			(layer "B.CrtYd")
		)
		(fp_line
			(start 0.504 -0.248)
			(end -0.494 -0.248)
			(stroke
				(width 0.15)
				(type solid)
			)
			(layer "B.Fab")
		)
		(fp_line
			(start -0.494 -0.248)
			(end -0.494 0.25)
			(stroke
				(width 0.15)
				(type solid)
			)
			(layer "B.Fab")
		)
		(fp_line
			(start 0.504 0.25)
			(end 0.504 -0.248)
			(stroke
				(width 0.15)
				(type solid)
			)
			(layer "B.Fab")
		)
		(fp_line
			(start -0.494 0.25)
			(end 0.504 0.25)
			(stroke
				(width 0.15)
				(type solid)
			)
			(layer "B.Fab")
		)
		(pad "1" smd roundrect
			(at -0.48 0 90)
			(size 0.59 0.64)
			(layers "B.Cu" "B.Mask" "B.Paste")
			(roundrect_rratio 0.25)
			(net 1 "GND")
			(pintype "passive")
		)
		(pad "2" smd roundrect
			(at 0.48 0 90)
			(size 0.59 0.64)
			(layers "B.Cu" "B.Mask" "B.Paste")
			(roundrect_rratio 0.25)
			(net 25 "+1V35")
			(pintype "passive")
		)
	)
	(footprint "antmicro-footprints:R_0402_1005Metric"
		(layer "B.Cu")
		(at 256.901 170.34762)
		(descr "Resistor SMD 0402")
		(tags "resistor SMD 0402")
		(property "Reference" "R38"
			(at 2.549 -1.64762 225)
			(layer "B.SilkS")
			(effects
				(font
					(size 0.7 0.7)
					(thickness 0.15)
				)
				(justify left bottom mirror)
			)
		)
		(property "Value" "R_100k_0402"
			(at 0 -1.4 180)
			(layer "B.Fab")
			(effects
				(font
					(size 0.7 0.7)
					(thickness 0.15)
				)
				(justify left bottom mirror)
			)
		)
		(property "Description" "SMD Chip Resistor, 100 kohm, ± 1%, 62.5 mW, 0402 [1005 Metric], Thick Film, General Purpose"
			(at 0 0 0)
			(layer "F.Fab")
			(hide yes)
			(effects
				(font
					(size 1.27 1.27)
					(thickness 0.15)
				)
			)
		)
		(property "Author" "Antmicro"
			(at 0 0 0)
			(layer "B.Fab")
			(hide yes)
			(effects
				(font
					(size 1 1)
					(thickness 0.15)
				)
				(justify mirror)
			)
		)
		(property "License" "Apache-2.0"
			(at 0 0 0)
			(layer "B.Fab")
			(hide yes)
			(effects
				(font
					(size 1 1)
					(thickness 0.15)
				)
				(justify mirror)
			)
		)
		(property "MPN" "CR0402-FX-1003GLF"
			(at 0 0 0)
			(layer "B.Fab")
			(hide yes)
			(effects
				(font
					(size 1 1)
					(thickness 0.15)
				)
				(justify mirror)
			)
		)
		(property "Manufacturer" "Bourns"
			(at 0 0 0)
			(layer "B.Fab")
			(hide yes)
			(effects
				(font
					(size 1 1)
					(thickness 0.15)
				)
				(justify mirror)
			)
		)
		(property "Tolerance" "1%"
			(at 0 0 0)
			(layer "B.Fab")
			(hide yes)
			(effects
				(font
					(size 1 1)
					(thickness 0.15)
				)
				(justify mirror)
			)
		)
		(property "Val" "100k"
			(at 0 0 0)
			(layer "B.Fab")
			(hide yes)
			(effects
				(font
					(size 1 1)
					(thickness 0.15)
				)
				(justify mirror)
			)
		)
		(sheetname "Power supply")
		(sheetfile "power-supply.kicad_sch")
		(attr smd)
		(fp_rect
			(start -0.925 0.47)
			(end 0.925 -0.47)
			(stroke
				(width 0.05)
				(type default)
			)
			(fill no)
			(layer "B.CrtYd")
		)
		(fp_rect
			(start -0.5 0.25)
			(end 0.5 -0.25)
			(stroke
				(width 0.15)
				(type solid)
			)
			(fill no)
			(layer "B.Fab")
		)
		(pad "1" smd roundrect
			(at -0.48 0)
			(size 0.59 0.64)
			(layers "B.Cu" "B.Mask" "B.Paste")
			(roundrect_rratio 0.25)
			(net 889 "/Power supply/PG")
			(pintype "passive")
		)
		(pad "2" smd roundrect
			(at 0.48 0)
			(size 0.59 0.64)
			(layers "B.Cu" "B.Mask" "B.Paste")
			(roundrect_rratio 0.25)
			(net 698 "/Power supply/VDD")
			(pintype "passive")
		)
	)
	(footprint "antmicro-footprints:C_0402_1005Metric"
		(layer "B.Cu")
		(at 247.6 78.7)
		(descr "Capacitor SMD 0402")
		(tags "capacitor SMD 0402")
		(property "Reference" "C215"
			(at -1.25 -0.55 0)
			(layer "B.SilkS")
			(effects
				(font
					(size 0.7 0.7)
					(thickness 0.15)
				)
				(justify right bottom mirror)
			)
		)
		(property "Value" "C_1u_0402"
			(at 0 -1.4 0)
			(layer "B.Fab")
			(effects
				(font
					(size 0.7 0.7)
					(thickness 0.15)
				)
				(justify right bottom mirror)
			)
		)
		(property "Description" "SMD Multilayer Ceramic Capacitor, 1 µF, 10 V, 0402 [1005 Metric], ± 10%, X6S, C"
			(at 0 0 0)
			(layer "F.Fab")
			(hide yes)
			(effects
				(font
					(size 1.27 1.27)
					(thickness 0.15)
				)
			)
		)
		(property "Author" "Antmicro"
			(at 0 0 0)
			(layer "B.Fab")
			(hide yes)
			(effects
				(font
					(size 1 1)
					(thickness 0.15)
				)
				(justify mirror)
			)
		)
		(property "Dielectric" ""
			(at 0 0 0)
			(layer "B.Fab")
			(hide yes)
			(effects
				(font
					(size 1 1)
					(thickness 0.15)
				)
				(justify mirror)
			)
		)
		(property "License" "Apache-2.0"
			(at 0 0 0)
			(layer "B.Fab")
			(hide yes)
			(effects
				(font
					(size 1 1)
					(thickness 0.15)
				)
				(justify mirror)
			)
		)
		(property "MPN" "C1005X6S1A105K050BC"
			(at 0 0 0)
			(layer "B.Fab")
			(hide yes)
			(effects
				(font
					(size 1 1)
					(thickness 0.15)
				)
				(justify mirror)
			)
		)
		(property "Manufacturer" "TDK"
			(at 0 0 0)
			(layer "B.Fab")
			(hide yes)
			(effects
				(font
					(size 1 1)
					(thickness 0.15)
				)
				(justify mirror)
			)
		)
		(property "Val" "1u"
			(at 0 0 0)
			(layer "B.Fab")
			(hide yes)
			(effects
				(font
					(size 1 1)
					(thickness 0.15)
				)
				(justify mirror)
			)
		)
		(property "Voltage" ""
			(at 0 0 0)
			(layer "B.Fab")
			(hide yes)
			(effects
				(font
					(size 1 1)
					(thickness 0.15)
				)
				(justify mirror)
			)
		)
		(sheetname "User GPIO + LED + button + DIP switch")
		(sheetfile "user-gpio.kicad_sch")
		(attr smd)
		(fp_rect
			(start -0.925 0.47)
			(end 0.925 -0.47)
			(stroke
				(width 0.05)
				(type default)
			)
			(fill no)
			(layer "B.CrtYd")
		)
		(fp_line
			(start -0.494 -0.248)
			(end -0.494 0.25)
			(stroke
				(width 0.15)
				(type solid)
			)
			(layer "B.Fab")
		)
		(fp_line
			(start -0.494 0.25)
			(end 0.504 0.25)
			(stroke
				(width 0.15)
				(type solid)
			)
			(layer "B.Fab")
		)
		(fp_line
			(start 0.504 -0.248)
			(end -0.494 -0.248)
			(stroke
				(width 0.15)
				(type solid)
			)
			(layer "B.Fab")
		)
		(fp_line
			(start 0.504 0.25)
			(end 0.504 -0.248)
			(stroke
				(width 0.15)
				(type solid)
			)
			(layer "B.Fab")
		)
		(pad "1" smd roundrect
			(at -0.48 0)
			(size 0.59 0.64)
			(layers "B.Cu" "B.Mask" "B.Paste")
			(roundrect_rratio 0.25)
			(net 1 "GND")
			(pintype "passive")
		)
		(pad "2" smd roundrect
			(at 0.48 0)
			(size 0.59 0.64)
			(layers "B.Cu" "B.Mask" "B.Paste")
			(roundrect_rratio 0.25)
			(net 24 "+3V3")
			(pintype "passive")
		)
	)
	(footprint "antmicro-footprints:R_0402_1005Metric"
		(layer "B.Cu")
		(at 195.691252 92.85 180)
		(descr "Resistor SMD 0402")
		(tags "resistor SMD 0402")
		(property "Reference" "R200"
			(at 0.716252 -0.425 0)
			(layer "B.SilkS")
			(effects
				(font
					(size 0.7 0.7)
					(thickness 0.15)
				)
				(justify left bottom mirror)
			)
		)
		(property "Value" "R_10k_0402"
			(at 0 -1.4 0)
			(layer "B.Fab")
			(effects
				(font
					(size 0.7 0.7)
					(thickness 0.15)
				)
				(justify left bottom mirror)
			)
		)
		(property "Description" "SMD Chip Resistor, 10 kohm, ± 1%, 62.5 mW, 0402 [1005 Metric], Thick Film, General Purpose"
			(at 0 0 180)
			(layer "F.Fab")
			(hide yes)
			(effects
				(font
					(size 1.27 1.27)
					(thickness 0.15)
				)
			)
		)
		(property "Author" "Antmicro"
			(at 391.382504 185.7 0)
			(layer "B.Fab")
			(hide yes)
			(effects
				(font
					(size 1 1)
					(thickness 0.15)
				)
				(justify mirror)
			)
		)
		(property "License" "Apache-2.0"
			(at 391.382504 185.7 0)
			(layer "B.Fab")
			(hide yes)
			(effects
				(font
					(size 1 1)
					(thickness 0.15)
				)
				(justify mirror)
			)
		)
		(property "MPN" "CR0402-FX-1002GLF"
			(at 391.382504 185.7 0)
			(layer "B.Fab")
			(hide yes)
			(effects
				(font
					(size 1 1)
					(thickness 0.15)
				)
				(justify mirror)
			)
		)
		(property "Manufacturer" "Bourns"
			(at 391.382504 185.7 0)
			(layer "B.Fab")
			(hide yes)
			(effects
				(font
					(size 1 1)
					(thickness 0.15)
				)
				(justify mirror)
			)
		)
		(property "Tolerance" "1%"
			(at 391.382504 185.7 0)
			(layer "B.Fab")
			(hide yes)
			(effects
				(font
					(size 1 1)
					(thickness 0.15)
				)
				(justify mirror)
			)
		)
		(property "Val" "10k"
			(at 391.382504 185.7 0)
			(layer "B.Fab")
			(hide yes)
			(effects
				(font
					(size 1 1)
					(thickness 0.15)
				)
				(justify mirror)
			)
		)
		(sheetname "HDMI + Ethernet")
		(sheetfile "hdmi-ethernet.kicad_sch")
		(attr smd)
		(fp_rect
			(start -0.925 0.47)
			(end 0.925 -0.47)
			(stroke
				(width 0.05)
				(type default)
			)
			(fill no)
			(layer "B.CrtYd")
		)
		(fp_rect
			(start -0.5 0.25)
			(end 0.5 -0.25)
			(stroke
				(width 0.15)
				(type solid)
			)
			(fill no)
			(layer "B.Fab")
		)
		(pad "1" smd roundrect
			(at -0.48 0 180)
			(size 0.59 0.64)
			(layers "B.Cu" "B.Mask" "B.Paste")
			(roundrect_rratio 0.25)
			(net 504 "/FPGA Bank 16 & 17/GBE_RGMII.RXD2")
			(pintype "passive")
		)
		(pad "2" smd roundrect
			(at 0.48 0 180)
			(size 0.59 0.64)
			(layers "B.Cu" "B.Mask" "B.Paste")
			(roundrect_rratio 0.25)
			(net 24 "+3V3")
			(pintype "passive")
		)
	)
	(footprint "antmicro-footprints:NetTie-2_SMD_Pad0.127mm"
		(layer "B.Cu")
		(at 193.59 145.48 180)
		(descr "Net tie, 2 pin, 0.127mm  SMD pads")
		(tags "net tie")
		(property "Reference" "NT35"
			(at -0.128 1.345 0)
			(layer "B.SilkS")
			(hide yes)
			(effects
				(font
					(size 0.7 0.7)
					(thickness 0.15)
				)
				(justify left bottom mirror)
			)
		)
		(property "Value" "Net-Tie_2"
			(at 0 -1.199 0)
			(layer "B.Fab")
			(effects
				(font
					(size 0.7 0.7)
					(thickness 0.15)
				)
				(justify left bottom mirror)
			)
		)
		(property "Description" "Net tie, 2 pins"
			(at 0 0 180)
			(layer "F.Fab")
			(hide yes)
			(effects
				(font
					(size 1.27 1.27)
					(thickness 0.15)
				)
			)
		)
		(property "Author" "Antmicro"
			(at 387.18 290.96 0)
			(layer "B.Fab")
			(hide yes)
			(effects
				(font
					(size 1 1)
					(thickness 0.15)
				)
				(justify mirror)
			)
		)
		(property "License" "Apache-2.0"
			(at 387.18 290.96 0)
			(layer "B.Fab")
			(hide yes)
			(effects
				(font
					(size 1 1)
					(thickness 0.15)
				)
				(justify mirror)
			)
		)
		(property "MPN" ""
			(at 387.18 290.96 0)
			(layer "B.Fab")
			(hide yes)
			(effects
				(font
					(size 1 1)
					(thickness 0.15)
				)
				(justify mirror)
			)
		)
		(property "Manufacturer" ""
			(at 387.18 290.96 0)
			(layer "B.Fab")
			(hide yes)
			(effects
				(font
					(size 1 1)
					(thickness 0.15)
				)
				(justify mirror)
			)
		)
		(sheetname "DC-DC Converters")
		(sheetfile "dc-dc.kicad_sch")
		(attr exclude_from_pos_files)
		(net_tie_pad_groups "1, 2")
		(fp_poly
			(pts
				(xy -0.0635 0.0635) (xy 0.0625 0.0635) (xy 0.0625 -0.0635) (xy -0.0635 -0.0635)
			)
			(stroke
				(width 0)
				(type solid)
			)
			(fill yes)
			(layer "B.Cu")
		)
		(pad "1" smd roundrect
			(at -0.127 0)
			(size 0.127 0.127)
			(layers "B.Cu")
			(roundrect_rratio 0.5)
			(chamfer_ratio 0)
			(chamfer top_left bottom_left)
			(net 1 "GND")
			(pinfunction "1")
			(pintype "passive")
		)
		(pad "2" smd roundrect
			(at 0.126 0 180)
			(size 0.127 0.127)
			(layers "B.Cu")
			(roundrect_rratio 0.5)
			(chamfer_ratio 0)
			(chamfer top_left bottom_left)
			(net 1223 "/DC-DC Converters/SENSE_1V8_N")
			(pinfunction "2")
			(pintype "passive")
		)
	)
	(footprint "antmicro-footprints:QFN-2L_1.6x1x0.55mm"
		(layer "B.Cu")
		(at 261.701 179.7)
		(property "Reference" "D3"
			(at -0.851 -0.7 0)
			(layer "B.SilkS")
			(effects
				(font
					(size 0.7 0.7)
					(thickness 0.15)
				)
				(justify right bottom mirror)
			)
		)
		(property "Value" "ESDA25P35-1U1M"
			(at 0 -1.7 0)
			(layer "B.Fab")
			(effects
				(font
					(size 0.7 0.7)
					(thickness 0.15)
				)
				(justify right bottom mirror)
			)
		)
		(property "Description" "Unidirectional TVS, 30 kV, QFN-2L, 22 V, 195 pF"
			(at 0 0 0)
			(layer "F.Fab")
			(hide yes)
			(effects
				(font
					(size 1.27 1.27)
					(thickness 0.15)
				)
			)
		)
		(property "Author" "Antmicro"
			(at 0 0 0)
			(layer "B.Fab")
			(hide yes)
			(effects
				(font
					(size 1 1)
					(thickness 0.15)
				)
				(justify mirror)
			)
		)
		(property "License" "Apache-2.0"
			(at 0 0 0)
			(layer "B.Fab")
			(hide yes)
			(effects
				(font
					(size 1 1)
					(thickness 0.15)
				)
				(justify mirror)
			)
		)
		(property "MPN" "ESDA25P35-1U1M"
			(at 0 0 0)
			(layer "B.Fab")
			(hide yes)
			(effects
				(font
					(size 1 1)
					(thickness 0.15)
				)
				(justify mirror)
			)
		)
		(property "Manufacturer" "STMicroelectronics"
			(at 0 0 0)
			(layer "B.Fab")
			(hide yes)
			(effects
				(font
					(size 1 1)
					(thickness 0.15)
				)
				(justify mirror)
			)
		)
		(property "Public" "False"
			(at 0 0 0)
			(layer "B.Fab")
			(hide yes)
			(effects
				(font
					(size 1 1)
					(thickness 0.15)
				)
				(justify mirror)
			)
		)
		(sheetname "Power supply")
		(sheetfile "power-supply.kicad_sch")
		(attr smd)
		(fp_line
			(start -1.2 0.4)
			(end -1.2 -0.4)
			(stroke
				(width 0.15)
				(type solid)
			)
			(layer "B.SilkS")
		)
		(fp_line
			(start 0.27 -0.3)
			(end -0.27 -0.3)
			(stroke
				(width 0.15)
				(type solid)
			)
			(layer "B.SilkS")
		)
		(fp_line
			(start 0.27 0.3)
			(end -0.27 0.3)
			(stroke
				(width 0.15)
				(type solid)
			)
			(layer "B.SilkS")
		)
		(fp_rect
			(start 1.25 -0.65)
			(end -1.25 0.65)
			(stroke
				(width 0.05)
				(type solid)
			)
			(fill no)
			(layer "B.CrtYd")
		)
		(fp_line
			(start -0.199 -0.2)
			(end -0.199 -0.1)
			(stroke
				(width 0.15)
				(type solid)
			)
			(layer "B.Fab")
		)
		(fp_line
			(start -0.199 0)
			(end -0.597 0)
			(stroke
				(width 0.15)
				(type solid)
			)
			(layer "B.Fab")
		)
		(fp_line
			(start -0.199 0.202)
			(end -0.199 -0.1)
			(stroke
				(width 0.15)
				(type solid)
			)
			(layer "B.Fab")
		)
		(fp_line
			(start -0.101 0)
			(end 0.201 -0.2)
			(stroke
				(width 0.15)
				(type solid)
			)
			(layer "B.Fab")
		)
		(fp_line
			(start 0.201 -0.2)
			(end 0.201 0)
			(stroke
				(width 0.15)
				(type solid)
			)
			(layer "B.Fab")
		)
		(fp_line
			(start 0.201 0)
			(end 0.201 0.202)
			(stroke
				(width 0.15)
				(type solid)
			)
			(layer "B.Fab")
		)
		(fp_line
			(start 0.201 0.202)
			(end -0.101 0)
			(stroke
				(width 0.15)
				(type solid)
			)
			(layer "B.Fab")
		)
		(fp_line
			(start 0.599 0)
			(end 0.201 0)
			(stroke
				(width 0.15)
				(type solid)
			)
			(layer "B.Fab")
		)
		(fp_rect
			(start 0.848 -0.4)
			(end -0.85 0.402)
			(stroke
				(width 0.15)
				(type solid)
			)
			(fill no)
			(layer "B.Fab")
		)
		(pad "1" smd roundrect
			(at -0.7 0 180)
			(size 0.8 1)
			(layers "B.Cu" "B.Mask" "B.Paste")
			(roundrect_rratio 0.2)
			(net 4 "/Power supply/DC_IN")
			(pinfunction "C")
			(pintype "passive")
		)
		(pad "2" smd roundrect
			(at 0.7 0 180)
			(size 0.8 1)
			(layers "B.Cu" "B.Mask" "B.Paste")
			(roundrect_rratio 0.2)
			(net 1 "GND")
			(pinfunction "A")
			(pintype "passive")
		)
	)
	(footprint "antmicro-footprints:C_0402_1005Metric"
		(layer "B.Cu")
		(at 191.5 144 90)
		(descr "Capacitor SMD 0402")
		(tags "capacitor SMD 0402")
		(property "Reference" "C91"
			(at 1.025 1.275 270)
			(layer "B.SilkS")
			(effects
				(font
					(size 0.7 0.7)
					(thickness 0.15)
				)
				(justify left bottom mirror)
			)
		)
		(property "Value" "C_100n_0402"
			(at 0 -1.169 270)
			(layer "B.Fab")
			(effects
				(font
					(size 0.7 0.7)
					(thickness 0.15)
				)
				(justify left bottom mirror)
			)
		)
		(property "Description" "SMD Multilayer Ceramic Capacitor, 0.1 µF, 50 V, 0402 [1005 Metric], ± 10%, X5R, GRM Series"
			(at 0 0 90)
			(layer "F.Fab")
			(hide yes)
			(effects
				(font
					(size 1.27 1.27)
					(thickness 0.15)
				)
			)
		)
		(property "Author" "Antmicro"
			(at 335.5 -47.5 0)
			(layer "B.Fab")
			(hide yes)
			(effects
				(font
					(size 1 1)
					(thickness 0.15)
				)
				(justify mirror)
			)
		)
		(property "Dielectric" "X5R"
			(at 335.5 -47.5 0)
			(layer "B.Fab")
			(hide yes)
			(effects
				(font
					(size 1 1)
					(thickness 0.15)
				)
				(justify mirror)
			)
		)
		(property "License" "Apache-2.0"
			(at 335.5 -47.5 0)
			(layer "B.Fab")
			(hide yes)
			(effects
				(font
					(size 1 1)
					(thickness 0.15)
				)
				(justify mirror)
			)
		)
		(property "MPN" "GRM155R61H104KE14D"
			(at 335.5 -47.5 0)
			(layer "B.Fab")
			(hide yes)
			(effects
				(font
					(size 1 1)
					(thickness 0.15)
				)
				(justify mirror)
			)
		)
		(property "Manufacturer" "Murata"
			(at 335.5 -47.5 0)
			(layer "B.Fab")
			(hide yes)
			(effects
				(font
					(size 1 1)
					(thickness 0.15)
				)
				(justify mirror)
			)
		)
		(property "Val" "100n"
			(at 335.5 -47.5 0)
			(layer "B.Fab")
			(hide yes)
			(effects
				(font
					(size 1 1)
					(thickness 0.15)
				)
				(justify mirror)
			)
		)
		(property "Voltage" "50V"
			(at 335.5 -47.5 0)
			(layer "B.Fab")
			(hide yes)
			(effects
				(font
					(size 1 1)
					(thickness 0.15)
				)
				(justify mirror)
			)
		)
		(sheetname "FPGA Bank 33 & 34")
		(sheetfile "fpga-bank-33-34.kicad_sch")
		(attr smd)
		(fp_rect
			(start -0.925 0.47)
			(end 0.925 -0.47)
			(stroke
				(width 0.05)
				(type default)
			)
			(fill no)
			(layer "B.CrtYd")
		)
		(fp_line
			(start 0.504 -0.248)
			(end -0.494 -0.248)
			(stroke
				(width 0.15)
				(type solid)
			)
			(layer "B.Fab")
		)
		(fp_line
			(start -0.494 -0.248)
			(end -0.494 0.25)
			(stroke
				(width 0.15)
				(type solid)
			)
			(layer "B.Fab")
		)
		(fp_line
			(start 0.504 0.25)
			(end 0.504 -0.248)
			(stroke
				(width 0.15)
				(type solid)
			)
			(layer "B.Fab")
		)
		(fp_line
			(start -0.494 0.25)
			(end 0.504 0.25)
			(stroke
				(width 0.15)
				(type solid)
			)
			(layer "B.Fab")
		)
		(pad "1" smd roundrect
			(at -0.48 0 90)
			(size 0.59 0.64)
			(layers "B.Cu" "B.Mask" "B.Paste")
			(roundrect_rratio 0.25)
			(net 1 "GND")
			(pintype "passive")
		)
		(pad "2" smd roundrect
			(at 0.48 0 90)
			(size 0.59 0.64)
			(layers "B.Cu" "B.Mask" "B.Paste")
			(roundrect_rratio 0.25)
			(net 25 "+1V35")
			(pintype "passive")
		)
	)
	(footprint "antmicro-footprints:C_0402_1005Metric"
		(layer "B.Cu")
		(at 201.75 119.05)
		(descr "Capacitor SMD 0402")
		(tags "capacitor SMD 0402")
		(property "Reference" "C87"
			(at 1.025 -0.475 180)
			(layer "B.SilkS")
			(effects
				(font
					(size 0.7 0.7)
					(thickness 0.15)
				)
				(justify left bottom mirror)
			)
		)
		(property "Value" "C_100n_0402"
			(at 0 -1.169 180)
			(layer "B.Fab")
			(effects
				(font
					(size 0.7 0.7)
					(thickness 0.15)
				)
				(justify left bottom mirror)
			)
		)
		(property "Description" "SMD Multilayer Ceramic Capacitor, 0.1 µF, 50 V, 0402 [1005 Metric], ± 10%, X5R, GRM Series"
			(at 0 0 0)
			(layer "F.Fab")
			(hide yes)
			(effects
				(font
					(size 1.27 1.27)
					(thickness 0.15)
				)
			)
		)
		(property "Author" "Antmicro"
			(at 0 0 0)
			(layer "B.Fab")
			(hide yes)
			(effects
				(font
					(size 1 1)
					(thickness 0.15)
				)
				(justify mirror)
			)
		)
		(property "Dielectric" "X5R"
			(at 0 0 0)
			(layer "B.Fab")
			(hide yes)
			(effects
				(font
					(size 1 1)
					(thickness 0.15)
				)
				(justify mirror)
			)
		)
		(property "License" "Apache-2.0"
			(at 0 0 0)
			(layer "B.Fab")
			(hide yes)
			(effects
				(font
					(size 1 1)
					(thickness 0.15)
				)
				(justify mirror)
			)
		)
		(property "MPN" "GRM155R61H104KE14D"
			(at 0 0 0)
			(layer "B.Fab")
			(hide yes)
			(effects
				(font
					(size 1 1)
					(thickness 0.15)
				)
				(justify mirror)
			)
		)
		(property "Manufacturer" "Murata"
			(at 0 0 0)
			(layer "B.Fab")
			(hide yes)
			(effects
				(font
					(size 1 1)
					(thickness 0.15)
				)
				(justify mirror)
			)
		)
		(property "Val" "100n"
			(at 0 0 0)
			(layer "B.Fab")
			(hide yes)
			(effects
				(font
					(size 1 1)
					(thickness 0.15)
				)
				(justify mirror)
			)
		)
		(property "Voltage" "50V"
			(at 0 0 0)
			(layer "B.Fab")
			(hide yes)
			(effects
				(font
					(size 1 1)
					(thickness 0.15)
				)
				(justify mirror)
			)
		)
		(sheetname "FPGA Bank 16 & 17")
		(sheetfile "fpga-bank-16-17.kicad_sch")
		(attr smd)
		(fp_rect
			(start -0.925 0.47)
			(end 0.925 -0.47)
			(stroke
				(width 0.05)
				(type default)
			)
			(fill no)
			(layer "B.CrtYd")
		)
		(fp_line
			(start -0.494 -0.248)
			(end -0.494 0.25)
			(stroke
				(width 0.15)
				(type solid)
			)
			(layer "B.Fab")
		)
		(fp_line
			(start -0.494 0.25)
			(end 0.504 0.25)
			(stroke
				(width 0.15)
				(type solid)
			)
			(layer "B.Fab")
		)
		(fp_line
			(start 0.504 -0.248)
			(end -0.494 -0.248)
			(stroke
				(width 0.15)
				(type solid)
			)
			(layer "B.Fab")
		)
		(fp_line
			(start 0.504 0.25)
			(end 0.504 -0.248)
			(stroke
				(width 0.15)
				(type solid)
			)
			(layer "B.Fab")
		)
		(pad "1" smd roundrect
			(at -0.48 0)
			(size 0.59 0.64)
			(layers "B.Cu" "B.Mask" "B.Paste")
			(roundrect_rratio 0.25)
			(net 1 "GND")
			(pintype "passive")
		)
		(pad "2" smd roundrect
			(at 0.48 0)
			(size 0.59 0.64)
			(layers "B.Cu" "B.Mask" "B.Paste")
			(roundrect_rratio 0.25)
			(net 24 "+3V3")
			(pintype "passive")
		)
	)
	(footprint "antmicro-footprints:R_0402_1005Metric"
		(layer "B.Cu")
		(at 266.001 124.7 180)
		(descr "Resistor SMD 0402")
		(tags "resistor SMD 0402")
		(property "Reference" "R169"
			(at 0.901 -0.7 0)
			(layer "B.SilkS")
			(effects
				(font
					(size 0.7 0.7)
					(thickness 0.15)
				)
				(justify left bottom mirror)
			)
		)
		(property "Value" "R_15k_0402"
			(at 0 -1.4 0)
			(layer "B.Fab")
			(effects
				(font
					(size 0.7 0.7)
					(thickness 0.15)
				)
				(justify left bottom mirror)
			)
		)
		(property "Description" "SMD Chip Resistor, 15 kohm, ± 1%, 62.5 mW, 0402 [1005 Metric], Thick Film, General Purpose"
			(at 0 0 180)
			(layer "F.Fab")
			(hide yes)
			(effects
				(font
					(size 1.27 1.27)
					(thickness 0.15)
				)
			)
		)
		(property "Author" "Antmicro"
			(at 532.002 249.4 0)
			(layer "B.Fab")
			(hide yes)
			(effects
				(font
					(size 1 1)
					(thickness 0.15)
				)
				(justify mirror)
			)
		)
		(property "DNP" "DNP"
			(at 532.002 249.4 0)
			(layer "B.Fab")
			(hide yes)
			(effects
				(font
					(size 1 1)
					(thickness 0.15)
				)
				(justify mirror)
			)
		)
		(property "License" "Apache-2.0"
			(at 532.002 249.4 0)
			(layer "B.Fab")
			(hide yes)
			(effects
				(font
					(size 1 1)
					(thickness 0.15)
				)
				(justify mirror)
			)
		)
		(property "MPN" "CR0402-FX-1502GLF"
			(at 532.002 249.4 0)
			(layer "B.Fab")
			(hide yes)
			(effects
				(font
					(size 1 1)
					(thickness 0.15)
				)
				(justify mirror)
			)
		)
		(property "Manufacturer" "Bourns"
			(at 532.002 249.4 0)
			(layer "B.Fab")
			(hide yes)
			(effects
				(font
					(size 1 1)
					(thickness 0.15)
				)
				(justify mirror)
			)
		)
		(property "Tolerance" "1%"
			(at 532.002 249.4 0)
			(layer "B.Fab")
			(hide yes)
			(effects
				(font
					(size 1 1)
					(thickness 0.15)
				)
				(justify mirror)
			)
		)
		(property "Val" "15k"
			(at 532.002 249.4 0)
			(layer "B.Fab")
			(hide yes)
			(effects
				(font
					(size 1 1)
					(thickness 0.15)
				)
				(justify mirror)
			)
		)
		(property "dnp" ""
			(at 532.002 249.4 0)
			(layer "B.Fab")
			(hide yes)
			(effects
				(font
					(size 1 1)
					(thickness 0.15)
				)
				(justify mirror)
			)
		)
		(property "exclude_from_bom" ""
			(at 532.002 249.4 0)
			(layer "B.Fab")
			(hide yes)
			(effects
				(font
					(size 1 1)
					(thickness 0.15)
				)
				(justify mirror)
			)
		)
		(sheetname "USB PHY")
		(sheetfile "usb-phy.kicad_sch")
		(attr smd exclude_from_bom)
		(fp_rect
			(start -0.925 0.47)
			(end 0.925 -0.47)
			(stroke
				(width 0.05)
				(type default)
			)
			(fill no)
			(layer "B.CrtYd")
		)
		(fp_rect
			(start -0.5 0.25)
			(end 0.5 -0.25)
			(stroke
				(width 0.15)
				(type solid)
			)
			(fill no)
			(layer "B.Fab")
		)
		(pad "1" smd roundrect
			(at -0.48 0 180)
			(size 0.59 0.64)
			(layers "B.Cu" "B.Mask" "B.Paste")
			(roundrect_rratio 0.25)
			(net 1 "GND")
			(pintype "passive")
		)
		(pad "2" smd roundrect
			(at 0.48 0 180)
			(size 0.59 0.64)
			(layers "B.Cu" "B.Mask" "B.Paste")
			(roundrect_rratio 0.25)
			(net 842 "/USB PHY/USB_USR_CONN_D+")
			(pintype "passive")
		)
	)
	(footprint "antmicro-footprints:C_0402_1005Metric"
		(layer "B.Cu")
		(at 192 122.275)
		(descr "Capacitor SMD 0402")
		(tags "capacitor SMD 0402")
		(property "Reference" "C111"
			(at 23.025 -29.55 180)
			(layer "B.SilkS")
			(effects
				(font
					(size 0.7 0.7)
					(thickness 0.15)
				)
				(justify left bottom mirror)
			)
		)
		(property "Value" "C_100n_0402"
			(at 0 -1.169 180)
			(layer "B.Fab")
			(effects
				(font
					(size 0.7 0.7)
					(thickness 0.15)
				)
				(justify left bottom mirror)
			)
		)
		(property "Description" "SMD Multilayer Ceramic Capacitor, 0.1 µF, 50 V, 0402 [1005 Metric], ± 10%, X5R, GRM Series"
			(at 0 0 0)
			(layer "F.Fab")
			(hide yes)
			(effects
				(font
					(size 1.27 1.27)
					(thickness 0.15)
				)
			)
		)
		(property "Author" "Antmicro"
			(at 0 0 0)
			(layer "B.Fab")
			(hide yes)
			(effects
				(font
					(size 1 1)
					(thickness 0.15)
				)
				(justify mirror)
			)
		)
		(property "Dielectric" "X5R"
			(at 0 0 0)
			(layer "B.Fab")
			(hide yes)
			(effects
				(font
					(size 1 1)
					(thickness 0.15)
				)
				(justify mirror)
			)
		)
		(property "License" "Apache-2.0"
			(at 0 0 0)
			(layer "B.Fab")
			(hide yes)
			(effects
				(font
					(size 1 1)
					(thickness 0.15)
				)
				(justify mirror)
			)
		)
		(property "MPN" "GRM155R61H104KE14D"
			(at 0 0 0)
			(layer "B.Fab")
			(hide yes)
			(effects
				(font
					(size 1 1)
					(thickness 0.15)
				)
				(justify mirror)
			)
		)
		(property "Manufacturer" "Murata"
			(at 0 0 0)
			(layer "B.Fab")
			(hide yes)
			(effects
				(font
					(size 1 1)
					(thickness 0.15)
				)
				(justify mirror)
			)
		)
		(property "Val" "100n"
			(at 0 0 0)
			(layer "B.Fab")
			(hide yes)
			(effects
				(font
					(size 1 1)
					(thickness 0.15)
				)
				(justify mirror)
			)
		)
		(property "Voltage" "50V"
			(at 0 0 0)
			(layer "B.Fab")
			(hide yes)
			(effects
				(font
					(size 1 1)
					(thickness 0.15)
				)
				(justify mirror)
			)
		)
		(sheetname "FPGA supply")
		(sheetfile "fpga-supply.kicad_sch")
		(attr smd)
		(fp_rect
			(start -0.925 0.47)
			(end 0.925 -0.47)
			(stroke
				(width 0.05)
				(type default)
			)
			(fill no)
			(layer "B.CrtYd")
		)
		(fp_line
			(start -0.494 -0.248)
			(end -0.494 0.25)
			(stroke
				(width 0.15)
				(type solid)
			)
			(layer "B.Fab")
		)
		(fp_line
			(start -0.494 0.25)
			(end 0.504 0.25)
			(stroke
				(width 0.15)
				(type solid)
			)
			(layer "B.Fab")
		)
		(fp_line
			(start 0.504 -0.248)
			(end -0.494 -0.248)
			(stroke
				(width 0.15)
				(type solid)
			)
			(layer "B.Fab")
		)
		(fp_line
			(start 0.504 0.25)
			(end 0.504 -0.248)
			(stroke
				(width 0.15)
				(type solid)
			)
			(layer "B.Fab")
		)
		(pad "1" smd roundrect
			(at -0.48 0)
			(size 0.59 0.64)
			(layers "B.Cu" "B.Mask" "B.Paste")
			(roundrect_rratio 0.25)
			(net 6 "+1V0_MGTAVCC")
			(pintype "passive")
		)
		(pad "2" smd roundrect
			(at 0.48 0)
			(size 0.59 0.64)
			(layers "B.Cu" "B.Mask" "B.Paste")
			(roundrect_rratio 0.25)
			(net 1 "GND")
			(pintype "passive")
		)
	)
	(footprint "antmicro-footprints:C_0201"
		(layer "B.Cu")
		(at 202.65 126.5 -90)
		(descr "Capacitor SMD 0201")
		(tags "capacitor SMD 0201")
		(property "Reference" "C129"
			(at -31.25 -27 90)
			(layer "B.SilkS")
			(effects
				(font
					(size 0.7 0.7)
					(thickness 0.15)
				)
				(justify left bottom mirror)
			)
		)
		(property "Value" "C_100n_0201"
			(at 0 -1.4 90)
			(layer "B.Fab")
			(effects
				(font
					(size 0.7 0.7)
					(thickness 0.15)
				)
				(justify left bottom mirror)
			)
		)
		(property "Description" "SMD Multilayer Ceramic Capacitor, 0.1 µF, 6.3 V, 0201 [0603 Metric], ± 10%, X6S, CC Series"
			(at 0 0 270)
			(layer "F.Fab")
			(hide yes)
			(effects
				(font
					(size 1.27 1.27)
					(thickness 0.15)
				)
			)
		)
		(property "Author" "Antmicro"
			(at 76.15 329.15 0)
			(layer "B.Fab")
			(hide yes)
			(effects
				(font
					(size 1 1)
					(thickness 0.15)
				)
				(justify mirror)
			)
		)
		(property "Dielectric" ""
			(at 76.15 329.15 0)
			(layer "B.Fab")
			(hide yes)
			(effects
				(font
					(size 1 1)
					(thickness 0.15)
				)
				(justify mirror)
			)
		)
		(property "License" "Apache-2.0"
			(at 76.15 329.15 0)
			(layer "B.Fab")
			(hide yes)
			(effects
				(font
					(size 1 1)
					(thickness 0.15)
				)
				(justify mirror)
			)
		)
		(property "MPN" "CC0201KRX6S5BB104"
			(at 76.15 329.15 0)
			(layer "B.Fab")
			(hide yes)
			(effects
				(font
					(size 1 1)
					(thickness 0.15)
				)
				(justify mirror)
			)
		)
		(property "Manufacturer" "YAGEO"
			(at 76.15 329.15 0)
			(layer "B.Fab")
			(hide yes)
			(effects
				(font
					(size 1 1)
					(thickness 0.15)
				)
				(justify mirror)
			)
		)
		(property "Val" "100n"
			(at 76.15 329.15 0)
			(layer "B.Fab")
			(hide yes)
			(effects
				(font
					(size 1 1)
					(thickness 0.15)
				)
				(justify mirror)
			)
		)
		(property "Voltage" ""
			(at 76.15 329.15 0)
			(layer "B.Fab")
			(hide yes)
			(effects
				(font
					(size 1 1)
					(thickness 0.15)
				)
				(justify mirror)
			)
		)
		(sheetname "FPGA supply")
		(sheetfile "fpga-supply.kicad_sch")
		(attr smd)
		(fp_rect
			(start -0.7 0.35)
			(end 0.7 -0.35)
			(stroke
				(width 0.05)
				(type default)
			)
			(fill no)
			(layer "B.CrtYd")
		)
		(fp_rect
			(start 0.3 -0.15)
			(end -0.301 0.149)
			(stroke
				(width 0.15)
				(type solid)
			)
			(fill no)
			(layer "B.Fab")
		)
		(pad "" smd roundrect
			(at -0.349 0.002 270)
			(size 0.318 0.36)
			(layers "B.Paste")
			(roundrect_rratio 0.25)
		)
		(pad "" smd roundrect
			(at 0.341 0.002 270)
			(size 0.318 0.36)
			(layers "B.Paste")
			(roundrect_rratio 0.25)
		)
		(pad "1" smd roundrect
			(at -0.321 0.002 270)
			(size 0.46 0.4)
			(layers "B.Cu" "B.Mask")
			(roundrect_rratio 0.25)
			(net 1 "GND")
			(pintype "passive")
		)
		(pad "2" smd roundrect
			(at 0.32 0.002 270)
			(size 0.46 0.4)
			(layers "B.Cu" "B.Mask")
			(roundrect_rratio 0.25)
			(net 650 "+1V0")
			(pintype "passive")
		)
	)
	(footprint "antmicro-footprints:C_0402_1005Metric"
		(layer "B.Cu")
		(at 206 144.5)
		(descr "Capacitor SMD 0402")
		(tags "capacitor SMD 0402")
		(property "Reference" "C11"
			(at 1.125 -0.45 180)
			(layer "B.SilkS")
			(effects
				(font
					(size 0.7 0.7)
					(thickness 0.15)
				)
				(justify left bottom mirror)
			)
		)
		(property "Value" "C_100n_0402"
			(at 0 -1.169 180)
			(layer "B.Fab")
			(effects
				(font
					(size 0.7 0.7)
					(thickness 0.15)
				)
				(justify left bottom mirror)
			)
		)
		(property "Description" "SMD Multilayer Ceramic Capacitor, 0.1 µF, 50 V, 0402 [1005 Metric], ± 10%, X5R, GRM Series"
			(at 0 0 0)
			(layer "F.Fab")
			(hide yes)
			(effects
				(font
					(size 1.27 1.27)
					(thickness 0.15)
				)
			)
		)
		(property "Author" "Antmicro"
			(at 0 0 0)
			(layer "B.Fab")
			(hide yes)
			(effects
				(font
					(size 1 1)
					(thickness 0.15)
				)
				(justify mirror)
			)
		)
		(property "Dielectric" "X5R"
			(at 0 0 0)
			(layer "B.Fab")
			(hide yes)
			(effects
				(font
					(size 1 1)
					(thickness 0.15)
				)
				(justify mirror)
			)
		)
		(property "License" "Apache-2.0"
			(at 0 0 0)
			(layer "B.Fab")
			(hide yes)
			(effects
				(font
					(size 1 1)
					(thickness 0.15)
				)
				(justify mirror)
			)
		)
		(property "MPN" "GRM155R61H104KE14D"
			(at 0 0 0)
			(layer "B.Fab")
			(hide yes)
			(effects
				(font
					(size 1 1)
					(thickness 0.15)
				)
				(justify mirror)
			)
		)
		(property "Manufacturer" "Murata"
			(at 0 0 0)
			(layer "B.Fab")
			(hide yes)
			(effects
				(font
					(size 1 1)
					(thickness 0.15)
				)
				(justify mirror)
			)
		)
		(property "Val" "100n"
			(at 0 0 0)
			(layer "B.Fab")
			(hide yes)
			(effects
				(font
					(size 1 1)
					(thickness 0.15)
				)
				(justify mirror)
			)
		)
		(property "Voltage" "50V"
			(at 0 0 0)
			(layer "B.Fab")
			(hide yes)
			(effects
				(font
					(size 1 1)
					(thickness 0.15)
				)
				(justify mirror)
			)
		)
		(sheetname "FPGA Bank 12 & 13")
		(sheetfile "fpga-bank-12-13.kicad_sch")
		(attr smd)
		(fp_rect
			(start -0.925 0.47)
			(end 0.925 -0.47)
			(stroke
				(width 0.05)
				(type default)
			)
			(fill no)
			(layer "B.CrtYd")
		)
		(fp_line
			(start -0.494 -0.248)
			(end -0.494 0.25)
			(stroke
				(width 0.15)
				(type solid)
			)
			(layer "B.Fab")
		)
		(fp_line
			(start -0.494 0.25)
			(end 0.504 0.25)
			(stroke
				(width 0.15)
				(type solid)
			)
			(layer "B.Fab")
		)
		(fp_line
			(start 0.504 -0.248)
			(end -0.494 -0.248)
			(stroke
				(width 0.15)
				(type solid)
			)
			(layer "B.Fab")
		)
		(fp_line
			(start 0.504 0.25)
			(end 0.504 -0.248)
			(stroke
				(width 0.15)
				(type solid)
			)
			(layer "B.Fab")
		)
		(pad "1" smd roundrect
			(at -0.48 0)
			(size 0.59 0.64)
			(layers "B.Cu" "B.Mask" "B.Paste")
			(roundrect_rratio 0.25)
			(net 1 "GND")
			(pintype "passive")
		)
		(pad "2" smd roundrect
			(at 0.48 0)
			(size 0.59 0.64)
			(layers "B.Cu" "B.Mask" "B.Paste")
			(roundrect_rratio 0.25)
			(net 24 "+3V3")
			(pintype "passive")
		)
	)
	(footprint "antmicro-footprints:NetTie-2_SMD_Pad0.127mm"
		(layer "B.Cu")
		(at 251.701 127.2 90)
		(descr "Net tie, 2 pin, 0.127mm  SMD pads")
		(tags "net tie")
		(property "Reference" "NT19"
			(at -0.128 1.345 270)
			(layer "B.SilkS")
			(hide yes)
			(effects
				(font
					(size 0.7 0.7)
					(thickness 0.15)
				)
				(justify left bottom mirror)
			)
		)
		(property "Value" "Net-Tie_2"
			(at 0 -1.199 270)
			(layer "B.Fab")
			(effects
				(font
					(size 0.7 0.7)
					(thickness 0.15)
				)
				(justify left bottom mirror)
			)
		)
		(property "Description" "Net tie, 2 pins"
			(at 0 0 90)
			(layer "F.Fab")
			(hide yes)
			(effects
				(font
					(size 1.27 1.27)
					(thickness 0.15)
				)
			)
		)
		(property "Author" "Antmicro"
			(at 378.901 -124.501 0)
			(layer "B.Fab")
			(hide yes)
			(effects
				(font
					(size 1 1)
					(thickness 0.15)
				)
				(justify mirror)
			)
		)
		(property "License" "Apache-2.0"
			(at 378.901 -124.501 0)
			(layer "B.Fab")
			(hide yes)
			(effects
				(font
					(size 1 1)
					(thickness 0.15)
				)
				(justify mirror)
			)
		)
		(property "MPN" ""
			(at 378.901 -124.501 0)
			(layer "B.Fab")
			(hide yes)
			(effects
				(font
					(size 1 1)
					(thickness 0.15)
				)
				(justify mirror)
			)
		)
		(property "Manufacturer" ""
			(at 378.901 -124.501 0)
			(layer "B.Fab")
			(hide yes)
			(effects
				(font
					(size 1 1)
					(thickness 0.15)
				)
				(justify mirror)
			)
		)
		(sheetname "FPGA Config")
		(sheetfile "fpga-config.kicad_sch")
		(attr exclude_from_pos_files)
		(net_tie_pad_groups "1, 2")
		(fp_poly
			(pts
				(xy -0.0635 0.0635) (xy 0.0625 0.0635) (xy 0.0625 -0.0635) (xy -0.0635 -0.0635)
			)
			(stroke
				(width 0)
				(type solid)
			)
			(fill yes)
			(layer "B.Cu")
		)
		(pad "1" smd roundrect
			(at -0.127 0 270)
			(size 0.127 0.127)
			(layers "B.Cu")
			(roundrect_rratio 0.5)
			(chamfer_ratio 0)
			(chamfer top_left bottom_left)
			(net 1332 "/SUP_MCU.CCLK")
			(pinfunction "1")
			(pintype "passive")
		)
		(pad "2" smd roundrect
			(at 0.126 0 90)
			(size 0.127 0.127)
			(layers "B.Cu")
			(roundrect_rratio 0.5)
			(chamfer_ratio 0)
			(chamfer top_left bottom_left)
			(net 56 "/FPGA Bank 14 & 15/SYSTEM_FLASH.CLK")
			(pinfunction "2")
			(pintype "passive")
		)
	)
	(footprint "antmicro-footprints:C_0402_1005Metric"
		(layer "B.Cu")
		(at 213 140.5 180)
		(descr "Capacitor SMD 0402")
		(tags "capacitor SMD 0402")
		(property "Reference" "C24"
			(at -1.1 0.475 0)
			(layer "B.SilkS")
			(effects
				(font
					(size 0.7 0.7)
					(thickness 0.15)
				)
				(justify left bottom mirror)
			)
		)
		(property "Value" "C_100n_0402"
			(at 0 -1.169 0)
			(layer "B.Fab")
			(effects
				(font
					(size 0.7 0.7)
					(thickness 0.15)
				)
				(justify left bottom mirror)
			)
		)
		(property "Description" "SMD Multilayer Ceramic Capacitor, 0.1 µF, 50 V, 0402 [1005 Metric], ± 10%, X5R, GRM Series"
			(at 0 0 180)
			(layer "F.Fab")
			(hide yes)
			(effects
				(font
					(size 1.27 1.27)
					(thickness 0.15)
				)
			)
		)
		(property "Author" "Antmicro"
			(at 426 281 0)
			(layer "B.Fab")
			(hide yes)
			(effects
				(font
					(size 1 1)
					(thickness 0.15)
				)
				(justify mirror)
			)
		)
		(property "Dielectric" "X5R"
			(at 426 281 0)
			(layer "B.Fab")
			(hide yes)
			(effects
				(font
					(size 1 1)
					(thickness 0.15)
				)
				(justify mirror)
			)
		)
		(property "License" "Apache-2.0"
			(at 426 281 0)
			(layer "B.Fab")
			(hide yes)
			(effects
				(font
					(size 1 1)
					(thickness 0.15)
				)
				(justify mirror)
			)
		)
		(property "MPN" "GRM155R61H104KE14D"
			(at 426 281 0)
			(layer "B.Fab")
			(hide yes)
			(effects
				(font
					(size 1 1)
					(thickness 0.15)
				)
				(justify mirror)
			)
		)
		(property "Manufacturer" "Murata"
			(at 426 281 0)
			(layer "B.Fab")
			(hide yes)
			(effects
				(font
					(size 1 1)
					(thickness 0.15)
				)
				(justify mirror)
			)
		)
		(property "Val" "100n"
			(at 426 281 0)
			(layer "B.Fab")
			(hide yes)
			(effects
				(font
					(size 1 1)
					(thickness 0.15)
				)
				(justify mirror)
			)
		)
		(property "Voltage" "50V"
			(at 426 281 0)
			(layer "B.Fab")
			(hide yes)
			(effects
				(font
					(size 1 1)
					(thickness 0.15)
				)
				(justify mirror)
			)
		)
		(sheetname "FPGA Bank 12 & 13")
		(sheetfile "fpga-bank-12-13.kicad_sch")
		(attr smd)
		(fp_rect
			(start -0.925 0.47)
			(end 0.925 -0.47)
			(stroke
				(width 0.05)
				(type default)
			)
			(fill no)
			(layer "B.CrtYd")
		)
		(fp_line
			(start 0.504 0.25)
			(end 0.504 -0.248)
			(stroke
				(width 0.15)
				(type solid)
			)
			(layer "B.Fab")
		)
		(fp_line
			(start 0.504 -0.248)
			(end -0.494 -0.248)
			(stroke
				(width 0.15)
				(type solid)
			)
			(layer "B.Fab")
		)
		(fp_line
			(start -0.494 0.25)
			(end 0.504 0.25)
			(stroke
				(width 0.15)
				(type solid)
			)
			(layer "B.Fab")
		)
		(fp_line
			(start -0.494 -0.248)
			(end -0.494 0.25)
			(stroke
				(width 0.15)
				(type solid)
			)
			(layer "B.Fab")
		)
		(pad "1" smd roundrect
			(at -0.48 0 180)
			(size 0.59 0.64)
			(layers "B.Cu" "B.Mask" "B.Paste")
			(roundrect_rratio 0.25)
			(net 1 "GND")
			(pintype "passive")
		)
		(pad "2" smd roundrect
			(at 0.48 0 180)
			(size 0.59 0.64)
			(layers "B.Cu" "B.Mask" "B.Paste")
			(roundrect_rratio 0.25)
			(net 24 "+3V3")
			(pintype "passive")
		)
	)
	(footprint "antmicro-footprints:NetTie-2_SMD_Pad0.127mm"
		(layer "B.Cu")
		(at 190.09 112.64)
		(descr "Net tie, 2 pin, 0.127mm  SMD pads")
		(tags "net tie")
		(property "Reference" "NT33"
			(at -0.128 1.345 180)
			(layer "B.SilkS")
			(hide yes)
			(effects
				(font
					(size 0.7 0.7)
					(thickness 0.15)
				)
				(justify left bottom mirror)
			)
		)
		(property "Value" "Net-Tie_2"
			(at 0 -1.199 180)
			(layer "B.Fab")
			(effects
				(font
					(size 0.7 0.7)
					(thickness 0.15)
				)
				(justify left bottom mirror)
			)
		)
		(property "Description" "Net tie, 2 pins"
			(at 0 0 0)
			(layer "F.Fab")
			(hide yes)
			(effects
				(font
					(size 1.27 1.27)
					(thickness 0.15)
				)
			)
		)
		(property "Author" "Antmicro"
			(at 0 0 0)
			(layer "B.Fab")
			(hide yes)
			(effects
				(font
					(size 1 1)
					(thickness 0.15)
				)
				(justify mirror)
			)
		)
		(property "License" "Apache-2.0"
			(at 0 0 0)
			(layer "B.Fab")
			(hide yes)
			(effects
				(font
					(size 1 1)
					(thickness 0.15)
				)
				(justify mirror)
			)
		)
		(property "MPN" ""
			(at 0 0 0)
			(layer "B.Fab")
			(hide yes)
			(effects
				(font
					(size 1 1)
					(thickness 0.15)
				)
				(justify mirror)
			)
		)
		(property "Manufacturer" ""
			(at 0 0 0)
			(layer "B.Fab")
			(hide yes)
			(effects
				(font
					(size 1 1)
					(thickness 0.15)
				)
				(justify mirror)
			)
		)
		(sheetname "DC-DC Converters")
		(sheetfile "dc-dc.kicad_sch")
		(attr exclude_from_pos_files)
		(net_tie_pad_groups "1, 2")
		(fp_poly
			(pts
				(xy -0.0635 0.0635) (xy 0.0625 0.0635) (xy 0.0625 -0.0635) (xy -0.0635 -0.0635)
			)
			(stroke
				(width 0)
				(type solid)
			)
			(fill yes)
			(layer "B.Cu")
		)
		(pad "1" smd roundrect
			(at -0.127 0 180)
			(size 0.127 0.127)
			(layers "B.Cu")
			(roundrect_rratio 0.5)
			(chamfer_ratio 0)
			(chamfer top_left bottom_left)
			(net 1221 "/DC-DC Converters/SENSE_1V0_P")
			(pinfunction "1")
			(pintype "passive")
		)
		(pad "2" smd roundrect
			(at 0.126 0)
			(size 0.127 0.127)
			(layers "B.Cu")
			(roundrect_rratio 0.5)
			(chamfer_ratio 0)
			(chamfer top_left bottom_left)
			(net 6 "+1V0_MGTAVCC")
			(pinfunction "2")
			(pintype "passive")
		)
	)
	(footprint "antmicro-footprints:C_0402_1005Metric"
		(layer "B.Cu")
		(at 244.701 158)
		(descr "Capacitor SMD 0402")
		(tags "capacitor SMD 0402")
		(property "Reference" "C291"
			(at 1.374 -0.5 180)
			(layer "B.SilkS")
			(effects
				(font
					(size 0.7 0.7)
					(thickness 0.15)
				)
				(justify left bottom mirror)
			)
		)
		(property "Value" "C_100n_0402"
			(at 0 -1.169 180)
			(layer "B.Fab")
			(effects
				(font
					(size 0.7 0.7)
					(thickness 0.15)
				)
				(justify left bottom mirror)
			)
		)
		(property "Description" "SMD Multilayer Ceramic Capacitor, 0.1 µF, 50 V, 0402 [1005 Metric], ± 10%, X5R, GRM Series"
			(at 0 0 0)
			(layer "F.Fab")
			(hide yes)
			(effects
				(font
					(size 1.27 1.27)
					(thickness 0.15)
				)
			)
		)
		(property "Author" "Antmicro"
			(at 0 0 0)
			(layer "B.Fab")
			(hide yes)
			(effects
				(font
					(size 1 1)
					(thickness 0.15)
				)
				(justify mirror)
			)
		)
		(property "Dielectric" "X5R"
			(at 0 0 0)
			(layer "B.Fab")
			(hide yes)
			(effects
				(font
					(size 1 1)
					(thickness 0.15)
				)
				(justify mirror)
			)
		)
		(property "License" "Apache-2.0"
			(at 0 0 0)
			(layer "B.Fab")
			(hide yes)
			(effects
				(font
					(size 1 1)
					(thickness 0.15)
				)
				(justify mirror)
			)
		)
		(property "MPN" "GRM155R61H104KE14D"
			(at 0 0 0)
			(layer "B.Fab")
			(hide yes)
			(effects
				(font
					(size 1 1)
					(thickness 0.15)
				)
				(justify mirror)
			)
		)
		(property "Manufacturer" "Murata"
			(at 0 0 0)
			(layer "B.Fab")
			(hide yes)
			(effects
				(font
					(size 1 1)
					(thickness 0.15)
				)
				(justify mirror)
			)
		)
		(property "Val" "100n"
			(at 0 0 0)
			(layer "B.Fab")
			(hide yes)
			(effects
				(font
					(size 1 1)
					(thickness 0.15)
				)
				(justify mirror)
			)
		)
		(property "Voltage" "50V"
			(at 0 0 0)
			(layer "B.Fab")
			(hide yes)
			(effects
				(font
					(size 1 1)
					(thickness 0.15)
				)
				(justify mirror)
			)
		)
		(sheetname "HDMI + Ethernet")
		(sheetfile "hdmi-ethernet.kicad_sch")
		(attr smd)
		(fp_rect
			(start -0.925 0.47)
			(end 0.925 -0.47)
			(stroke
				(width 0.05)
				(type default)
			)
			(fill no)
			(layer "B.CrtYd")
		)
		(fp_line
			(start -0.494 -0.248)
			(end -0.494 0.25)
			(stroke
				(width 0.15)
				(type solid)
			)
			(layer "B.Fab")
		)
		(fp_line
			(start -0.494 0.25)
			(end 0.504 0.25)
			(stroke
				(width 0.15)
				(type solid)
			)
			(layer "B.Fab")
		)
		(fp_line
			(start 0.504 -0.248)
			(end -0.494 -0.248)
			(stroke
				(width 0.15)
				(type solid)
			)
			(layer "B.Fab")
		)
		(fp_line
			(start 0.504 0.25)
			(end 0.504 -0.248)
			(stroke
				(width 0.15)
				(type solid)
			)
			(layer "B.Fab")
		)
		(pad "1" smd roundrect
			(at -0.48 0)
			(size 0.59 0.64)
			(layers "B.Cu" "B.Mask" "B.Paste")
			(roundrect_rratio 0.25)
			(net 1 "GND")
			(pintype "passive")
		)
		(pad "2" smd roundrect
			(at 0.48 0)
			(size 0.59 0.64)
			(layers "B.Cu" "B.Mask" "B.Paste")
			(roundrect_rratio 0.25)
			(net 730 "/HDMI + Ethernet/GBE_CONN_COMM")
			(pintype "passive")
		)
	)
	(footprint "antmicro-footprints:C_0402_1005Metric"
		(layer "B.Cu")
		(at 198.325 125.825)
		(descr "Capacitor SMD 0402")
		(tags "capacitor SMD 0402")
		(property "Reference" "C121"
			(at 26.275 -29.375 180)
			(layer "B.SilkS")
			(effects
				(font
					(size 0.7 0.7)
					(thickness 0.15)
				)
				(justify left bottom mirror)
			)
		)
		(property "Value" "C_100n_0402"
			(at 0 -1.169 180)
			(layer "B.Fab")
			(effects
				(font
					(size 0.7 0.7)
					(thickness 0.15)
				)
				(justify left bottom mirror)
			)
		)
		(property "Description" "SMD Multilayer Ceramic Capacitor, 0.1 µF, 50 V, 0402 [1005 Metric], ± 10%, X5R, GRM Series"
			(at 0 0 0)
			(layer "F.Fab")
			(hide yes)
			(effects
				(font
					(size 1.27 1.27)
					(thickness 0.15)
				)
			)
		)
		(property "Author" "Antmicro"
			(at 0 0 0)
			(layer "B.Fab")
			(hide yes)
			(effects
				(font
					(size 1 1)
					(thickness 0.15)
				)
				(justify mirror)
			)
		)
		(property "Dielectric" "X5R"
			(at 0 0 0)
			(layer "B.Fab")
			(hide yes)
			(effects
				(font
					(size 1 1)
					(thickness 0.15)
				)
				(justify mirror)
			)
		)
		(property "License" "Apache-2.0"
			(at 0 0 0)
			(layer "B.Fab")
			(hide yes)
			(effects
				(font
					(size 1 1)
					(thickness 0.15)
				)
				(justify mirror)
			)
		)
		(property "MPN" "GRM155R61H104KE14D"
			(at 0 0 0)
			(layer "B.Fab")
			(hide yes)
			(effects
				(font
					(size 1 1)
					(thickness 0.15)
				)
				(justify mirror)
			)
		)
		(property "Manufacturer" "Murata"
			(at 0 0 0)
			(layer "B.Fab")
			(hide yes)
			(effects
				(font
					(size 1 1)
					(thickness 0.15)
				)
				(justify mirror)
			)
		)
		(property "Val" "100n"
			(at 0 0 0)
			(layer "B.Fab")
			(hide yes)
			(effects
				(font
					(size 1 1)
					(thickness 0.15)
				)
				(justify mirror)
			)
		)
		(property "Voltage" "50V"
			(at 0 0 0)
			(layer "B.Fab")
			(hide yes)
			(effects
				(font
					(size 1 1)
					(thickness 0.15)
				)
				(justify mirror)
			)
		)
		(sheetname "FPGA supply")
		(sheetfile "fpga-supply.kicad_sch")
		(attr smd)
		(fp_rect
			(start -0.925 0.47)
			(end 0.925 -0.47)
			(stroke
				(width 0.05)
				(type default)
			)
			(fill no)
			(layer "B.CrtYd")
		)
		(fp_line
			(start -0.494 -0.248)
			(end -0.494 0.25)
			(stroke
				(width 0.15)
				(type solid)
			)
			(layer "B.Fab")
		)
		(fp_line
			(start -0.494 0.25)
			(end 0.504 0.25)
			(stroke
				(width 0.15)
				(type solid)
			)
			(layer "B.Fab")
		)
		(fp_line
			(start 0.504 -0.248)
			(end -0.494 -0.248)
			(stroke
				(width 0.15)
				(type solid)
			)
			(layer "B.Fab")
		)
		(fp_line
			(start 0.504 0.25)
			(end 0.504 -0.248)
			(stroke
				(width 0.15)
				(type solid)
			)
			(layer "B.Fab")
		)
		(pad "1" smd roundrect
			(at -0.48 0)
			(size 0.59 0.64)
			(layers "B.Cu" "B.Mask" "B.Paste")
			(roundrect_rratio 0.25)
			(net 1 "GND")
			(pintype "passive")
		)
		(pad "2" smd roundrect
			(at 0.48 0)
			(size 0.59 0.64)
			(layers "B.Cu" "B.Mask" "B.Paste")
			(roundrect_rratio 0.25)
			(net 650 "+1V0")
			(pintype "passive")
		)
	)
	(footprint "antmicro-footprints:C_0603_1608Metric"
		(layer "B.Cu")
		(at 216.1 126.2 -90)
		(descr "Capacitor SMD 0603")
		(tags "capacitor 0603")
		(property "Reference" "C3"
			(at -0.8 -1.375 90)
			(layer "B.SilkS")
			(effects
				(font
					(size 0.7 0.7)
					(thickness 0.15)
				)
				(justify left bottom mirror)
			)
		)
		(property "Value" "C_47u_0603"
			(at 0 -1.6 90)
			(layer "B.Fab")
			(effects
				(font
					(size 0.7 0.7)
					(thickness 0.15)
				)
				(justify left bottom mirror)
			)
		)
		(property "Description" "SMD Multilayer Ceramic Capacitor, 47 µF, 6.3 V, 0603 [1608 Metric], ± 20%, X5R, GRM Series"
			(at 0 0 270)
			(layer "F.Fab")
			(hide yes)
			(effects
				(font
					(size 1.27 1.27)
					(thickness 0.15)
				)
			)
		)
		(property "Author" "Antmicro"
			(at 89.9 342.3 0)
			(layer "B.Fab")
			(hide yes)
			(effects
				(font
					(size 1 1)
					(thickness 0.15)
				)
				(justify mirror)
			)
		)
		(property "Dielectric" ""
			(at 89.9 342.3 0)
			(layer "B.Fab")
			(hide yes)
			(effects
				(font
					(size 1 1)
					(thickness 0.15)
				)
				(justify mirror)
			)
		)
		(property "License" "Apache-2.0"
			(at 89.9 342.3 0)
			(layer "B.Fab")
			(hide yes)
			(effects
				(font
					(size 1 1)
					(thickness 0.15)
				)
				(justify mirror)
			)
		)
		(property "MPN" "GRM188R60J476ME15D"
			(at 89.9 342.3 0)
			(layer "B.Fab")
			(hide yes)
			(effects
				(font
					(size 1 1)
					(thickness 0.15)
				)
				(justify mirror)
			)
		)
		(property "Manufacturer" "Murata"
			(at 89.9 342.3 0)
			(layer "B.Fab")
			(hide yes)
			(effects
				(font
					(size 1 1)
					(thickness 0.15)
				)
				(justify mirror)
			)
		)
		(property "Val" "47u"
			(at 89.9 342.3 0)
			(layer "B.Fab")
			(hide yes)
			(effects
				(font
					(size 1 1)
					(thickness 0.15)
				)
				(justify mirror)
			)
		)
		(property "Voltage" ""
			(at 89.9 342.3 0)
			(layer "B.Fab")
			(hide yes)
			(effects
				(font
					(size 1 1)
					(thickness 0.15)
				)
				(justify mirror)
			)
		)
		(sheetname "FPGA Bank 12 & 13")
		(sheetfile "fpga-bank-12-13.kicad_sch")
		(attr smd)
		(fp_line
			(start -0.15 0.4)
			(end 0.15 0.4)
			(stroke
				(width 0.15)
				(type solid)
			)
			(layer "B.SilkS")
		)
		(fp_line
			(start -0.15 -0.4)
			(end 0.15 -0.4)
			(stroke
				(width 0.15)
				(type solid)
			)
			(layer "B.SilkS")
		)
		(fp_rect
			(start -1.25 0.65)
			(end 1.25 -0.65)
			(stroke
				(width 0.05)
				(type solid)
			)
			(fill no)
			(layer "B.CrtYd")
		)
		(fp_rect
			(start -0.8 0.4)
			(end 0.8 -0.4)
			(stroke
				(width 0.15)
				(type solid)
			)
			(fill no)
			(layer "B.Fab")
		)
		(pad "1" smd roundrect
			(at -0.7 0 270)
			(size 0.8 1)
			(layers "B.Cu" "B.Mask" "B.Paste")
			(roundrect_rratio 0.2)
			(net 1 "GND")
			(pintype "passive")
		)
		(pad "2" smd roundrect
			(at 0.7 0 270)
			(size 0.8 1)
			(layers "B.Cu" "B.Mask" "B.Paste")
			(roundrect_rratio 0.2)
			(net 24 "+3V3")
			(pintype "passive")
		)
	)
	(footprint "antmicro-footprints:R_0402_1005Metric"
		(layer "B.Cu")
		(at 223.2 146.2 -90)
		(descr "Resistor SMD 0402")
		(tags "resistor SMD 0402")
		(property "Reference" "R236"
			(at -3.625 -0.375 90)
			(layer "B.SilkS")
			(effects
				(font
					(size 0.7 0.7)
					(thickness 0.15)
				)
				(justify left bottom mirror)
			)
		)
		(property "Value" "R_10R_0402"
			(at 0 -1.4 90)
			(layer "B.Fab")
			(effects
				(font
					(size 0.7 0.7)
					(thickness 0.15)
				)
				(justify left bottom mirror)
			)
		)
		(property "Description" "SMD Chip Resistor, 10 ohm, ± 1%, 62.5 mW, 0402 [1005 Metric], Thick Film, General Purpose"
			(at 0 0 270)
			(layer "F.Fab")
			(hide yes)
			(effects
				(font
					(size 1.27 1.27)
					(thickness 0.15)
				)
			)
		)
		(property "Author" "Antmicro"
			(at 77 369.4 0)
			(layer "B.Fab")
			(hide yes)
			(effects
				(font
					(size 1 1)
					(thickness 0.15)
				)
				(justify mirror)
			)
		)
		(property "License" "Apache-2.0"
			(at 77 369.4 0)
			(layer "B.Fab")
			(hide yes)
			(effects
				(font
					(size 1 1)
					(thickness 0.15)
				)
				(justify mirror)
			)
		)
		(property "MPN" "CR0402-FX-10R0GLF"
			(at 77 369.4 0)
			(layer "B.Fab")
			(hide yes)
			(effects
				(font
					(size 1 1)
					(thickness 0.15)
				)
				(justify mirror)
			)
		)
		(property "Manufacturer" "Bourns"
			(at 77 369.4 0)
			(layer "B.Fab")
			(hide yes)
			(effects
				(font
					(size 1 1)
					(thickness 0.15)
				)
				(justify mirror)
			)
		)
		(property "Tolerance" "1%"
			(at 77 369.4 0)
			(layer "B.Fab")
			(hide yes)
			(effects
				(font
					(size 1 1)
					(thickness 0.15)
				)
				(justify mirror)
			)
		)
		(property "Val" "10R"
			(at 77 369.4 0)
			(layer "B.Fab")
			(hide yes)
			(effects
				(font
					(size 1 1)
					(thickness 0.15)
				)
				(justify mirror)
			)
		)
		(sheetname "HDMI + Ethernet")
		(sheetfile "hdmi-ethernet.kicad_sch")
		(attr smd)
		(fp_rect
			(start -0.925 0.47)
			(end 0.925 -0.47)
			(stroke
				(width 0.05)
				(type default)
			)
			(fill no)
			(layer "B.CrtYd")
		)
		(fp_rect
			(start -0.5 0.25)
			(end 0.5 -0.25)
			(stroke
				(width 0.15)
				(type solid)
			)
			(fill no)
			(layer "B.Fab")
		)
		(pad "1" smd roundrect
			(at -0.48 0 270)
			(size 0.59 0.64)
			(layers "B.Cu" "B.Mask" "B.Paste")
			(roundrect_rratio 0.25)
			(net 519 "/FPGA Bank 18 & 32/ETH_RMII.RXD0")
			(pintype "passive")
		)
		(pad "2" smd roundrect
			(at 0.48 0 270)
			(size 0.59 0.64)
			(layers "B.Cu" "B.Mask" "B.Paste")
			(roundrect_rratio 0.25)
			(net 946 "/HDMI + Ethernet/ETH_PHY_RXDO")
			(pintype "passive")
		)
	)
	(footprint "antmicro-footprints:R_0402_1005Metric"
		(layer "B.Cu")
		(at 241.499999 84.699999 90)
		(descr "Resistor SMD 0402")
		(tags "resistor SMD 0402")
		(property "Reference" "R126"
			(at -0.725001 0.400001 270)
			(layer "B.SilkS")
			(effects
				(font
					(size 0.7 0.7)
					(thickness 0.15)
				)
				(justify left bottom mirror)
			)
		)
		(property "Value" "R_100R_0402"
			(at 0 -1.4 270)
			(layer "B.Fab")
			(effects
				(font
					(size 0.7 0.7)
					(thickness 0.15)
				)
				(justify left bottom mirror)
			)
		)
		(property "Description" "SMD Chip Resistor, 100 ohm, ± 1%, 62.5 mW, 0402 [1005 Metric], Thick Film, General Purpose"
			(at 0 0 90)
			(layer "F.Fab")
			(hide yes)
			(effects
				(font
					(size 1.27 1.27)
					(thickness 0.15)
				)
			)
		)
		(property "Author" "Antmicro"
			(at 326.199998 -156.8 0)
			(layer "B.Fab")
			(hide yes)
			(effects
				(font
					(size 1 1)
					(thickness 0.15)
				)
				(justify mirror)
			)
		)
		(property "License" "Apache-2.0"
			(at 326.199998 -156.8 0)
			(layer "B.Fab")
			(hide yes)
			(effects
				(font
					(size 1 1)
					(thickness 0.15)
				)
				(justify mirror)
			)
		)
		(property "MPN" "CR0402-FX-1000GLF"
			(at 326.199998 -156.8 0)
			(layer "B.Fab")
			(hide yes)
			(effects
				(font
					(size 1 1)
					(thickness 0.15)
				)
				(justify mirror)
			)
		)
		(property "Manufacturer" "Bourns"
			(at 326.199998 -156.8 0)
			(layer "B.Fab")
			(hide yes)
			(effects
				(font
					(size 1 1)
					(thickness 0.15)
				)
				(justify mirror)
			)
		)
		(property "Tolerance" "1%"
			(at 326.199998 -156.8 0)
			(layer "B.Fab")
			(hide yes)
			(effects
				(font
					(size 1 1)
					(thickness 0.15)
				)
				(justify mirror)
			)
		)
		(property "Val" "100R"
			(at 326.199998 -156.8 0)
			(layer "B.Fab")
			(hide yes)
			(effects
				(font
					(size 1 1)
					(thickness 0.15)
				)
				(justify mirror)
			)
		)
		(sheetname "User GPIO + LED + button + DIP switch")
		(sheetfile "user-gpio.kicad_sch")
		(attr smd)
		(fp_rect
			(start -0.925 0.47)
			(end 0.925 -0.47)
			(stroke
				(width 0.05)
				(type default)
			)
			(fill no)
			(layer "B.CrtYd")
		)
		(fp_rect
			(start -0.5 0.25)
			(end 0.5 -0.25)
			(stroke
				(width 0.15)
				(type solid)
			)
			(fill no)
			(layer "B.Fab")
		)
		(pad "1" smd roundrect
			(at -0.48 0 90)
			(size 0.59 0.64)
			(layers "B.Cu" "B.Mask" "B.Paste")
			(roundrect_rratio 0.25)
			(net 471 "/FPGA Bank 12 & 13/PMOD_B.IO3")
			(pintype "passive")
		)
		(pad "2" smd roundrect
			(at 0.48 0 90)
			(size 0.59 0.64)
			(layers "B.Cu" "B.Mask" "B.Paste")
			(roundrect_rratio 0.25)
			(net 813 "/User GPIO + LED + button + DIP switch/PMOD_B_3")
			(pintype "passive")
		)
	)
	(footprint "antmicro-footprints:R_0402_1005Metric"
		(layer "B.Cu")
		(at 190.6 84.8 90)
		(descr "Resistor SMD 0402")
		(tags "resistor SMD 0402")
		(property "Reference" "R137"
			(at -0.725 0.4 270)
			(layer "B.SilkS")
			(effects
				(font
					(size 0.7 0.7)
					(thickness 0.15)
				)
				(justify left bottom mirror)
			)
		)
		(property "Value" "R_100R_0402"
			(at 0 -1.4 270)
			(layer "B.Fab")
			(effects
				(font
					(size 0.7 0.7)
					(thickness 0.15)
				)
				(justify left bottom mirror)
			)
		)
		(property "Description" "SMD Chip Resistor, 100 ohm, ± 1%, 62.5 mW, 0402 [1005 Metric], Thick Film, General Purpose"
			(at 0 0 90)
			(layer "F.Fab")
			(hide yes)
			(effects
				(font
					(size 1.27 1.27)
					(thickness 0.15)
				)
			)
		)
		(property "Author" "Antmicro"
			(at 275.4 -105.8 0)
			(layer "B.Fab")
			(hide yes)
			(effects
				(font
					(size 1 1)
					(thickness 0.15)
				)
				(justify mirror)
			)
		)
		(property "License" "Apache-2.0"
			(at 275.4 -105.8 0)
			(layer "B.Fab")
			(hide yes)
			(effects
				(font
					(size 1 1)
					(thickness 0.15)
				)
				(justify mirror)
			)
		)
		(property "MPN" "CR0402-FX-1000GLF"
			(at 275.4 -105.8 0)
			(layer "B.Fab")
			(hide yes)
			(effects
				(font
					(size 1 1)
					(thickness 0.15)
				)
				(justify mirror)
			)
		)
		(property "Manufacturer" "Bourns"
			(at 275.4 -105.8 0)
			(layer "B.Fab")
			(hide yes)
			(effects
				(font
					(size 1 1)
					(thickness 0.15)
				)
				(justify mirror)
			)
		)
		(property "Tolerance" "1%"
			(at 275.4 -105.8 0)
			(layer "B.Fab")
			(hide yes)
			(effects
				(font
					(size 1 1)
					(thickness 0.15)
				)
				(justify mirror)
			)
		)
		(property "Val" "100R"
			(at 275.4 -105.8 0)
			(layer "B.Fab")
			(hide yes)
			(effects
				(font
					(size 1 1)
					(thickness 0.15)
				)
				(justify mirror)
			)
		)
		(sheetname "User GPIO + LED + button + DIP switch")
		(sheetfile "user-gpio.kicad_sch")
		(attr smd)
		(fp_rect
			(start -0.925 0.47)
			(end 0.925 -0.47)
			(stroke
				(width 0.05)
				(type default)
			)
			(fill no)
			(layer "B.CrtYd")
		)
		(fp_rect
			(start -0.5 0.25)
			(end 0.5 -0.25)
			(stroke
				(width 0.15)
				(type solid)
			)
			(fill no)
			(layer "B.Fab")
		)
		(pad "1" smd roundrect
			(at -0.48 0 90)
			(size 0.59 0.64)
			(layers "B.Cu" "B.Mask" "B.Paste")
			(roundrect_rratio 0.25)
			(net 828 "/User GPIO + LED + button + DIP switch/CW_20PIN_TSCK")
			(pintype "passive")
		)
		(pad "2" smd roundrect
			(at 0.48 0 90)
			(size 0.59 0.64)
			(layers "B.Cu" "B.Mask" "B.Paste")
			(roundrect_rratio 0.25)
			(net 477 "/FPGA Bank 12 & 13/CW_HEADER.TSCK")
			(pintype "passive")
		)
	)
	(footprint "antmicro-footprints:C_0603_1608Metric"
		(layer "B.Cu")
		(at 186 181.85)
		(descr "Capacitor SMD 0603")
		(tags "capacitor 0603")
		(property "Reference" "C314"
			(at 1.3 -0.575 180)
			(layer "B.SilkS")
			(effects
				(font
					(size 0.7 0.7)
					(thickness 0.15)
				)
				(justify left bottom mirror)
			)
		)
		(property "Value" "C_1u_25V_0603"
			(at 0 -1.6 180)
			(layer "B.Fab")
			(effects
				(font
					(size 0.7 0.7)
					(thickness 0.15)
				)
				(justify left bottom mirror)
			)
		)
		(property "Description" "SMD Multilayer Ceramic Capacitor, 1 µF, 25 V, 0603 [1608 Metric], ± 10%, X5R, CL"
			(at 0 0 0)
			(layer "F.Fab")
			(hide yes)
			(effects
				(font
					(size 1.27 1.27)
					(thickness 0.15)
				)
			)
		)
		(property "Author" "Antmicro"
			(at 0 0 0)
			(layer "B.Fab")
			(hide yes)
			(effects
				(font
					(size 1 1)
					(thickness 0.15)
				)
				(justify mirror)
			)
		)
		(property "Dielectric" ""
			(at 0 0 0)
			(layer "B.Fab")
			(hide yes)
			(effects
				(font
					(size 1 1)
					(thickness 0.15)
				)
				(justify mirror)
			)
		)
		(property "License" "Apache-2.0"
			(at 0 0 0)
			(layer "B.Fab")
			(hide yes)
			(effects
				(font
					(size 1 1)
					(thickness 0.15)
				)
				(justify mirror)
			)
		)
		(property "MPN" "CL10A105KA8NNNC"
			(at 0 0 0)
			(layer "B.Fab")
			(hide yes)
			(effects
				(font
					(size 1 1)
					(thickness 0.15)
				)
				(justify mirror)
			)
		)
		(property "Manufacturer" "Samsung Electro-Mechanics"
			(at 0 0 0)
			(layer "B.Fab")
			(hide yes)
			(effects
				(font
					(size 1 1)
					(thickness 0.15)
				)
				(justify mirror)
			)
		)
		(property "Val" "1u"
			(at 0 0 0)
			(layer "B.Fab")
			(hide yes)
			(effects
				(font
					(size 1 1)
					(thickness 0.15)
				)
				(justify mirror)
			)
		)
		(property "Voltage" "25V"
			(at 0 0 0)
			(layer "B.Fab")
			(hide yes)
			(effects
				(font
					(size 1 1)
					(thickness 0.15)
				)
				(justify mirror)
			)
		)
		(sheetname "DC-DC Converters")
		(sheetfile "dc-dc.kicad_sch")
		(attr smd)
		(fp_line
			(start -0.15 -0.4)
			(end 0.15 -0.4)
			(stroke
				(width 0.15)
				(type solid)
			)
			(layer "B.SilkS")
		)
		(fp_line
			(start -0.15 0.4)
			(end 0.15 0.4)
			(stroke
				(width 0.15)
				(type solid)
			)
			(layer "B.SilkS")
		)
		(fp_rect
			(start -1.25 0.65)
			(end 1.25 -0.65)
			(stroke
				(width 0.05)
				(type solid)
			)
			(fill no)
			(layer "B.CrtYd")
		)
		(fp_rect
			(start -0.8 0.4)
			(end 0.8 -0.4)
			(stroke
				(width 0.15)
				(type solid)
			)
			(fill no)
			(layer "B.Fab")
		)
		(pad "1" smd roundrect
			(at -0.7 0)
			(size 0.8 1)
			(layers "B.Cu" "B.Mask" "B.Paste")
			(roundrect_rratio 0.2)
			(net 702 "VDC")
			(pintype "passive")
		)
		(pad "2" smd roundrect
			(at 0.7 0)
			(size 0.8 1)
			(layers "B.Cu" "B.Mask" "B.Paste")
			(roundrect_rratio 0.2)
			(net 1 "GND")
			(pintype "passive")
		)
	)
	(footprint "antmicro-footprints:C_0201"
		(layer "B.Cu")
		(at 190 131.5 180)
		(descr "Capacitor SMD 0201")
		(tags "capacitor SMD 0201")
		(property "Reference" "C157"
			(at 0.55 -0.4 0)
			(layer "B.SilkS")
			(effects
				(font
					(size 0.7 0.7)
					(thickness 0.15)
				)
				(justify left bottom mirror)
			)
		)
		(property "Value" "C_100n_0201"
			(at 0 -1.4 0)
			(layer "B.Fab")
			(effects
				(font
					(size 0.7 0.7)
					(thickness 0.15)
				)
				(justify left bottom mirror)
			)
		)
		(property "Description" "SMD Multilayer Ceramic Capacitor, 0.1 µF, 6.3 V, 0201 [0603 Metric], ± 10%, X6S, CC Series"
			(at 0 0 180)
			(layer "F.Fab")
			(hide yes)
			(effects
				(font
					(size 1.27 1.27)
					(thickness 0.15)
				)
			)
		)
		(property "Author" "Antmicro"
			(at 380 263 0)
			(layer "B.Fab")
			(hide yes)
			(effects
				(font
					(size 1 1)
					(thickness 0.15)
				)
				(justify mirror)
			)
		)
		(property "Dielectric" ""
			(at 380 263 0)
			(layer "B.Fab")
			(hide yes)
			(effects
				(font
					(size 1 1)
					(thickness 0.15)
				)
				(justify mirror)
			)
		)
		(property "License" "Apache-2.0"
			(at 380 263 0)
			(layer "B.Fab")
			(hide yes)
			(effects
				(font
					(size 1 1)
					(thickness 0.15)
				)
				(justify mirror)
			)
		)
		(property "MPN" "CC0201KRX6S5BB104"
			(at 380 263 0)
			(layer "B.Fab")
			(hide yes)
			(effects
				(font
					(size 1 1)
					(thickness 0.15)
				)
				(justify mirror)
			)
		)
		(property "Manufacturer" "YAGEO"
			(at 380 263 0)
			(layer "B.Fab")
			(hide yes)
			(effects
				(font
					(size 1 1)
					(thickness 0.15)
				)
				(justify mirror)
			)
		)
		(property "Val" "100n"
			(at 380 263 0)
			(layer "B.Fab")
			(hide yes)
			(effects
				(font
					(size 1 1)
					(thickness 0.15)
				)
				(justify mirror)
			)
		)
		(property "Voltage" ""
			(at 380 263 0)
			(layer "B.Fab")
			(hide yes)
			(effects
				(font
					(size 1 1)
					(thickness 0.15)
				)
				(justify mirror)
			)
		)
		(sheetname "FPGA supply")
		(sheetfile "fpga-supply.kicad_sch")
		(attr smd)
		(fp_rect
			(start -0.7 0.35)
			(end 0.7 -0.35)
			(stroke
				(width 0.05)
				(type default)
			)
			(fill no)
			(layer "B.CrtYd")
		)
		(fp_rect
			(start 0.3 -0.15)
			(end -0.301 0.149)
			(stroke
				(width 0.15)
				(type solid)
			)
			(fill no)
			(layer "B.Fab")
		)
		(pad "" smd roundrect
			(at -0.349 0.002 180)
			(size 0.318 0.36)
			(layers "B.Paste")
			(roundrect_rratio 0.25)
		)
		(pad "" smd roundrect
			(at 0.341 0.002 180)
			(size 0.318 0.36)
			(layers "B.Paste")
			(roundrect_rratio 0.25)
		)
		(pad "1" smd roundrect
			(at -0.321 0.002 180)
			(size 0.46 0.4)
			(layers "B.Cu" "B.Mask")
			(roundrect_rratio 0.25)
			(net 1 "GND")
			(pintype "passive")
		)
		(pad "2" smd roundrect
			(at 0.32 0.002 180)
			(size 0.46 0.4)
			(layers "B.Cu" "B.Mask")
			(roundrect_rratio 0.25)
			(net 8 "+1V2_MGTAVTT")
			(pintype "passive")
		)
	)
	(footprint "antmicro-footprints:R_0402_1005Metric"
		(layer "B.Cu")
		(at 176.1 167.8 180)
		(descr "Resistor SMD 0402")
		(tags "resistor SMD 0402")
		(property "Reference" "R363"
			(at -1.3 0.575 0)
			(layer "B.SilkS")
			(effects
				(font
					(size 0.7 0.7)
					(thickness 0.15)
				)
				(justify left bottom mirror)
			)
		)
		(property "Value" "R_0R_0402"
			(at 0 -1.4 0)
			(layer "B.Fab")
			(effects
				(font
					(size 0.7 0.7)
					(thickness 0.15)
				)
				(justify left bottom mirror)
			)
		)
		(property "Description" "SMD Chip Resistor, Jumper, 0 ohm, 100 mW, 0402 [1005 Metric], Thick Film, General Purpose"
			(at 0 0 180)
			(layer "F.Fab")
			(hide yes)
			(effects
				(font
					(size 1.27 1.27)
					(thickness 0.15)
				)
			)
		)
		(property "Author" "Antmicro"
			(at 352.2 335.6 0)
			(layer "B.Fab")
			(hide yes)
			(effects
				(font
					(size 1 1)
					(thickness 0.15)
				)
				(justify mirror)
			)
		)
		(property "Current" "1A"
			(at 352.2 335.6 0)
			(layer "B.Fab")
			(hide yes)
			(effects
				(font
					(size 1 1)
					(thickness 0.15)
				)
				(justify mirror)
			)
		)
		(property "DNP" "DNP"
			(at 352.2 335.6 0)
			(layer "B.Fab")
			(hide yes)
			(effects
				(font
					(size 1 1)
					(thickness 0.15)
				)
				(justify mirror)
			)
		)
		(property "License" "Apache-2.0"
			(at 352.2 335.6 0)
			(layer "B.Fab")
			(hide yes)
			(effects
				(font
					(size 1 1)
					(thickness 0.15)
				)
				(justify mirror)
			)
		)
		(property "MPN" "ERJ2GE0R00X"
			(at 352.2 335.6 0)
			(layer "B.Fab")
			(hide yes)
			(effects
				(font
					(size 1 1)
					(thickness 0.15)
				)
				(justify mirror)
			)
		)
		(property "Manufacturer" "Panasonic"
			(at 352.2 335.6 0)
			(layer "B.Fab")
			(hide yes)
			(effects
				(font
					(size 1 1)
					(thickness 0.15)
				)
				(justify mirror)
			)
		)
		(property "Tolerance" ""
			(at 352.2 335.6 0)
			(layer "B.Fab")
			(hide yes)
			(effects
				(font
					(size 1 1)
					(thickness 0.15)
				)
				(justify mirror)
			)
		)
		(property "Val" "0R"
			(at 352.2 335.6 0)
			(layer "B.Fab")
			(hide yes)
			(effects
				(font
					(size 1 1)
					(thickness 0.15)
				)
				(justify mirror)
			)
		)
		(property "dnp" ""
			(at 352.2 335.6 0)
			(layer "B.Fab")
			(hide yes)
			(effects
				(font
					(size 1 1)
					(thickness 0.15)
				)
				(justify mirror)
			)
		)
		(property "exclude_from_bom" ""
			(at 352.2 335.6 0)
			(layer "B.Fab")
			(hide yes)
			(effects
				(font
					(size 1 1)
					(thickness 0.15)
				)
				(justify mirror)
			)
		)
		(sheetname "DC-DC Converters")
		(sheetfile "dc-dc.kicad_sch")
		(attr smd exclude_from_bom)
		(fp_rect
			(start -0.925 0.47)
			(end 0.925 -0.47)
			(stroke
				(width 0.05)
				(type default)
			)
			(fill no)
			(layer "B.CrtYd")
		)
		(fp_rect
			(start -0.5 0.25)
			(end 0.5 -0.25)
			(stroke
				(width 0.15)
				(type solid)
			)
			(fill no)
			(layer "B.Fab")
		)
		(pad "1" smd roundrect
			(at -0.48 0 180)
			(size 0.59 0.64)
			(layers "B.Cu" "B.Mask" "B.Paste")
			(roundrect_rratio 0.25)
			(net 1052 "/DC-DC Converters/SW2")
			(pintype "passive")
		)
		(pad "2" smd roundrect
			(at 0.48 0 180)
			(size 0.59 0.64)
			(layers "B.Cu" "B.Mask" "B.Paste")
			(roundrect_rratio 0.25)
			(net 1143 "/DC-DC Converters/SW1")
			(pintype "passive")
		)
	)
	(footprint "antmicro-footprints:C_0402_1005Metric"
		(layer "B.Cu")
		(at 190 138.5)
		(descr "Capacitor SMD 0402")
		(tags "capacitor SMD 0402")
		(property "Reference" "C375"
			(at 0.925 1.275 180)
			(layer "B.SilkS")
			(effects
				(font
					(size 0.7 0.7)
					(thickness 0.15)
				)
				(justify left bottom mirror)
			)
		)
		(property "Value" "C_100n_0402"
			(at 0 -1.169 180)
			(layer "B.Fab")
			(effects
				(font
					(size 0.7 0.7)
					(thickness 0.15)
				)
				(justify left bottom mirror)
			)
		)
		(property "Description" "SMD Multilayer Ceramic Capacitor, 0.1 µF, 50 V, 0402 [1005 Metric], ± 10%, X5R, GRM Series"
			(at 0 0 0)
			(layer "F.Fab")
			(hide yes)
			(effects
				(font
					(size 1.27 1.27)
					(thickness 0.15)
				)
			)
		)
		(property "Author" "Antmicro"
			(at 0 0 0)
			(layer "B.Fab")
			(hide yes)
			(effects
				(font
					(size 1 1)
					(thickness 0.15)
				)
				(justify mirror)
			)
		)
		(property "Dielectric" "X5R"
			(at 0 0 0)
			(layer "B.Fab")
			(hide yes)
			(effects
				(font
					(size 1 1)
					(thickness 0.15)
				)
				(justify mirror)
			)
		)
		(property "License" "Apache-2.0"
			(at 0 0 0)
			(layer "B.Fab")
			(hide yes)
			(effects
				(font
					(size 1 1)
					(thickness 0.15)
				)
				(justify mirror)
			)
		)
		(property "MPN" "GRM155R61H104KE14D"
			(at 0 0 0)
			(layer "B.Fab")
			(hide yes)
			(effects
				(font
					(size 1 1)
					(thickness 0.15)
				)
				(justify mirror)
			)
		)
		(property "Manufacturer" "Murata"
			(at 0 0 0)
			(layer "B.Fab")
			(hide yes)
			(effects
				(font
					(size 1 1)
					(thickness 0.15)
				)
				(justify mirror)
			)
		)
		(property "Val" "100n"
			(at 0 0 0)
			(layer "B.Fab")
			(hide yes)
			(effects
				(font
					(size 1 1)
					(thickness 0.15)
				)
				(justify mirror)
			)
		)
		(property "Voltage" "50V"
			(at 0 0 0)
			(layer "B.Fab")
			(hide yes)
			(effects
				(font
					(size 1 1)
					(thickness 0.15)
				)
				(justify mirror)
			)
		)
		(sheetname "FPGA Bank 33 & 34")
		(sheetfile "fpga-bank-33-34.kicad_sch")
		(attr smd)
		(fp_rect
			(start -0.925 0.47)
			(end 0.925 -0.47)
			(stroke
				(width 0.05)
				(type default)
			)
			(fill no)
			(layer "B.CrtYd")
		)
		(fp_line
			(start -0.494 -0.248)
			(end -0.494 0.25)
			(stroke
				(width 0.15)
				(type solid)
			)
			(layer "B.Fab")
		)
		(fp_line
			(start -0.494 0.25)
			(end 0.504 0.25)
			(stroke
				(width 0.15)
				(type solid)
			)
			(layer "B.Fab")
		)
		(fp_line
			(start 0.504 -0.248)
			(end -0.494 -0.248)
			(stroke
				(width 0.15)
				(type solid)
			)
			(layer "B.Fab")
		)
		(fp_line
			(start 0.504 0.25)
			(end 0.504 -0.248)
			(stroke
				(width 0.15)
				(type solid)
			)
			(layer "B.Fab")
		)
		(pad "1" smd roundrect
			(at -0.48 0)
			(size 0.59 0.64)
			(layers "B.Cu" "B.Mask" "B.Paste")
			(roundrect_rratio 0.25)
			(net 1 "GND")
			(pintype "passive")
		)
		(pad "2" smd roundrect
			(at 0.48 0)
			(size 0.59 0.64)
			(layers "B.Cu" "B.Mask" "B.Paste")
			(roundrect_rratio 0.25)
			(net 11 "+0V675_VREF")
			(pintype "passive")
		)
	)
	(footprint "antmicro-footprints:R_0402_1005Metric"
		(layer "B.Cu")
		(at 265.936 148.3)
		(descr "Resistor SMD 0402")
		(tags "resistor SMD 0402")
		(property "Reference" "R58"
			(at -3.851 0.325 180)
			(layer "B.SilkS")
			(effects
				(font
					(size 0.7 0.7)
					(thickness 0.15)
				)
				(justify left bottom mirror)
			)
		)
		(property "Value" "R_1k_0402"
			(at 0 -1.4 180)
			(layer "B.Fab")
			(effects
				(font
					(size 0.7 0.7)
					(thickness 0.15)
				)
				(justify left bottom mirror)
			)
		)
		(property "Description" "SMD Chip Resistor, 1 kohm, ± 1%, 63 mW, 0402 [1005 Metric], Thick Film, General Purpose"
			(at 0 0 0)
			(layer "F.Fab")
			(hide yes)
			(effects
				(font
					(size 1.27 1.27)
					(thickness 0.15)
				)
			)
		)
		(property "Author" "Antmicro"
			(at 0 0 0)
			(layer "B.Fab")
			(hide yes)
			(effects
				(font
					(size 1 1)
					(thickness 0.15)
				)
				(justify mirror)
			)
		)
		(property "License" "Apache-2.0"
			(at 0 0 0)
			(layer "B.Fab")
			(hide yes)
			(effects
				(font
					(size 1 1)
					(thickness 0.15)
				)
				(justify mirror)
			)
		)
		(property "MPN" "CR0402-FX-1001GLF"
			(at 0 0 0)
			(layer "B.Fab")
			(hide yes)
			(effects
				(font
					(size 1 1)
					(thickness 0.15)
				)
				(justify mirror)
			)
		)
		(property "Manufacturer" "Bourns"
			(at 0 0 0)
			(layer "B.Fab")
			(hide yes)
			(effects
				(font
					(size 1 1)
					(thickness 0.15)
				)
				(justify mirror)
			)
		)
		(property "Tolerance" "1%"
			(at 0 0 0)
			(layer "B.Fab")
			(hide yes)
			(effects
				(font
					(size 1 1)
					(thickness 0.15)
				)
				(justify mirror)
			)
		)
		(property "Val" "1k"
			(at 0 0 0)
			(layer "B.Fab")
			(hide yes)
			(effects
				(font
					(size 1 1)
					(thickness 0.15)
				)
				(justify mirror)
			)
		)
		(sheetname "Power supply")
		(sheetfile "power-supply.kicad_sch")
		(attr smd)
		(fp_rect
			(start -0.925 0.47)
			(end 0.925 -0.47)
			(stroke
				(width 0.05)
				(type default)
			)
			(fill no)
			(layer "B.CrtYd")
		)
		(fp_rect
			(start -0.5 0.25)
			(end 0.5 -0.25)
			(stroke
				(width 0.15)
				(type solid)
			)
			(fill no)
			(layer "B.Fab")
		)
		(pad "1" smd roundrect
			(at -0.48 0)
			(size 0.59 0.64)
			(layers "B.Cu" "B.Mask" "B.Paste")
			(roundrect_rratio 0.25)
			(net 24 "+3V3")
			(pintype "passive")
		)
		(pad "2" smd roundrect
			(at 0.48 0)
			(size 0.59 0.64)
			(layers "B.Cu" "B.Mask" "B.Paste")
			(roundrect_rratio 0.25)
			(net 19 "Net-(D11-A)")
			(pintype "passive")
		)
	)
	(footprint "antmicro-footprints:R_1206_3216Metric"
		(layer "B.Cu")
		(at 255.231 178.63 90)
		(property "Reference" "R47"
			(at 2.255 1.019 0)
			(layer "B.SilkS")
			(effects
				(font
					(size 0.7 0.7)
					(thickness 0.15)
				)
				(justify left bottom mirror)
			)
		)
		(property "Value" "R_1k3_1206"
			(at 0 -2 270)
			(layer "B.Fab")
			(effects
				(font
					(size 0.7 0.7)
					(thickness 0.15)
				)
				(justify left bottom mirror)
			)
		)
		(property "Description" "SMT Chip Resistor, 1.3 kohm, ± 1%, 250 mW, 1206 [3216 Metric], Thick Film, General Purpose"
			(at 0 0 90)
			(layer "F.Fab")
			(hide yes)
			(effects
				(font
					(size 1.27 1.27)
					(thickness 0.15)
				)
			)
		)
		(property "Author" "Antmicro"
			(at 433.861 -76.601 0)
			(layer "B.Fab")
			(hide yes)
			(effects
				(font
					(size 1 1)
					(thickness 0.15)
				)
				(justify mirror)
			)
		)
		(property "License" "Apache-2.0"
			(at 433.861 -76.601 0)
			(layer "B.Fab")
			(hide yes)
			(effects
				(font
					(size 1 1)
					(thickness 0.15)
				)
				(justify mirror)
			)
		)
		(property "MPN" "CR1206-JW-132ELF"
			(at 433.861 -76.601 0)
			(layer "B.Fab")
			(hide yes)
			(effects
				(font
					(size 1 1)
					(thickness 0.15)
				)
				(justify mirror)
			)
		)
		(property "Manufacturer" "Bourns"
			(at 433.861 -76.601 0)
			(layer "B.Fab")
			(hide yes)
			(effects
				(font
					(size 1 1)
					(thickness 0.15)
				)
				(justify mirror)
			)
		)
		(property "Tolerance" "1%"
			(at 433.861 -76.601 0)
			(layer "B.Fab")
			(hide yes)
			(effects
				(font
					(size 1 1)
					(thickness 0.15)
				)
				(justify mirror)
			)
		)
		(property "Val" "1k3"
			(at 433.861 -76.601 0)
			(layer "B.Fab")
			(hide yes)
			(effects
				(font
					(size 1 1)
					(thickness 0.15)
				)
				(justify mirror)
			)
		)
		(sheetname "Power supply")
		(sheetfile "power-supply.kicad_sch")
		(attr smd)
		(fp_line
			(start 0.8 -0.901)
			(end -0.8 -0.901)
			(stroke
				(width 0.15)
				(type solid)
			)
			(layer "B.SilkS")
		)
		(fp_line
			(start 0.8 0.899)
			(end -0.8 0.899)
			(stroke
				(width 0.15)
				(type solid)
			)
			(layer "B.SilkS")
		)
		(fp_rect
			(start -2.325 1.15)
			(end 2.325 -1.15)
			(stroke
				(width 0.05)
				(type default)
			)
			(fill no)
			(layer "B.CrtYd")
		)
		(fp_line
			(start -1.601 -0.8)
			(end 1.6 -0.8)
			(stroke
				(width 0.15)
				(type solid)
			)
			(layer "B.Fab")
		)
		(fp_line
			(start 1.6 0.802)
			(end 1.6 -0.8)
			(stroke
				(width 0.15)
				(type solid)
			)
			(layer "B.Fab")
		)
		(fp_line
			(start -1.601 0.802)
			(end -1.601 -0.8)
			(stroke
				(width 0.15)
				(type solid)
			)
			(layer "B.Fab")
		)
		(fp_line
			(start -1.601 0.802)
			(end 1.6 0.802)
			(stroke
				(width 0.15)
				(type solid)
			)
			(layer "B.Fab")
		)
		(pad "1" smd roundrect
			(at -1.5 -0.001 90)
			(size 1.15 1.8)
			(layers "B.Cu" "B.Mask" "B.Paste")
			(roundrect_rratio 0.25)
			(net 697 "/Power supply/VSS")
			(pintype "passive")
		)
		(pad "2" smd roundrect
			(at 1.5 -0.001 90)
			(size 1.15 1.8)
			(layers "B.Cu" "B.Mask" "B.Paste")
			(roundrect_rratio 0.25)
			(net 881 "/Power supply/AMPS_CTL")
			(pintype "passive")
		)
	)
	(footprint "antmicro-footprints:C_0201"
		(layer "B.Cu")
		(at 184.350001 127.500001)
		(descr "Capacitor SMD 0201")
		(tags "capacitor SMD 0201")
		(property "Reference" "C161"
			(at -3.350001 0.374999 0)
			(layer "B.SilkS")
			(effects
				(font
					(size 0.7 0.7)
					(thickness 0.15)
				)
				(justify right bottom mirror)
			)
		)
		(property "Value" "C_4u7_0201"
			(at 0 -1.4 0)
			(layer "B.Fab")
			(effects
				(font
					(size 0.7 0.7)
					(thickness 0.15)
				)
				(justify right bottom mirror)
			)
		)
		(property "Description" "SMD Multilayer Ceramic Capacitor, 4.7 µF, 6.3 V, 0201 [0603 Metric], ± 20%, X5R, GRM Series"
			(at 0 0 0)
			(layer "F.Fab")
			(hide yes)
			(effects
				(font
					(size 1.27 1.27)
					(thickness 0.15)
				)
			)
		)
		(property "Author" "Antmicro"
			(at 0 0 0)
			(layer "B.Fab")
			(hide yes)
			(effects
				(font
					(size 1 1)
					(thickness 0.15)
				)
				(justify mirror)
			)
		)
		(property "Dielectric" ""
			(at 0 0 0)
			(layer "B.Fab")
			(hide yes)
			(effects
				(font
					(size 1 1)
					(thickness 0.15)
				)
				(justify mirror)
			)
		)
		(property "License" "Apache-2.0"
			(at 0 0 0)
			(layer "B.Fab")
			(hide yes)
			(effects
				(font
					(size 1 1)
					(thickness 0.15)
				)
				(justify mirror)
			)
		)
		(property "MPN" "GRM035R60J475ME15D"
			(at 0 0 0)
			(layer "B.Fab")
			(hide yes)
			(effects
				(font
					(size 1 1)
					(thickness 0.15)
				)
				(justify mirror)
			)
		)
		(property "Manufacturer" "Murata"
			(at 0 0 0)
			(layer "B.Fab")
			(hide yes)
			(effects
				(font
					(size 1 1)
					(thickness 0.15)
				)
				(justify mirror)
			)
		)
		(property "Val" "4u7"
			(at 0 0 0)
			(layer "B.Fab")
			(hide yes)
			(effects
				(font
					(size 1 1)
					(thickness 0.15)
				)
				(justify mirror)
			)
		)
		(property "Voltage" ""
			(at 0 0 0)
			(layer "B.Fab")
			(hide yes)
			(effects
				(font
					(size 1 1)
					(thickness 0.15)
				)
				(justify mirror)
			)
		)
		(sheetname "FPGA supply")
		(sheetfile "fpga-supply.kicad_sch")
		(attr smd)
		(fp_rect
			(start -0.7 0.35)
			(end 0.7 -0.35)
			(stroke
				(width 0.05)
				(type default)
			)
			(fill no)
			(layer "B.CrtYd")
		)
		(fp_rect
			(start 0.3 -0.15)
			(end -0.301 0.149)
			(stroke
				(width 0.15)
				(type solid)
			)
			(fill no)
			(layer "B.Fab")
		)
		(pad "" smd roundrect
			(at -0.349 0.002)
			(size 0.318 0.36)
			(layers "B.Paste")
			(roundrect_rratio 0.25)
		)
		(pad "" smd roundrect
			(at 0.341 0.002)
			(size 0.318 0.36)
			(layers "B.Paste")
			(roundrect_rratio 0.25)
		)
		(pad "1" smd roundrect
			(at -0.321 0.002)
			(size 0.46 0.4)
			(layers "B.Cu" "B.Mask")
			(roundrect_rratio 0.25)
			(net 1 "GND")
			(pintype "passive")
		)
		(pad "2" smd roundrect
			(at 0.32 0.002)
			(size 0.46 0.4)
			(layers "B.Cu" "B.Mask")
			(roundrect_rratio 0.25)
			(net 8 "+1V2_MGTAVTT")
			(pintype "passive")
		)
	)
	(footprint "antmicro-footprints:R_0402_1005Metric"
		(layer "B.Cu")
		(at 158.825001 79.930001 90)
		(descr "Resistor SMD 0402")
		(tags "resistor SMD 0402")
		(property "Reference" "R264"
			(at 1.305001 -0.500001 270)
			(layer "B.SilkS")
			(effects
				(font
					(size 0.7 0.7)
					(thickness 0.15)
				)
				(justify left bottom mirror)
			)
		)
		(property "Value" "R_100k_0402"
			(at 0 -1.4 270)
			(layer "B.Fab")
			(effects
				(font
					(size 0.7 0.7)
					(thickness 0.15)
				)
				(justify left bottom mirror)
			)
		)
		(property "Description" "SMD Chip Resistor, 100 kohm, ± 1%, 62.5 mW, 0402 [1005 Metric], Thick Film, General Purpose"
			(at 0 0 90)
			(layer "F.Fab")
			(hide yes)
			(effects
				(font
					(size 1.27 1.27)
					(thickness 0.15)
				)
			)
		)
		(property "Author" "Antmicro"
			(at 238.755002 -78.895 0)
			(layer "B.Fab")
			(hide yes)
			(effects
				(font
					(size 1 1)
					(thickness 0.15)
				)
				(justify mirror)
			)
		)
		(property "License" "Apache-2.0"
			(at 238.755002 -78.895 0)
			(layer "B.Fab")
			(hide yes)
			(effects
				(font
					(size 1 1)
					(thickness 0.15)
				)
				(justify mirror)
			)
		)
		(property "MPN" "CR0402-FX-1003GLF"
			(at 238.755002 -78.895 0)
			(layer "B.Fab")
			(hide yes)
			(effects
				(font
					(size 1 1)
					(thickness 0.15)
				)
				(justify mirror)
			)
		)
		(property "Manufacturer" "Bourns"
			(at 238.755002 -78.895 0)
			(layer "B.Fab")
			(hide yes)
			(effects
				(font
					(size 1 1)
					(thickness 0.15)
				)
				(justify mirror)
			)
		)
		(property "Tolerance" "1%"
			(at 238.755002 -78.895 0)
			(layer "B.Fab")
			(hide yes)
			(effects
				(font
					(size 1 1)
					(thickness 0.15)
				)
				(justify mirror)
			)
		)
		(property "Val" "100k"
			(at 238.755002 -78.895 0)
			(layer "B.Fab")
			(hide yes)
			(effects
				(font
					(size 1 1)
					(thickness 0.15)
				)
				(justify mirror)
			)
		)
		(sheetname "FMC+ HSPC")
		(sheetfile "fmc-hspc.kicad_sch")
		(attr smd)
		(fp_rect
			(start -0.925 0.47)
			(end 0.925 -0.47)
			(stroke
				(width 0.05)
				(type default)
			)
			(fill no)
			(layer "B.CrtYd")
		)
		(fp_rect
			(start -0.5 0.25)
			(end 0.5 -0.25)
			(stroke
				(width 0.15)
				(type solid)
			)
			(fill no)
			(layer "B.Fab")
		)
		(pad "1" smd roundrect
			(at -0.48 0 90)
			(size 0.59 0.64)
			(layers "B.Cu" "B.Mask" "B.Paste")
			(roundrect_rratio 0.25)
			(net 696 "/FMC+ HSPC/FMC.PRSNT_M2C")
			(pintype "passive")
		)
		(pad "2" smd roundrect
			(at 0.48 0 90)
			(size 0.59 0.64)
			(layers "B.Cu" "B.Mask" "B.Paste")
			(roundrect_rratio 0.25)
			(net 24 "+3V3")
			(pintype "passive")
		)
	)
	(footprint "antmicro-footprints:R_0402_1005Metric"
		(layer "B.Cu")
		(at 258.4 93.4 -90)
		(descr "Resistor SMD 0402")
		(tags "resistor SMD 0402")
		(property "Reference" "R357"
			(at -1.45 -1.275 90)
			(layer "B.SilkS")
			(effects
				(font
					(size 0.7 0.7)
					(thickness 0.15)
				)
				(justify left bottom mirror)
			)
		)
		(property "Value" "R_100k_0402"
			(at 0 -1.4 90)
			(layer "B.Fab")
			(effects
				(font
					(size 0.7 0.7)
					(thickness 0.15)
				)
				(justify left bottom mirror)
			)
		)
		(property "Description" "SMD Chip Resistor, 100 kohm, ± 1%, 62.5 mW, 0402 [1005 Metric], Thick Film, General Purpose"
			(at 0 0 270)
			(layer "F.Fab")
			(hide yes)
			(effects
				(font
					(size 1.27 1.27)
					(thickness 0.15)
				)
			)
		)
		(property "Author" "Antmicro"
			(at 165 351.8 0)
			(layer "B.Fab")
			(hide yes)
			(effects
				(font
					(size 1 1)
					(thickness 0.15)
				)
				(justify mirror)
			)
		)
		(property "License" "Apache-2.0"
			(at 165 351.8 0)
			(layer "B.Fab")
			(hide yes)
			(effects
				(font
					(size 1 1)
					(thickness 0.15)
				)
				(justify mirror)
			)
		)
		(property "MPN" "CR0402-FX-1003GLF"
			(at 165 351.8 0)
			(layer "B.Fab")
			(hide yes)
			(effects
				(font
					(size 1 1)
					(thickness 0.15)
				)
				(justify mirror)
			)
		)
		(property "Manufacturer" "Bourns"
			(at 165 351.8 0)
			(layer "B.Fab")
			(hide yes)
			(effects
				(font
					(size 1 1)
					(thickness 0.15)
				)
				(justify mirror)
			)
		)
		(property "Tolerance" "1%"
			(at 165 351.8 0)
			(layer "B.Fab")
			(hide yes)
			(effects
				(font
					(size 1 1)
					(thickness 0.15)
				)
				(justify mirror)
			)
		)
		(property "Val" "100k"
			(at 165 351.8 0)
			(layer "B.Fab")
			(hide yes)
			(effects
				(font
					(size 1 1)
					(thickness 0.15)
				)
				(justify mirror)
			)
		)
		(sheetname "User GPIO + LED + button + DIP switch")
		(sheetfile "user-gpio.kicad_sch")
		(attr smd)
		(fp_rect
			(start -0.925 0.47)
			(end 0.925 -0.47)
			(stroke
				(width 0.05)
				(type default)
			)
			(fill no)
			(layer "B.CrtYd")
		)
		(fp_rect
			(start -0.5 0.25)
			(end 0.5 -0.25)
			(stroke
				(width 0.15)
				(type solid)
			)
			(fill no)
			(layer "B.Fab")
		)
		(pad "1" smd roundrect
			(at -0.48 0 270)
			(size 0.59 0.64)
			(layers "B.Cu" "B.Mask" "B.Paste")
			(roundrect_rratio 0.25)
			(net 1303 "/USER_IO.LED_GREEN4")
			(pintype "passive")
		)
		(pad "2" smd roundrect
			(at 0.48 0 270)
			(size 0.59 0.64)
			(layers "B.Cu" "B.Mask" "B.Paste")
			(roundrect_rratio 0.25)
			(net 1 "GND")
			(pintype "passive")
		)
	)
	(footprint "antmicro-footprints:C_0201"
		(layer "B.Cu")
		(at 198.5 128)
		(descr "Capacitor SMD 0201")
		(tags "capacitor SMD 0201")
		(property "Reference" "C388"
			(at 23.5 -28.825 0)
			(layer "B.SilkS")
			(effects
				(font
					(size 0.7 0.7)
					(thickness 0.15)
				)
				(justify right bottom mirror)
			)
		)
		(property "Value" "C_100n_0201"
			(at 0 -1.4 0)
			(layer "B.Fab")
			(effects
				(font
					(size 0.7 0.7)
					(thickness 0.15)
				)
				(justify right bottom mirror)
			)
		)
		(property "Description" "SMD Multilayer Ceramic Capacitor, 0.1 µF, 6.3 V, 0201 [0603 Metric], ± 10%, X6S, CC Series"
			(at 0 0 0)
			(layer "F.Fab")
			(hide yes)
			(effects
				(font
					(size 1.27 1.27)
					(thickness 0.15)
				)
			)
		)
		(property "Author" "Antmicro"
			(at 0 0 0)
			(layer "B.Fab")
			(hide yes)
			(effects
				(font
					(size 1 1)
					(thickness 0.15)
				)
				(justify mirror)
			)
		)
		(property "Dielectric" ""
			(at 0 0 0)
			(layer "B.Fab")
			(hide yes)
			(effects
				(font
					(size 1 1)
					(thickness 0.15)
				)
				(justify mirror)
			)
		)
		(property "License" "Apache-2.0"
			(at 0 0 0)
			(layer "B.Fab")
			(hide yes)
			(effects
				(font
					(size 1 1)
					(thickness 0.15)
				)
				(justify mirror)
			)
		)
		(property "MPN" "CC0201KRX6S5BB104"
			(at 0 0 0)
			(layer "B.Fab")
			(hide yes)
			(effects
				(font
					(size 1 1)
					(thickness 0.15)
				)
				(justify mirror)
			)
		)
		(property "Manufacturer" "YAGEO"
			(at 0 0 0)
			(layer "B.Fab")
			(hide yes)
			(effects
				(font
					(size 1 1)
					(thickness 0.15)
				)
				(justify mirror)
			)
		)
		(property "Val" "100n"
			(at 0 0 0)
			(layer "B.Fab")
			(hide yes)
			(effects
				(font
					(size 1 1)
					(thickness 0.15)
				)
				(justify mirror)
			)
		)
		(property "Voltage" ""
			(at 0 0 0)
			(layer "B.Fab")
			(hide yes)
			(effects
				(font
					(size 1 1)
					(thickness 0.15)
				)
				(justify mirror)
			)
		)
		(sheetname "FPGA supply")
		(sheetfile "fpga-supply.kicad_sch")
		(attr smd)
		(fp_rect
			(start -0.7 0.35)
			(end 0.7 -0.35)
			(stroke
				(width 0.05)
				(type default)
			)
			(fill no)
			(layer "B.CrtYd")
		)
		(fp_rect
			(start 0.3 -0.15)
			(end -0.301 0.149)
			(stroke
				(width 0.15)
				(type solid)
			)
			(fill no)
			(layer "B.Fab")
		)
		(pad "" smd roundrect
			(at -0.349 0.002)
			(size 0.318 0.36)
			(layers "B.Paste")
			(roundrect_rratio 0.25)
		)
		(pad "" smd roundrect
			(at 0.341 0.002)
			(size 0.318 0.36)
			(layers "B.Paste")
			(roundrect_rratio 0.25)
		)
		(pad "1" smd roundrect
			(at -0.321 0.002)
			(size 0.46 0.4)
			(layers "B.Cu" "B.Mask")
			(roundrect_rratio 0.25)
			(net 1 "GND")
			(pintype "passive")
		)
		(pad "2" smd roundrect
			(at 0.32 0.002)
			(size 0.46 0.4)
			(layers "B.Cu" "B.Mask")
			(roundrect_rratio 0.25)
			(net 622 "+1V85_ADC")
			(pintype "passive")
		)
	)
	(footprint "antmicro-footprints:F_1206_3216Metric"
		(layer "B.Cu")
		(at 259.251 181.75)
		(property "Reference" "F1"
			(at 0.624 2.075 180)
			(layer "B.SilkS")
			(effects
				(font
					(size 0.7 0.7)
					(thickness 0.15)
				)
				(justify left bottom mirror)
			)
		)
		(property "Value" "F_10A_1206"
			(at 0 -2 180)
			(layer "B.Fab")
			(effects
				(font
					(size 0.7 0.7)
					(thickness 0.15)
				)
				(justify left bottom mirror)
			)
		)
		(property "Description" "Fuse, Surface Mount, 10 A, Slow Blow, 32 VAC, 63 VDC, 1206 (3216 Metric), UST 1206"
			(at 0 0 0)
			(layer "F.Fab")
			(hide yes)
			(effects
				(font
					(size 1.27 1.27)
					(thickness 0.15)
				)
			)
		)
		(property "Author" "Antmicro"
			(at 0 0 0)
			(layer "B.Fab")
			(hide yes)
			(effects
				(font
					(size 1 1)
					(thickness 0.15)
				)
				(justify mirror)
			)
		)
		(property "License" "Apache-2.0"
			(at 0 0 0)
			(layer "B.Fab")
			(hide yes)
			(effects
				(font
					(size 1 1)
					(thickness 0.15)
				)
				(justify mirror)
			)
		)
		(property "MPN" "3413.0328.22"
			(at 0 0 0)
			(layer "B.Fab")
			(hide yes)
			(effects
				(font
					(size 1 1)
					(thickness 0.15)
				)
				(justify mirror)
			)
		)
		(property "Manufacturer" "Schurter"
			(at 0 0 0)
			(layer "B.Fab")
			(hide yes)
			(effects
				(font
					(size 1 1)
					(thickness 0.15)
				)
				(justify mirror)
			)
		)
		(sheetname "Power supply")
		(sheetfile "power-supply.kicad_sch")
		(attr smd)
		(fp_line
			(start 0.8 -0.901)
			(end -0.8 -0.901)
			(stroke
				(width 0.15)
				(type solid)
			)
			(layer "B.SilkS")
		)
		(fp_line
			(start 0.8 0.899)
			(end -0.8 0.899)
			(stroke
				(width 0.15)
				(type solid)
			)
			(layer "B.SilkS")
		)
		(fp_rect
			(start -2.325 1.15)
			(end 2.325 -1.15)
			(stroke
				(width 0.05)
				(type default)
			)
			(fill no)
			(layer "B.CrtYd")
		)
		(fp_line
			(start -1.677 -0.792)
			(end -1.677 0.861)
			(stroke
				(width 0.15)
				(type solid)
			)
			(layer "B.Fab")
		)
		(fp_line
			(start -1.677 0.861)
			(end 1.624 0.861)
			(stroke
				(width 0.15)
				(type solid)
			)
			(layer "B.Fab")
		)
		(fp_line
			(start 1.624 -0.792)
			(end -1.677 -0.792)
			(stroke
				(width 0.15)
				(type solid)
			)
			(layer "B.Fab")
		)
		(fp_line
			(start 1.624 0.861)
			(end 1.624 -0.792)
			(stroke
				(width 0.15)
				(type solid)
			)
			(layer "B.Fab")
		)
		(pad "1" smd roundrect
			(at -1.5 -0.001)
			(size 1.15 1.8)
			(layers "B.Cu" "B.Mask" "B.Paste")
			(roundrect_rratio 0.25)
			(net 1192 "Net-(F1-Pad1)")
			(pintype "passive")
		)
		(pad "2" smd roundrect
			(at 1.5 -0.001)
			(size 1.15 1.8)
			(layers "B.Cu" "B.Mask" "B.Paste")
			(roundrect_rratio 0.25)
			(net 4 "/Power supply/DC_IN")
			(pintype "passive")
		)
	)
	(footprint "antmicro-footprints:R_0402_1005Metric"
		(layer "B.Cu")
		(at 253.501 161.6 90)
		(descr "Resistor SMD 0402")
		(tags "resistor SMD 0402")
		(property "Reference" "R249"
			(at 1.35 5.874 270)
			(layer "B.SilkS")
			(effects
				(font
					(size 0.7 0.7)
					(thickness 0.15)
				)
				(justify left bottom mirror)
			)
		)
		(property "Value" "R_49R9_0402"
			(at 0 -1.4 270)
			(layer "B.Fab")
			(effects
				(font
					(size 0.7 0.7)
					(thickness 0.15)
				)
				(justify left bottom mirror)
			)
		)
		(property "Description" "SMD Chip Resistor, 49.9 ohm, ± 1%, 62.5 mW, 0402 [1005 Metric], Thick Film, General Purpose"
			(at 0 0 90)
			(layer "F.Fab")
			(hide yes)
			(effects
				(font
					(size 1.27 1.27)
					(thickness 0.15)
				)
			)
		)
		(property "Author" "Antmicro"
			(at 415.101 -91.901 0)
			(layer "B.Fab")
			(hide yes)
			(effects
				(font
					(size 1 1)
					(thickness 0.15)
				)
				(justify mirror)
			)
		)
		(property "License" "Apache-2.0"
			(at 415.101 -91.901 0)
			(layer "B.Fab")
			(hide yes)
			(effects
				(font
					(size 1 1)
					(thickness 0.15)
				)
				(justify mirror)
			)
		)
		(property "MPN" "CR0402-FX-49R9GLF"
			(at 415.101 -91.901 0)
			(layer "B.Fab")
			(hide yes)
			(effects
				(font
					(size 1 1)
					(thickness 0.15)
				)
				(justify mirror)
			)
		)
		(property "Manufacturer" "Bourns"
			(at 415.101 -91.901 0)
			(layer "B.Fab")
			(hide yes)
			(effects
				(font
					(size 1 1)
					(thickness 0.15)
				)
				(justify mirror)
			)
		)
		(property "Tolerance" "1%"
			(at 415.101 -91.901 0)
			(layer "B.Fab")
			(hide yes)
			(effects
				(font
					(size 1 1)
					(thickness 0.15)
				)
				(justify mirror)
			)
		)
		(property "Val" "49R9"
			(at 415.101 -91.901 0)
			(layer "B.Fab")
			(hide yes)
			(effects
				(font
					(size 1 1)
					(thickness 0.15)
				)
				(justify mirror)
			)
		)
		(sheetname "HDMI + Ethernet")
		(sheetfile "hdmi-ethernet.kicad_sch")
		(attr smd)
		(fp_rect
			(start -0.925 0.47)
			(end 0.925 -0.47)
			(stroke
				(width 0.05)
				(type default)
			)
			(fill no)
			(layer "B.CrtYd")
		)
		(fp_rect
			(start -0.5 0.25)
			(end 0.5 -0.25)
			(stroke
				(width 0.15)
				(type solid)
			)
			(fill no)
			(layer "B.Fab")
		)
		(pad "1" smd roundrect
			(at -0.48 0 90)
			(size 0.59 0.64)
			(layers "B.Cu" "B.Mask" "B.Paste")
			(roundrect_rratio 0.25)
			(net 726 "/HDMI + Ethernet/ETH2_P")
			(pintype "passive")
		)
		(pad "2" smd roundrect
			(at 0.48 0 90)
			(size 0.59 0.64)
			(layers "B.Cu" "B.Mask" "B.Paste")
			(roundrect_rratio 0.25)
			(net 721 "/HDMI + Ethernet/ETH_3V3")
			(pintype "passive")
		)
	)
	(footprint "antmicro-footprints:C_0402_1005Metric"
		(layer "B.Cu")
		(at 211.5 120 90)
		(descr "Capacitor SMD 0402")
		(tags "capacitor SMD 0402")
		(property "Reference" "C33"
			(at 1.1 1.25 270)
			(layer "B.SilkS")
			(effects
				(font
					(size 0.7 0.7)
					(thickness 0.15)
				)
				(justify left bottom mirror)
			)
		)
		(property "Value" "C_100n_0402"
			(at 0 -1.169 270)
			(layer "B.Fab")
			(effects
				(font
					(size 0.7 0.7)
					(thickness 0.15)
				)
				(justify left bottom mirror)
			)
		)
		(property "Description" "SMD Multilayer Ceramic Capacitor, 0.1 µF, 50 V, 0402 [1005 Metric], ± 10%, X5R, GRM Series"
			(at 0 0 90)
			(layer "F.Fab")
			(hide yes)
			(effects
				(font
					(size 1.27 1.27)
					(thickness 0.15)
				)
			)
		)
		(property "Author" "Antmicro"
			(at 331.5 -91.5 0)
			(layer "B.Fab")
			(hide yes)
			(effects
				(font
					(size 1 1)
					(thickness 0.15)
				)
				(justify mirror)
			)
		)
		(property "Dielectric" "X5R"
			(at 331.5 -91.5 0)
			(layer "B.Fab")
			(hide yes)
			(effects
				(font
					(size 1 1)
					(thickness 0.15)
				)
				(justify mirror)
			)
		)
		(property "License" "Apache-2.0"
			(at 331.5 -91.5 0)
			(layer "B.Fab")
			(hide yes)
			(effects
				(font
					(size 1 1)
					(thickness 0.15)
				)
				(justify mirror)
			)
		)
		(property "MPN" "GRM155R61H104KE14D"
			(at 331.5 -91.5 0)
			(layer "B.Fab")
			(hide yes)
			(effects
				(font
					(size 1 1)
					(thickness 0.15)
				)
				(justify mirror)
			)
		)
		(property "Manufacturer" "Murata"
			(at 331.5 -91.5 0)
			(layer "B.Fab")
			(hide yes)
			(effects
				(font
					(size 1 1)
					(thickness 0.15)
				)
				(justify mirror)
			)
		)
		(property "Val" "100n"
			(at 331.5 -91.5 0)
			(layer "B.Fab")
			(hide yes)
			(effects
				(font
					(size 1 1)
					(thickness 0.15)
				)
				(justify mirror)
			)
		)
		(property "Voltage" "50V"
			(at 331.5 -91.5 0)
			(layer "B.Fab")
			(hide yes)
			(effects
				(font
					(size 1 1)
					(thickness 0.15)
				)
				(justify mirror)
			)
		)
		(sheetname "FPGA Bank 16 & 17")
		(sheetfile "fpga-bank-16-17.kicad_sch")
		(attr smd)
		(fp_rect
			(start -0.925 0.47)
			(end 0.925 -0.47)
			(stroke
				(width 0.05)
				(type default)
			)
			(fill no)
			(layer "B.CrtYd")
		)
		(fp_line
			(start 0.504 -0.248)
			(end -0.494 -0.248)
			(stroke
				(width 0.15)
				(type solid)
			)
			(layer "B.Fab")
		)
		(fp_line
			(start -0.494 -0.248)
			(end -0.494 0.25)
			(stroke
				(width 0.15)
				(type solid)
			)
			(layer "B.Fab")
		)
		(fp_line
			(start 0.504 0.25)
			(end 0.504 -0.248)
			(stroke
				(width 0.15)
				(type solid)
			)
			(layer "B.Fab")
		)
		(fp_line
			(start -0.494 0.25)
			(end 0.504 0.25)
			(stroke
				(width 0.15)
				(type solid)
			)
			(layer "B.Fab")
		)
		(pad "1" smd roundrect
			(at -0.48 0 90)
			(size 0.59 0.64)
			(layers "B.Cu" "B.Mask" "B.Paste")
			(roundrect_rratio 0.25)
			(net 1 "GND")
			(pintype "passive")
		)
		(pad "2" smd roundrect
			(at 0.48 0 90)
			(size 0.59 0.64)
			(layers "B.Cu" "B.Mask" "B.Paste")
			(roundrect_rratio 0.25)
			(net 3 "VCC_USR_B")
			(pintype "passive")
		)
	)
	(footprint "antmicro-footprints:R_0402_1005Metric"
		(layer "B.Cu")
		(at 202.101 74.233 90)
		(descr "Resistor SMD 0402")
		(tags "resistor SMD 0402")
		(property "Reference" "R4"
			(at -0.742 0.374 270)
			(layer "B.SilkS")
			(effects
				(font
					(size 0.7 0.7)
					(thickness 0.15)
				)
				(justify left bottom mirror)
			)
		)
		(property "Value" "R_10k_0402"
			(at 0 -1.4 270)
			(layer "B.Fab")
			(effects
				(font
					(size 0.7 0.7)
					(thickness 0.15)
				)
				(justify left bottom mirror)
			)
		)
		(property "Description" "SMD Chip Resistor, 10 kohm, ± 1%, 62.5 mW, 0402 [1005 Metric], Thick Film, General Purpose"
			(at 0 0 90)
			(layer "F.Fab")
			(hide yes)
			(effects
				(font
					(size 1.27 1.27)
					(thickness 0.15)
				)
			)
		)
		(property "Author" "Antmicro"
			(at 276.334 -127.868 0)
			(layer "B.Fab")
			(hide yes)
			(effects
				(font
					(size 1 1)
					(thickness 0.15)
				)
				(justify mirror)
			)
		)
		(property "DNP" "DNP"
			(at 276.334 -127.868 0)
			(layer "B.Fab")
			(hide yes)
			(effects
				(font
					(size 1 1)
					(thickness 0.15)
				)
				(justify mirror)
			)
		)
		(property "License" "Apache-2.0"
			(at 276.334 -127.868 0)
			(layer "B.Fab")
			(hide yes)
			(effects
				(font
					(size 1 1)
					(thickness 0.15)
				)
				(justify mirror)
			)
		)
		(property "MPN" "CR0402-FX-1002GLF"
			(at 276.334 -127.868 0)
			(layer "B.Fab")
			(hide yes)
			(effects
				(font
					(size 1 1)
					(thickness 0.15)
				)
				(justify mirror)
			)
		)
		(property "Manufacturer" "Bourns"
			(at 276.334 -127.868 0)
			(layer "B.Fab")
			(hide yes)
			(effects
				(font
					(size 1 1)
					(thickness 0.15)
				)
				(justify mirror)
			)
		)
		(property "Tolerance" "1%"
			(at 276.334 -127.868 0)
			(layer "B.Fab")
			(hide yes)
			(effects
				(font
					(size 1 1)
					(thickness 0.15)
				)
				(justify mirror)
			)
		)
		(property "Val" "10k"
			(at 276.334 -127.868 0)
			(layer "B.Fab")
			(hide yes)
			(effects
				(font
					(size 1 1)
					(thickness 0.15)
				)
				(justify mirror)
			)
		)
		(property "dnp" ""
			(at 276.334 -127.868 0)
			(layer "B.Fab")
			(hide yes)
			(effects
				(font
					(size 1 1)
					(thickness 0.15)
				)
				(justify mirror)
			)
		)
		(property "exclude_from_bom" ""
			(at 276.334 -127.868 0)
			(layer "B.Fab")
			(hide yes)
			(effects
				(font
					(size 1 1)
					(thickness 0.15)
				)
				(justify mirror)
			)
		)
		(sheetname "FPGA Config")
		(sheetfile "fpga-config.kicad_sch")
		(attr smd exclude_from_bom)
		(fp_rect
			(start -0.925 0.47)
			(end 0.925 -0.47)
			(stroke
				(width 0.05)
				(type default)
			)
			(fill no)
			(layer "B.CrtYd")
		)
		(fp_rect
			(start -0.5 0.25)
			(end 0.5 -0.25)
			(stroke
				(width 0.15)
				(type solid)
			)
			(fill no)
			(layer "B.Fab")
		)
		(pad "1" smd roundrect
			(at -0.48 0 90)
			(size 0.59 0.64)
			(layers "B.Cu" "B.Mask" "B.Paste")
			(roundrect_rratio 0.25)
			(net 300 "/FPGA Config/MODE0")
			(pintype "passive")
		)
		(pad "2" smd roundrect
			(at 0.48 0 90)
			(size 0.59 0.64)
			(layers "B.Cu" "B.Mask" "B.Paste")
			(roundrect_rratio 0.25)
			(net 24 "+3V3")
			(pintype "passive")
		)
	)
	(footprint "antmicro-footprints:R_0402_1005Metric"
		(layer "B.Cu")
		(at 265.901 146.85)
		(descr "Resistor SMD 0402")
		(tags "resistor SMD 0402")
		(property "Reference" "R59"
			(at -3.851 0.325 180)
			(layer "B.SilkS")
			(effects
				(font
					(size 0.7 0.7)
					(thickness 0.15)
				)
				(justify left bottom mirror)
			)
		)
		(property "Value" "R_1k_0402"
			(at 0 -1.4 180)
			(layer "B.Fab")
			(effects
				(font
					(size 0.7 0.7)
					(thickness 0.15)
				)
				(justify left bottom mirror)
			)
		)
		(property "Description" "SMD Chip Resistor, 1 kohm, ± 1%, 63 mW, 0402 [1005 Metric], Thick Film, General Purpose"
			(at 0 0 0)
			(layer "F.Fab")
			(hide yes)
			(effects
				(font
					(size 1.27 1.27)
					(thickness 0.15)
				)
			)
		)
		(property "Author" "Antmicro"
			(at 0 0 0)
			(layer "B.Fab")
			(hide yes)
			(effects
				(font
					(size 1 1)
					(thickness 0.15)
				)
				(justify mirror)
			)
		)
		(property "License" "Apache-2.0"
			(at 0 0 0)
			(layer "B.Fab")
			(hide yes)
			(effects
				(font
					(size 1 1)
					(thickness 0.15)
				)
				(justify mirror)
			)
		)
		(property "MPN" "CR0402-FX-1001GLF"
			(at 0 0 0)
			(layer "B.Fab")
			(hide yes)
			(effects
				(font
					(size 1 1)
					(thickness 0.15)
				)
				(justify mirror)
			)
		)
		(property "Manufacturer" "Bourns"
			(at 0 0 0)
			(layer "B.Fab")
			(hide yes)
			(effects
				(font
					(size 1 1)
					(thickness 0.15)
				)
				(justify mirror)
			)
		)
		(property "Tolerance" "1%"
			(at 0 0 0)
			(layer "B.Fab")
			(hide yes)
			(effects
				(font
					(size 1 1)
					(thickness 0.15)
				)
				(justify mirror)
			)
		)
		(property "Val" "1k"
			(at 0 0 0)
			(layer "B.Fab")
			(hide yes)
			(effects
				(font
					(size 1 1)
					(thickness 0.15)
				)
				(justify mirror)
			)
		)
		(sheetname "Power supply")
		(sheetfile "power-supply.kicad_sch")
		(attr smd)
		(fp_rect
			(start -0.925 0.47)
			(end 0.925 -0.47)
			(stroke
				(width 0.05)
				(type default)
			)
			(fill no)
			(layer "B.CrtYd")
		)
		(fp_rect
			(start -0.5 0.25)
			(end 0.5 -0.25)
			(stroke
				(width 0.15)
				(type solid)
			)
			(fill no)
			(layer "B.Fab")
		)
		(pad "1" smd roundrect
			(at -0.48 0)
			(size 0.59 0.64)
			(layers "B.Cu" "B.Mask" "B.Paste")
			(roundrect_rratio 0.25)
			(net 24 "+3V3")
			(pintype "passive")
		)
		(pad "2" smd roundrect
			(at 0.48 0)
			(size 0.59 0.64)
			(layers "B.Cu" "B.Mask" "B.Paste")
			(roundrect_rratio 0.25)
			(net 755 "Net-(D12-A)")
			(pintype "passive")
		)
	)
	(footprint "antmicro-footprints:C_0402_1005Metric"
		(layer "B.Cu")
		(at 194.5 122 90)
		(descr "Capacitor SMD 0402")
		(tags "capacitor SMD 0402")
		(property "Reference" "C76"
			(at 31.125 23.5 270)
			(layer "B.SilkS")
			(effects
				(font
					(size 0.7 0.7)
					(thickness 0.15)
				)
				(justify left bottom mirror)
			)
		)
		(property "Value" "C_100n_0402"
			(at 0 -1.169 270)
			(layer "B.Fab")
			(effects
				(font
					(size 0.7 0.7)
					(thickness 0.15)
				)
				(justify left bottom mirror)
			)
		)
		(property "Description" "SMD Multilayer Ceramic Capacitor, 0.1 µF, 50 V, 0402 [1005 Metric], ± 10%, X5R, GRM Series"
			(at 0 0 90)
			(layer "F.Fab")
			(hide yes)
			(effects
				(font
					(size 1.27 1.27)
					(thickness 0.15)
				)
			)
		)
		(property "Author" "Antmicro"
			(at 316.5 -72.5 0)
			(layer "B.Fab")
			(hide yes)
			(effects
				(font
					(size 1 1)
					(thickness 0.15)
				)
				(justify mirror)
			)
		)
		(property "Dielectric" "X5R"
			(at 316.5 -72.5 0)
			(layer "B.Fab")
			(hide yes)
			(effects
				(font
					(size 1 1)
					(thickness 0.15)
				)
				(justify mirror)
			)
		)
		(property "License" "Apache-2.0"
			(at 316.5 -72.5 0)
			(layer "B.Fab")
			(hide yes)
			(effects
				(font
					(size 1 1)
					(thickness 0.15)
				)
				(justify mirror)
			)
		)
		(property "MPN" "GRM155R61H104KE14D"
			(at 316.5 -72.5 0)
			(layer "B.Fab")
			(hide yes)
			(effects
				(font
					(size 1 1)
					(thickness 0.15)
				)
				(justify mirror)
			)
		)
		(property "Manufacturer" "Murata"
			(at 316.5 -72.5 0)
			(layer "B.Fab")
			(hide yes)
			(effects
				(font
					(size 1 1)
					(thickness 0.15)
				)
				(justify mirror)
			)
		)
		(property "Val" "100n"
			(at 316.5 -72.5 0)
			(layer "B.Fab")
			(hide yes)
			(effects
				(font
					(size 1 1)
					(thickness 0.15)
				)
				(justify mirror)
			)
		)
		(property "Voltage" "50V"
			(at 316.5 -72.5 0)
			(layer "B.Fab")
			(hide yes)
			(effects
				(font
					(size 1 1)
					(thickness 0.15)
				)
				(justify mirror)
			)
		)
		(sheetname "FPGA Bank 18 & 32")
		(sheetfile "fpga-bank-18-32.kicad_sch")
		(attr smd)
		(fp_rect
			(start -0.925 0.47)
			(end 0.925 -0.47)
			(stroke
				(width 0.05)
				(type default)
			)
			(fill no)
			(layer "B.CrtYd")
		)
		(fp_line
			(start 0.504 -0.248)
			(end -0.494 -0.248)
			(stroke
				(width 0.15)
				(type solid)
			)
			(layer "B.Fab")
		)
		(fp_line
			(start -0.494 -0.248)
			(end -0.494 0.25)
			(stroke
				(width 0.15)
				(type solid)
			)
			(layer "B.Fab")
		)
		(fp_line
			(start 0.504 0.25)
			(end 0.504 -0.248)
			(stroke
				(width 0.15)
				(type solid)
			)
			(layer "B.Fab")
		)
		(fp_line
			(start -0.494 0.25)
			(end 0.504 0.25)
			(stroke
				(width 0.15)
				(type solid)
			)
			(layer "B.Fab")
		)
		(pad "1" smd roundrect
			(at -0.48 0 90)
			(size 0.59 0.64)
			(layers "B.Cu" "B.Mask" "B.Paste")
			(roundrect_rratio 0.25)
			(net 1 "GND")
			(pintype "passive")
		)
		(pad "2" smd roundrect
			(at 0.48 0 90)
			(size 0.59 0.64)
			(layers "B.Cu" "B.Mask" "B.Paste")
			(roundrect_rratio 0.25)
			(net 24 "+3V3")
			(pintype "passive")
		)
	)
	(footprint "antmicro-footprints:R_0402_1005Metric"
		(layer "B.Cu")
		(at 245.001 130.1 90)
		(descr "Resistor SMD 0402")
		(tags "resistor SMD 0402")
		(property "Reference" "R89"
			(at -0.8 0.374 270)
			(layer "B.SilkS")
			(effects
				(font
					(size 0.7 0.7)
					(thickness 0.15)
				)
				(justify left bottom mirror)
			)
		)
		(property "Value" "R_10k_0402"
			(at 0 -1.4 270)
			(layer "B.Fab")
			(effects
				(font
					(size 0.7 0.7)
					(thickness 0.15)
				)
				(justify left bottom mirror)
			)
		)
		(property "Description" "SMD Chip Resistor, 10 kohm, ± 1%, 62.5 mW, 0402 [1005 Metric], Thick Film, General Purpose"
			(at 0 0 90)
			(layer "F.Fab")
			(hide yes)
			(effects
				(font
					(size 1.27 1.27)
					(thickness 0.15)
				)
			)
		)
		(property "Author" "Antmicro"
			(at 375.101 -114.901 0)
			(layer "B.Fab")
			(hide yes)
			(effects
				(font
					(size 1 1)
					(thickness 0.15)
				)
				(justify mirror)
			)
		)
		(property "License" "Apache-2.0"
			(at 375.101 -114.901 0)
			(layer "B.Fab")
			(hide yes)
			(effects
				(font
					(size 1 1)
					(thickness 0.15)
				)
				(justify mirror)
			)
		)
		(property "MPN" "CR0402-FX-1002GLF"
			(at 375.101 -114.901 0)
			(layer "B.Fab")
			(hide yes)
			(effects
				(font
					(size 1 1)
					(thickness 0.15)
				)
				(justify mirror)
			)
		)
		(property "Manufacturer" "Bourns"
			(at 375.101 -114.901 0)
			(layer "B.Fab")
			(hide yes)
			(effects
				(font
					(size 1 1)
					(thickness 0.15)
				)
				(justify mirror)
			)
		)
		(property "Tolerance" "1%"
			(at 375.101 -114.901 0)
			(layer "B.Fab")
			(hide yes)
			(effects
				(font
					(size 1 1)
					(thickness 0.15)
				)
				(justify mirror)
			)
		)
		(property "Val" "10k"
			(at 375.101 -114.901 0)
			(layer "B.Fab")
			(hide yes)
			(effects
				(font
					(size 1 1)
					(thickness 0.15)
				)
				(justify mirror)
			)
		)
		(sheetname "SPI Flash + SD Card")
		(sheetfile "spi-flash.kicad_sch")
		(attr smd)
		(fp_rect
			(start -0.925 0.47)
			(end 0.925 -0.47)
			(stroke
				(width 0.05)
				(type default)
			)
			(fill no)
			(layer "B.CrtYd")
		)
		(fp_rect
			(start -0.5 0.25)
			(end 0.5 -0.25)
			(stroke
				(width 0.15)
				(type solid)
			)
			(fill no)
			(layer "B.Fab")
		)
		(pad "1" smd roundrect
			(at -0.48 0 90)
			(size 0.59 0.64)
			(layers "B.Cu" "B.Mask" "B.Paste")
			(roundrect_rratio 0.25)
			(net 394 "/FPGA Bank 33 & 34/SD_CARD.CLK")
			(pintype "passive")
		)
		(pad "2" smd roundrect
			(at 0.48 0 90)
			(size 0.59 0.64)
			(layers "B.Cu" "B.Mask" "B.Paste")
			(roundrect_rratio 0.25)
			(net 24 "+3V3")
			(pintype "passive")
		)
	)
	(footprint "antmicro-footprints:C_0201"
		(layer "B.Cu")
		(at 201.5 127.25 180)
		(descr "Capacitor SMD 0201")
		(tags "capacitor SMD 0201")
		(property "Reference" "C74"
			(at -26.925 29.35 0)
			(layer "B.SilkS")
			(effects
				(font
					(size 0.7 0.7)
					(thickness 0.15)
				)
				(justify left bottom mirror)
			)
		)
		(property "Value" "C_100n_0201"
			(at 0 -1.4 0)
			(layer "B.Fab")
			(effects
				(font
					(size 0.7 0.7)
					(thickness 0.15)
				)
				(justify left bottom mirror)
			)
		)
		(property "Description" "SMD Multilayer Ceramic Capacitor, 0.1 µF, 6.3 V, 0201 [0603 Metric], ± 10%, X6S, CC Series"
			(at 0 0 180)
			(layer "F.Fab")
			(hide yes)
			(effects
				(font
					(size 1.27 1.27)
					(thickness 0.15)
				)
			)
		)
		(property "Author" "Antmicro"
			(at 403 254.5 0)
			(layer "B.Fab")
			(hide yes)
			(effects
				(font
					(size 1 1)
					(thickness 0.15)
				)
				(justify mirror)
			)
		)
		(property "Dielectric" ""
			(at 403 254.5 0)
			(layer "B.Fab")
			(hide yes)
			(effects
				(font
					(size 1 1)
					(thickness 0.15)
				)
				(justify mirror)
			)
		)
		(property "License" "Apache-2.0"
			(at 403 254.5 0)
			(layer "B.Fab")
			(hide yes)
			(effects
				(font
					(size 1 1)
					(thickness 0.15)
				)
				(justify mirror)
			)
		)
		(property "MPN" "CC0201KRX6S5BB104"
			(at 403 254.5 0)
			(layer "B.Fab")
			(hide yes)
			(effects
				(font
					(size 1 1)
					(thickness 0.15)
				)
				(justify mirror)
			)
		)
		(property "Manufacturer" "YAGEO"
			(at 403 254.5 0)
			(layer "B.Fab")
			(hide yes)
			(effects
				(font
					(size 1 1)
					(thickness 0.15)
				)
				(justify mirror)
			)
		)
		(property "Val" "100n"
			(at 403 254.5 0)
			(layer "B.Fab")
			(hide yes)
			(effects
				(font
					(size 1 1)
					(thickness 0.15)
				)
				(justify mirror)
			)
		)
		(property "Voltage" ""
			(at 403 254.5 0)
			(layer "B.Fab")
			(hide yes)
			(effects
				(font
					(size 1 1)
					(thickness 0.15)
				)
				(justify mirror)
			)
		)
		(sheetname "FPGA supply")
		(sheetfile "fpga-supply.kicad_sch")
		(attr smd)
		(fp_rect
			(start -0.7 0.35)
			(end 0.7 -0.35)
			(stroke
				(width 0.05)
				(type default)
			)
			(fill no)
			(layer "B.CrtYd")
		)
		(fp_rect
			(start 0.3 -0.15)
			(end -0.301 0.149)
			(stroke
				(width 0.15)
				(type solid)
			)
			(fill no)
			(layer "B.Fab")
		)
		(pad "" smd roundrect
			(at -0.349 0.002 180)
			(size 0.318 0.36)
			(layers "B.Paste")
			(roundrect_rratio 0.25)
		)
		(pad "" smd roundrect
			(at 0.341 0.002 180)
			(size 0.318 0.36)
			(layers "B.Paste")
			(roundrect_rratio 0.25)
		)
		(pad "1" smd roundrect
			(at -0.321 0.002 180)
			(size 0.46 0.4)
			(layers "B.Cu" "B.Mask")
			(roundrect_rratio 0.25)
			(net 1 "GND")
			(pintype "passive")
		)
		(pad "2" smd roundrect
			(at 0.32 0.002 180)
			(size 0.46 0.4)
			(layers "B.Cu" "B.Mask")
			(roundrect_rratio 0.25)
			(net 650 "+1V0")
			(pintype "passive")
		)
	)
	(footprint "antmicro-footprints:C_0201"
		(layer "B.Cu")
		(at 202.65 128.5 -90)
		(descr "Capacitor SMD 0201")
		(tags "capacitor SMD 0201")
		(property "Reference" "C137"
			(at -30.475 -26.975 90)
			(layer "B.SilkS")
			(effects
				(font
					(size 0.7 0.7)
					(thickness 0.15)
				)
				(justify left bottom mirror)
			)
		)
		(property "Value" "C_100n_0201"
			(at 0 -1.4 90)
			(layer "B.Fab")
			(effects
				(font
					(size 0.7 0.7)
					(thickness 0.15)
				)
				(justify left bottom mirror)
			)
		)
		(property "Description" "SMD Multilayer Ceramic Capacitor, 0.1 µF, 6.3 V, 0201 [0603 Metric], ± 10%, X6S, CC Series"
			(at 0 0 270)
			(layer "F.Fab")
			(hide yes)
			(effects
				(font
					(size 1.27 1.27)
					(thickness 0.15)
				)
			)
		)
		(property "Author" "Antmicro"
			(at 74.15 331.15 0)
			(layer "B.Fab")
			(hide yes)
			(effects
				(font
					(size 1 1)
					(thickness 0.15)
				)
				(justify mirror)
			)
		)
		(property "Dielectric" ""
			(at 74.15 331.15 0)
			(layer "B.Fab")
			(hide yes)
			(effects
				(font
					(size 1 1)
					(thickness 0.15)
				)
				(justify mirror)
			)
		)
		(property "License" "Apache-2.0"
			(at 74.15 331.15 0)
			(layer "B.Fab")
			(hide yes)
			(effects
				(font
					(size 1 1)
					(thickness 0.15)
				)
				(justify mirror)
			)
		)
		(property "MPN" "CC0201KRX6S5BB104"
			(at 74.15 331.15 0)
			(layer "B.Fab")
			(hide yes)
			(effects
				(font
					(size 1 1)
					(thickness 0.15)
				)
				(justify mirror)
			)
		)
		(property "Manufacturer" "YAGEO"
			(at 74.15 331.15 0)
			(layer "B.Fab")
			(hide yes)
			(effects
				(font
					(size 1 1)
					(thickness 0.15)
				)
				(justify mirror)
			)
		)
		(property "Val" "100n"
			(at 74.15 331.15 0)
			(layer "B.Fab")
			(hide yes)
			(effects
				(font
					(size 1 1)
					(thickness 0.15)
				)
				(justify mirror)
			)
		)
		(property "Voltage" ""
			(at 74.15 331.15 0)
			(layer "B.Fab")
			(hide yes)
			(effects
				(font
					(size 1 1)
					(thickness 0.15)
				)
				(justify mirror)
			)
		)
		(sheetname "FPGA supply")
		(sheetfile "fpga-supply.kicad_sch")
		(attr smd)
		(fp_rect
			(start -0.7 0.35)
			(end 0.7 -0.35)
			(stroke
				(width 0.05)
				(type default)
			)
			(fill no)
			(layer "B.CrtYd")
		)
		(fp_rect
			(start 0.3 -0.15)
			(end -0.301 0.149)
			(stroke
				(width 0.15)
				(type solid)
			)
			(fill no)
			(layer "B.Fab")
		)
		(pad "" smd roundrect
			(at -0.349 0.002 270)
			(size 0.318 0.36)
			(layers "B.Paste")
			(roundrect_rratio 0.25)
		)
		(pad "" smd roundrect
			(at 0.341 0.002 270)
			(size 0.318 0.36)
			(layers "B.Paste")
			(roundrect_rratio 0.25)
		)
		(pad "1" smd roundrect
			(at -0.321 0.002 270)
			(size 0.46 0.4)
			(layers "B.Cu" "B.Mask")
			(roundrect_rratio 0.25)
			(net 1 "GND")
			(pintype "passive")
		)
		(pad "2" smd roundrect
			(at 0.32 0.002 270)
			(size 0.46 0.4)
			(layers "B.Cu" "B.Mask")
			(roundrect_rratio 0.25)
			(net 650 "+1V0")
			(pintype "passive")
		)
	)
	(footprint "antmicro-footprints:C_0201"
		(layer "B.Cu")
		(at 188.000001 124.500001 180)
		(descr "Capacitor SMD 0201")
		(tags "capacitor SMD 0201")
		(property "Reference" "C158"
			(at 0.700001 -0.349999 0)
			(layer "B.SilkS")
			(effects
				(font
					(size 0.7 0.7)
					(thickness 0.15)
				)
				(justify left bottom mirror)
			)
		)
		(property "Value" "C_100n_0201"
			(at 0 -1.4 0)
			(layer "B.Fab")
			(effects
				(font
					(size 0.7 0.7)
					(thickness 0.15)
				)
				(justify left bottom mirror)
			)
		)
		(property "Description" "SMD Multilayer Ceramic Capacitor, 0.1 µF, 6.3 V, 0201 [0603 Metric], ± 10%, X6S, CC Series"
			(at 0 0 180)
			(layer "F.Fab")
			(hide yes)
			(effects
				(font
					(size 1.27 1.27)
					(thickness 0.15)
				)
			)
		)
		(property "Author" "Antmicro"
			(at 376.000002 249.000002 0)
			(layer "B.Fab")
			(hide yes)
			(effects
				(font
					(size 1 1)
					(thickness 0.15)
				)
				(justify mirror)
			)
		)
		(property "Dielectric" ""
			(at 376.000002 249.000002 0)
			(layer "B.Fab")
			(hide yes)
			(effects
				(font
					(size 1 1)
					(thickness 0.15)
				)
				(justify mirror)
			)
		)
		(property "License" "Apache-2.0"
			(at 376.000002 249.000002 0)
			(layer "B.Fab")
			(hide yes)
			(effects
				(font
					(size 1 1)
					(thickness 0.15)
				)
				(justify mirror)
			)
		)
		(property "MPN" "CC0201KRX6S5BB104"
			(at 376.000002 249.000002 0)
			(layer "B.Fab")
			(hide yes)
			(effects
				(font
					(size 1 1)
					(thickness 0.15)
				)
				(justify mirror)
			)
		)
		(property "Manufacturer" "YAGEO"
			(at 376.000002 249.000002 0)
			(layer "B.Fab")
			(hide yes)
			(effects
				(font
					(size 1 1)
					(thickness 0.15)
				)
				(justify mirror)
			)
		)
		(property "Val" "100n"
			(at 376.000002 249.000002 0)
			(layer "B.Fab")
			(hide yes)
			(effects
				(font
					(size 1 1)
					(thickness 0.15)
				)
				(justify mirror)
			)
		)
		(property "Voltage" ""
			(at 376.000002 249.000002 0)
			(layer "B.Fab")
			(hide yes)
			(effects
				(font
					(size 1 1)
					(thickness 0.15)
				)
				(justify mirror)
			)
		)
		(sheetname "FPGA supply")
		(sheetfile "fpga-supply.kicad_sch")
		(attr smd)
		(fp_rect
			(start -0.7 0.35)
			(end 0.7 -0.35)
			(stroke
				(width 0.05)
				(type default)
			)
			(fill no)
			(layer "B.CrtYd")
		)
		(fp_rect
			(start 0.3 -0.15)
			(end -0.301 0.149)
			(stroke
				(width 0.15)
				(type solid)
			)
			(fill no)
			(layer "B.Fab")
		)
		(pad "" smd roundrect
			(at -0.349 0.002 180)
			(size 0.318 0.36)
			(layers "B.Paste")
			(roundrect_rratio 0.25)
		)
		(pad "" smd roundrect
			(at 0.341 0.002 180)
			(size 0.318 0.36)
			(layers "B.Paste")
			(roundrect_rratio 0.25)
		)
		(pad "1" smd roundrect
			(at -0.321 0.002 180)
			(size 0.46 0.4)
			(layers "B.Cu" "B.Mask")
			(roundrect_rratio 0.25)
			(net 1 "GND")
			(pintype "passive")
		)
		(pad "2" smd roundrect
			(at 0.32 0.002 180)
			(size 0.46 0.4)
			(layers "B.Cu" "B.Mask")
			(roundrect_rratio 0.25)
			(net 8 "+1V2_MGTAVTT")
			(pintype "passive")
		)
	)
	(footprint "antmicro-footprints:R_0402_1005Metric"
		(layer "B.Cu")
		(at 258.4 95.8 -90)
		(descr "Resistor SMD 0402")
		(tags "resistor SMD 0402")
		(property "Reference" "R358"
			(at -1.225 0.475 90)
			(layer "B.SilkS")
			(effects
				(font
					(size 0.7 0.7)
					(thickness 0.15)
				)
				(justify left bottom mirror)
			)
		)
		(property "Value" "R_100k_0402"
			(at 0 -1.4 90)
			(layer "B.Fab")
			(effects
				(font
					(size 0.7 0.7)
					(thickness 0.15)
				)
				(justify left bottom mirror)
			)
		)
		(property "Description" "SMD Chip Resistor, 100 kohm, ± 1%, 62.5 mW, 0402 [1005 Metric], Thick Film, General Purpose"
			(at 0 0 270)
			(layer "F.Fab")
			(hide yes)
			(effects
				(font
					(size 1.27 1.27)
					(thickness 0.15)
				)
			)
		)
		(property "Author" "Antmicro"
			(at 162.6 354.2 0)
			(layer "B.Fab")
			(hide yes)
			(effects
				(font
					(size 1 1)
					(thickness 0.15)
				)
				(justify mirror)
			)
		)
		(property "License" "Apache-2.0"
			(at 162.6 354.2 0)
			(layer "B.Fab")
			(hide yes)
			(effects
				(font
					(size 1 1)
					(thickness 0.15)
				)
				(justify mirror)
			)
		)
		(property "MPN" "CR0402-FX-1003GLF"
			(at 162.6 354.2 0)
			(layer "B.Fab")
			(hide yes)
			(effects
				(font
					(size 1 1)
					(thickness 0.15)
				)
				(justify mirror)
			)
		)
		(property "Manufacturer" "Bourns"
			(at 162.6 354.2 0)
			(layer "B.Fab")
			(hide yes)
			(effects
				(font
					(size 1 1)
					(thickness 0.15)
				)
				(justify mirror)
			)
		)
		(property "Tolerance" "1%"
			(at 162.6 354.2 0)
			(layer "B.Fab")
			(hide yes)
			(effects
				(font
					(size 1 1)
					(thickness 0.15)
				)
				(justify mirror)
			)
		)
		(property "Val" "100k"
			(at 162.6 354.2 0)
			(layer "B.Fab")
			(hide yes)
			(effects
				(font
					(size 1 1)
					(thickness 0.15)
				)
				(justify mirror)
			)
		)
		(sheetname "User GPIO + LED + button + DIP switch")
		(sheetfile "user-gpio.kicad_sch")
		(attr smd)
		(fp_rect
			(start -0.925 0.47)
			(end 0.925 -0.47)
			(stroke
				(width 0.05)
				(type default)
			)
			(fill no)
			(layer "B.CrtYd")
		)
		(fp_rect
			(start -0.5 0.25)
			(end 0.5 -0.25)
			(stroke
				(width 0.15)
				(type solid)
			)
			(fill no)
			(layer "B.Fab")
		)
		(pad "1" smd roundrect
			(at -0.48 0 270)
			(size 0.59 0.64)
			(layers "B.Cu" "B.Mask" "B.Paste")
			(roundrect_rratio 0.25)
			(net 1304 "/USER_IO.LED_GREEN5")
			(pintype "passive")
		)
		(pad "2" smd roundrect
			(at 0.48 0 270)
			(size 0.59 0.64)
			(layers "B.Cu" "B.Mask" "B.Paste")
			(roundrect_rratio 0.25)
			(net 1 "GND")
			(pintype "passive")
		)
	)
	(footprint "antmicro-footprints:R_0402_1005Metric"
		(layer "B.Cu")
		(at 198.991252 96.95 90)
		(descr "Resistor SMD 0402")
		(tags "resistor SMD 0402")
		(property "Reference" "R216"
			(at -3.35 0.383748 270)
			(layer "B.SilkS")
			(effects
				(font
					(size 0.7 0.7)
					(thickness 0.15)
				)
				(justify left bottom mirror)
			)
		)
		(property "Value" "R_2k2_0402"
			(at 0 -1.4 270)
			(layer "B.Fab")
			(effects
				(font
					(size 0.7 0.7)
					(thickness 0.15)
				)
				(justify left bottom mirror)
			)
		)
		(property "Description" "SMD Chip Resistor, 2.2 kohm, ± 1%, 62.5 mW, 0402 [1005 Metric], Thick Film, General Purpose"
			(at 0 0 90)
			(layer "F.Fab")
			(hide yes)
			(effects
				(font
					(size 1.27 1.27)
					(thickness 0.15)
				)
			)
		)
		(property "Author" "Antmicro"
			(at 295.941252 -102.041252 0)
			(layer "B.Fab")
			(hide yes)
			(effects
				(font
					(size 1 1)
					(thickness 0.15)
				)
				(justify mirror)
			)
		)
		(property "DNP" "DNP"
			(at 295.941252 -102.041252 0)
			(layer "B.Fab")
			(hide yes)
			(effects
				(font
					(size 1 1)
					(thickness 0.15)
				)
				(justify mirror)
			)
		)
		(property "License" "Apache-2.0"
			(at 295.941252 -102.041252 0)
			(layer "B.Fab")
			(hide yes)
			(effects
				(font
					(size 1 1)
					(thickness 0.15)
				)
				(justify mirror)
			)
		)
		(property "MPN" "CR0402-FX-2201GLF"
			(at 295.941252 -102.041252 0)
			(layer "B.Fab")
			(hide yes)
			(effects
				(font
					(size 1 1)
					(thickness 0.15)
				)
				(justify mirror)
			)
		)
		(property "Manufacturer" "Bourns"
			(at 295.941252 -102.041252 0)
			(layer "B.Fab")
			(hide yes)
			(effects
				(font
					(size 1 1)
					(thickness 0.15)
				)
				(justify mirror)
			)
		)
		(property "Tolerance" "1%"
			(at 295.941252 -102.041252 0)
			(layer "B.Fab")
			(hide yes)
			(effects
				(font
					(size 1 1)
					(thickness 0.15)
				)
				(justify mirror)
			)
		)
		(property "Val" "2k2"
			(at 295.941252 -102.041252 0)
			(layer "B.Fab")
			(hide yes)
			(effects
				(font
					(size 1 1)
					(thickness 0.15)
				)
				(justify mirror)
			)
		)
		(property "dnp" ""
			(at 295.941252 -102.041252 0)
			(layer "B.Fab")
			(hide yes)
			(effects
				(font
					(size 1 1)
					(thickness 0.15)
				)
				(justify mirror)
			)
		)
		(property "exclude_from_bom" ""
			(at 295.941252 -102.041252 0)
			(layer "B.Fab")
			(hide yes)
			(effects
				(font
					(size 1 1)
					(thickness 0.15)
				)
				(justify mirror)
			)
		)
		(sheetname "HDMI + Ethernet")
		(sheetfile "hdmi-ethernet.kicad_sch")
		(attr smd exclude_from_bom)
		(fp_rect
			(start -0.925 0.47)
			(end 0.925 -0.47)
			(stroke
				(width 0.05)
				(type default)
			)
			(fill no)
			(layer "B.CrtYd")
		)
		(fp_rect
			(start -0.5 0.25)
			(end 0.5 -0.25)
			(stroke
				(width 0.15)
				(type solid)
			)
			(fill no)
			(layer "B.Fab")
		)
		(pad "1" smd roundrect
			(at -0.48 0 90)
			(size 0.59 0.64)
			(layers "B.Cu" "B.Mask" "B.Paste")
			(roundrect_rratio 0.25)
			(net 508 "/FPGA Bank 16 & 17/GBE_RGMII.~{INT}")
			(pintype "passive")
		)
		(pad "2" smd roundrect
			(at 0.48 0 90)
			(size 0.59 0.64)
			(layers "B.Cu" "B.Mask" "B.Paste")
			(roundrect_rratio 0.25)
			(net 1 "GND")
			(pintype "passive")
		)
	)
	(footprint "antmicro-footprints:C_0402_1005Metric"
		(layer "B.Cu")
		(at 252.501 161.6 -90)
		(descr "Capacitor SMD 0402")
		(tags "capacitor SMD 0402")
		(property "Reference" "C276"
			(at -1.375 -5.924 90)
			(layer "B.SilkS")
			(effects
				(font
					(size 0.7 0.7)
					(thickness 0.15)
				)
				(justify left bottom mirror)
			)
		)
		(property "Value" "C_10p_0402"
			(at 0 -1.4 90)
			(layer "B.Fab")
			(effects
				(font
					(size 0.7 0.7)
					(thickness 0.15)
				)
				(justify left bottom mirror)
			)
		)
		(property "Description" "SMD Multilayer Ceramic Capacitor, 10 pF, 50 V, 0402 [1005 Metric], ± 2%, C0G / NP0, GCM"
			(at 0 0 270)
			(layer "F.Fab")
			(hide yes)
			(effects
				(font
					(size 1.27 1.27)
					(thickness 0.15)
				)
			)
		)
		(property "Author" "Antmicro"
			(at 90.901 414.101 0)
			(layer "B.Fab")
			(hide yes)
			(effects
				(font
					(size 1 1)
					(thickness 0.15)
				)
				(justify mirror)
			)
		)
		(property "Dielectric" "C0G"
			(at 90.901 414.101 0)
			(layer "B.Fab")
			(hide yes)
			(effects
				(font
					(size 1 1)
					(thickness 0.15)
				)
				(justify mirror)
			)
		)
		(property "License" "Apache-2.0"
			(at 90.901 414.101 0)
			(layer "B.Fab")
			(hide yes)
			(effects
				(font
					(size 1 1)
					(thickness 0.15)
				)
				(justify mirror)
			)
		)
		(property "MPN" "GCM1555C1H100GA16D"
			(at 90.901 414.101 0)
			(layer "B.Fab")
			(hide yes)
			(effects
				(font
					(size 1 1)
					(thickness 0.15)
				)
				(justify mirror)
			)
		)
		(property "Manufacturer" "Murata"
			(at 90.901 414.101 0)
			(layer "B.Fab")
			(hide yes)
			(effects
				(font
					(size 1 1)
					(thickness 0.15)
				)
				(justify mirror)
			)
		)
		(property "Val" "10p"
			(at 90.901 414.101 0)
			(layer "B.Fab")
			(hide yes)
			(effects
				(font
					(size 1 1)
					(thickness 0.15)
				)
				(justify mirror)
			)
		)
		(property "Voltage" "50V"
			(at 90.901 414.101 0)
			(layer "B.Fab")
			(hide yes)
			(effects
				(font
					(size 1 1)
					(thickness 0.15)
				)
				(justify mirror)
			)
		)
		(sheetname "HDMI + Ethernet")
		(sheetfile "hdmi-ethernet.kicad_sch")
		(attr smd)
		(fp_rect
			(start -0.925 0.47)
			(end 0.925 -0.47)
			(stroke
				(width 0.05)
				(type default)
			)
			(fill no)
			(layer "B.CrtYd")
		)
		(fp_line
			(start -0.494 0.25)
			(end 0.504 0.25)
			(stroke
				(width 0.15)
				(type solid)
			)
			(layer "B.Fab")
		)
		(fp_line
			(start 0.504 0.25)
			(end 0.504 -0.248)
			(stroke
				(width 0.15)
				(type solid)
			)
			(layer "B.Fab")
		)
		(fp_line
			(start -0.494 -0.248)
			(end -0.494 0.25)
			(stroke
				(width 0.15)
				(type solid)
			)
			(layer "B.Fab")
		)
		(fp_line
			(start 0.504 -0.248)
			(end -0.494 -0.248)
			(stroke
				(width 0.15)
				(type solid)
			)
			(layer "B.Fab")
		)
		(pad "1" smd roundrect
			(at -0.48 0 270)
			(size 0.59 0.64)
			(layers "B.Cu" "B.Mask" "B.Paste")
			(roundrect_rratio 0.25)
			(net 1 "GND")
			(pintype "passive")
		)
		(pad "2" smd roundrect
			(at 0.48 0 270)
			(size 0.59 0.64)
			(layers "B.Cu" "B.Mask" "B.Paste")
			(roundrect_rratio 0.25)
			(net 726 "/HDMI + Ethernet/ETH2_P")
			(pintype "passive")
		)
	)
	(footprint "antmicro-footprints:R_0402_1005Metric"
		(layer "B.Cu")
		(at 247.401 130.1 90)
		(descr "Resistor SMD 0402")
		(tags "resistor SMD 0402")
		(property "Reference" "R91"
			(at -0.8 0.374 270)
			(layer "B.SilkS")
			(effects
				(font
					(size 0.7 0.7)
					(thickness 0.15)
				)
				(justify left bottom mirror)
			)
		)
		(property "Value" "R_10k_0402"
			(at 0 -1.4 270)
			(layer "B.Fab")
			(effects
				(font
					(size 0.7 0.7)
					(thickness 0.15)
				)
				(justify left bottom mirror)
			)
		)
		(property "Description" "SMD Chip Resistor, 10 kohm, ± 1%, 62.5 mW, 0402 [1005 Metric], Thick Film, General Purpose"
			(at 0 0 90)
			(layer "F.Fab")
			(hide yes)
			(effects
				(font
					(size 1.27 1.27)
					(thickness 0.15)
				)
			)
		)
		(property "Author" "Antmicro"
			(at 377.501 -117.301 0)
			(layer "B.Fab")
			(hide yes)
			(effects
				(font
					(size 1 1)
					(thickness 0.15)
				)
				(justify mirror)
			)
		)
		(property "License" "Apache-2.0"
			(at 377.501 -117.301 0)
			(layer "B.Fab")
			(hide yes)
			(effects
				(font
					(size 1 1)
					(thickness 0.15)
				)
				(justify mirror)
			)
		)
		(property "MPN" "CR0402-FX-1002GLF"
			(at 377.501 -117.301 0)
			(layer "B.Fab")
			(hide yes)
			(effects
				(font
					(size 1 1)
					(thickness 0.15)
				)
				(justify mirror)
			)
		)
		(property "Manufacturer" "Bourns"
			(at 377.501 -117.301 0)
			(layer "B.Fab")
			(hide yes)
			(effects
				(font
					(size 1 1)
					(thickness 0.15)
				)
				(justify mirror)
			)
		)
		(property "Tolerance" "1%"
			(at 377.501 -117.301 0)
			(layer "B.Fab")
			(hide yes)
			(effects
				(font
					(size 1 1)
					(thickness 0.15)
				)
				(justify mirror)
			)
		)
		(property "Val" "10k"
			(at 377.501 -117.301 0)
			(layer "B.Fab")
			(hide yes)
			(effects
				(font
					(size 1 1)
					(thickness 0.15)
				)
				(justify mirror)
			)
		)
		(sheetname "SPI Flash + SD Card")
		(sheetfile "spi-flash.kicad_sch")
		(attr smd)
		(fp_rect
			(start -0.925 0.47)
			(end 0.925 -0.47)
			(stroke
				(width 0.05)
				(type default)
			)
			(fill no)
			(layer "B.CrtYd")
		)
		(fp_rect
			(start -0.5 0.25)
			(end 0.5 -0.25)
			(stroke
				(width 0.15)
				(type solid)
			)
			(fill no)
			(layer "B.Fab")
		)
		(pad "1" smd roundrect
			(at -0.48 0 90)
			(size 0.59 0.64)
			(layers "B.Cu" "B.Mask" "B.Paste")
			(roundrect_rratio 0.25)
			(net 397 "/FPGA Bank 33 & 34/SD_CARD.DAT1")
			(pintype "passive")
		)
		(pad "2" smd roundrect
			(at 0.48 0 90)
			(size 0.59 0.64)
			(layers "B.Cu" "B.Mask" "B.Paste")
			(roundrect_rratio 0.25)
			(net 24 "+3V3")
			(pintype "passive")
		)
	)
	(footprint "antmicro-footprints:C_0402_1005Metric"
		(layer "B.Cu")
		(at 211.5 136 -90)
		(descr "Capacitor SMD 0402")
		(tags "capacitor SMD 0402")
		(property "Reference" "C36"
			(at -1.15 -1.275 90)
			(layer "B.SilkS")
			(effects
				(font
					(size 0.7 0.7)
					(thickness 0.15)
				)
				(justify left bottom mirror)
			)
		)
		(property "Value" "C_100n_0402"
			(at 0 -1.169 90)
			(layer "B.Fab")
			(effects
				(font
					(size 0.7 0.7)
					(thickness 0.15)
				)
				(justify left bottom mirror)
			)
		)
		(property "Description" "SMD Multilayer Ceramic Capacitor, 0.1 µF, 50 V, 0402 [1005 Metric], ± 10%, X5R, GRM Series"
			(at 0 0 270)
			(layer "F.Fab")
			(hide yes)
			(effects
				(font
					(size 1.27 1.27)
					(thickness 0.15)
				)
			)
		)
		(property "Author" "Antmicro"
			(at 75.5 347.5 0)
			(layer "B.Fab")
			(hide yes)
			(effects
				(font
					(size 1 1)
					(thickness 0.15)
				)
				(justify mirror)
			)
		)
		(property "Dielectric" "X5R"
			(at 75.5 347.5 0)
			(layer "B.Fab")
			(hide yes)
			(effects
				(font
					(size 1 1)
					(thickness 0.15)
				)
				(justify mirror)
			)
		)
		(property "License" "Apache-2.0"
			(at 75.5 347.5 0)
			(layer "B.Fab")
			(hide yes)
			(effects
				(font
					(size 1 1)
					(thickness 0.15)
				)
				(justify mirror)
			)
		)
		(property "MPN" "GRM155R61H104KE14D"
			(at 75.5 347.5 0)
			(layer "B.Fab")
			(hide yes)
			(effects
				(font
					(size 1 1)
					(thickness 0.15)
				)
				(justify mirror)
			)
		)
		(property "Manufacturer" "Murata"
			(at 75.5 347.5 0)
			(layer "B.Fab")
			(hide yes)
			(effects
				(font
					(size 1 1)
					(thickness 0.15)
				)
				(justify mirror)
			)
		)
		(property "Val" "100n"
			(at 75.5 347.5 0)
			(layer "B.Fab")
			(hide yes)
			(effects
				(font
					(size 1 1)
					(thickness 0.15)
				)
				(justify mirror)
			)
		)
		(property "Voltage" "50V"
			(at 75.5 347.5 0)
			(layer "B.Fab")
			(hide yes)
			(effects
				(font
					(size 1 1)
					(thickness 0.15)
				)
				(justify mirror)
			)
		)
		(sheetname "FPGA Bank 12 & 13")
		(sheetfile "fpga-bank-12-13.kicad_sch")
		(attr smd)
		(fp_rect
			(start -0.925 0.47)
			(end 0.925 -0.47)
			(stroke
				(width 0.05)
				(type default)
			)
			(fill no)
			(layer "B.CrtYd")
		)
		(fp_line
			(start -0.494 0.25)
			(end 0.504 0.25)
			(stroke
				(width 0.15)
				(type solid)
			)
			(layer "B.Fab")
		)
		(fp_line
			(start 0.504 0.25)
			(end 0.504 -0.248)
			(stroke
				(width 0.15)
				(type solid)
			)
			(layer "B.Fab")
		)
		(fp_line
			(start -0.494 -0.248)
			(end -0.494 0.25)
			(stroke
				(width 0.15)
				(type solid)
			)
			(layer "B.Fab")
		)
		(fp_line
			(start 0.504 -0.248)
			(end -0.494 -0.248)
			(stroke
				(width 0.15)
				(type solid)
			)
			(layer "B.Fab")
		)
		(pad "1" smd roundrect
			(at -0.48 0 270)
			(size 0.59 0.64)
			(layers "B.Cu" "B.Mask" "B.Paste")
			(roundrect_rratio 0.25)
			(net 1 "GND")
			(pintype "passive")
		)
		(pad "2" smd roundrect
			(at 0.48 0 270)
			(size 0.59 0.64)
			(layers "B.Cu" "B.Mask" "B.Paste")
			(roundrect_rratio 0.25)
			(net 24 "+3V3")
			(pintype "passive")
		)
	)
	(footprint "antmicro-footprints:C_1206_3216Metric"
		(layer "B.Cu")
		(at 163.360401 128.826401)
		(descr "Capacitor SMD 1206")
		(tags "capacitor SMD 1206")
		(property "Reference" "C297"
			(at -1.410401 2.023599 0)
			(layer "B.SilkS")
			(effects
				(font
					(size 0.7 0.7)
					(thickness 0.15)
				)
				(justify right bottom mirror)
			)
		)
		(property "Value" "C_47u_16V_1206"
			(at 0 -2.1 0)
			(layer "B.Fab")
			(effects
				(font
					(size 0.7 0.7)
					(thickness 0.15)
				)
				(justify right bottom mirror)
			)
		)
		(property "Description" "SMD Multilayer Ceramic Capacitor, 47 µF, 16 V, 1206 [3216 Metric], ± 20%, X5R, C"
			(at 0 0 0)
			(layer "F.Fab")
			(hide yes)
			(effects
				(font
					(size 1.27 1.27)
					(thickness 0.15)
				)
			)
		)
		(property "Author" "Antmicro"
			(at 0 0 0)
			(layer "B.Fab")
			(hide yes)
			(effects
				(font
					(size 1 1)
					(thickness 0.15)
				)
				(justify mirror)
			)
		)
		(property "Dielectric" "X5R"
			(at 0 0 0)
			(layer "B.Fab")
			(hide yes)
			(effects
				(font
					(size 1 1)
					(thickness 0.15)
				)
				(justify mirror)
			)
		)
		(property "License" "Apache-2.0"
			(at 0 0 0)
			(layer "B.Fab")
			(hide yes)
			(effects
				(font
					(size 1 1)
					(thickness 0.15)
				)
				(justify mirror)
			)
		)
		(property "MPN" "C3216X5R1C476M160AB"
			(at 0 0 0)
			(layer "B.Fab")
			(hide yes)
			(effects
				(font
					(size 1 1)
					(thickness 0.15)
				)
				(justify mirror)
			)
		)
		(property "Manufacturer" "TDK"
			(at 0 0 0)
			(layer "B.Fab")
			(hide yes)
			(effects
				(font
					(size 1 1)
					(thickness 0.15)
				)
				(justify mirror)
			)
		)
		(property "Val" "47u"
			(at 0 0 0)
			(layer "B.Fab")
			(hide yes)
			(effects
				(font
					(size 1 1)
					(thickness 0.15)
				)
				(justify mirror)
			)
		)
		(property "Voltage" "16V"
			(at 0 0 0)
			(layer "B.Fab")
			(hide yes)
			(effects
				(font
					(size 1 1)
					(thickness 0.15)
				)
				(justify mirror)
			)
		)
		(sheetname "FMC+ HSPC")
		(sheetfile "fmc-hspc.kicad_sch")
		(attr smd)
		(fp_line
			(start 0.8 -0.901)
			(end -0.8 -0.901)
			(stroke
				(width 0.15)
				(type solid)
			)
			(layer "B.SilkS")
		)
		(fp_line
			(start 0.8 0.899)
			(end -0.8 0.899)
			(stroke
				(width 0.15)
				(type solid)
			)
			(layer "B.SilkS")
		)
		(fp_rect
			(start -2.325 1.15)
			(end 2.325 -1.15)
			(stroke
				(width 0.05)
				(type default)
			)
			(fill no)
			(layer "B.CrtYd")
		)
		(fp_rect
			(start -1.6 0.799)
			(end 1.6 -0.801)
			(stroke
				(width 0.15)
				(type solid)
			)
			(fill no)
			(layer "B.Fab")
		)
		(pad "1" smd roundrect
			(at -1.5 -0.001)
			(size 1.15 1.8)
			(layers "B.Cu" "B.Mask" "B.Paste")
			(roundrect_rratio 0.25)
			(net 1 "GND")
			(pintype "passive")
		)
		(pad "2" smd roundrect
			(at 1.5 -0.001)
			(size 1.15 1.8)
			(layers "B.Cu" "B.Mask" "B.Paste")
			(roundrect_rratio 0.25)
			(net 59 "12P0V")
			(pintype "passive")
		)
	)
	(footprint "antmicro-footprints:FB_0603_1608Metric"
		(layer "B.Cu")
		(at 249.401 112.6)
		(property "Reference" "FB9"
			(at -1.251 0.35 180)
			(layer "B.SilkS")
			(effects
				(font
					(size 0.7 0.7)
					(thickness 0.15)
				)
				(justify left bottom mirror)
			)
		)
		(property "Value" "FB_120Z_2A_Murata-BLM18PG_0603"
			(at 0 -1.7 180)
			(layer "B.Fab")
			(effects
				(font
					(size 0.7 0.7)
					(thickness 0.15)
				)
				(justify left bottom mirror)
			)
		)
		(property "Description" "Ferrite Bead, 0603 [1608 Metric], 120 ohm, 2 A, BLM18P, 0.05 ohm, ± 25%, DC power line"
			(at 0 0 0)
			(layer "F.Fab")
			(hide yes)
			(effects
				(font
					(size 1.27 1.27)
					(thickness 0.15)
				)
			)
		)
		(property "Author" "Antmicro"
			(at 0 0 0)
			(layer "B.Fab")
			(hide yes)
			(effects
				(font
					(size 1 1)
					(thickness 0.15)
				)
				(justify mirror)
			)
		)
		(property "Current" ""
			(at 0 0 0)
			(layer "B.Fab")
			(hide yes)
			(effects
				(font
					(size 1 1)
					(thickness 0.15)
				)
				(justify mirror)
			)
		)
		(property "License" "Apache-2.0"
			(at 0 0 0)
			(layer "B.Fab")
			(hide yes)
			(effects
				(font
					(size 1 1)
					(thickness 0.15)
				)
				(justify mirror)
			)
		)
		(property "MPN" "BLM18PG121SN1D"
			(at 0 0 0)
			(layer "B.Fab")
			(hide yes)
			(effects
				(font
					(size 1 1)
					(thickness 0.15)
				)
				(justify mirror)
			)
		)
		(property "Manufacturer" "Murata"
			(at 0 0 0)
			(layer "B.Fab")
			(hide yes)
			(effects
				(font
					(size 1 1)
					(thickness 0.15)
				)
				(justify mirror)
			)
		)
		(property "Val" "120Z/2A"
			(at 0 0 0)
			(layer "B.Fab")
			(hide yes)
			(effects
				(font
					(size 1 1)
					(thickness 0.15)
				)
				(justify mirror)
			)
		)
		(sheetname "HDMI + Ethernet")
		(sheetfile "hdmi-ethernet.kicad_sch")
		(attr smd)
		(fp_line
			(start -0.15 -0.4)
			(end 0.15 -0.4)
			(stroke
				(width 0.15)
				(type solid)
			)
			(layer "B.SilkS")
		)
		(fp_line
			(start -0.15 0.4)
			(end 0.15 0.4)
			(stroke
				(width 0.15)
				(type solid)
			)
			(layer "B.SilkS")
		)
		(fp_rect
			(start -1.25 0.65)
			(end 1.25 -0.65)
			(stroke
				(width 0.05)
				(type solid)
			)
			(fill no)
			(layer "B.CrtYd")
		)
		(fp_line
			(start -0.803 -0.406)
			(end -0.803 0.408)
			(stroke
				(width 0.15)
				(type solid)
			)
			(layer "B.Fab")
		)
		(fp_line
			(start 0.8 -0.406)
			(end -0.803 -0.406)
			(stroke
				(width 0.15)
				(type solid)
			)
			(layer "B.Fab")
		)
		(fp_line
			(start 0.8 0.408)
			(end -0.803 0.408)
			(stroke
				(width 0.15)
				(type solid)
			)
			(layer "B.Fab")
		)
		(fp_line
			(start 0.8 0.408)
			(end 0.8 -0.406)
			(stroke
				(width 0.15)
				(type solid)
			)
			(layer "B.Fab")
		)
		(pad "1" smd roundrect
			(at -0.7 0)
			(size 0.8 1)
			(layers "B.Cu" "B.Mask" "B.Paste")
			(roundrect_rratio 0.2)
			(net 703 "+5V")
			(pintype "passive")
		)
		(pad "2" smd roundrect
			(at 0.7 0)
			(size 0.8 1)
			(layers "B.Cu" "B.Mask" "B.Paste")
			(roundrect_rratio 0.2)
			(net 795 "/HDMI + Ethernet/HDMI_5V")
			(pintype "passive")
		)
	)
	(footprint "antmicro-footprints:C_0201"
		(layer "B.Cu")
		(at 201.5 132.85)
		(descr "Capacitor SMD 0201")
		(tags "capacitor SMD 0201")
		(property "Reference" "C139"
			(at 24.4 -28.4 0)
			(layer "B.SilkS")
			(effects
				(font
					(size 0.7 0.7)
					(thickness 0.15)
				)
				(justify right bottom mirror)
			)
		)
		(property "Value" "C_100n_0201"
			(at 0 -1.4 0)
			(layer "B.Fab")
			(effects
				(font
					(size 0.7 0.7)
					(thickness 0.15)
				)
				(justify right bottom mirror)
			)
		)
		(property "Description" "SMD Multilayer Ceramic Capacitor, 0.1 µF, 6.3 V, 0201 [0603 Metric], ± 10%, X6S, CC Series"
			(at 0 0 0)
			(layer "F.Fab")
			(hide yes)
			(effects
				(font
					(size 1.27 1.27)
					(thickness 0.15)
				)
			)
		)
		(property "Author" "Antmicro"
			(at 0 0 0)
			(layer "B.Fab")
			(hide yes)
			(effects
				(font
					(size 1 1)
					(thickness 0.15)
				)
				(justify mirror)
			)
		)
		(property "Dielectric" ""
			(at 0 0 0)
			(layer "B.Fab")
			(hide yes)
			(effects
				(font
					(size 1 1)
					(thickness 0.15)
				)
				(justify mirror)
			)
		)
		(property "License" "Apache-2.0"
			(at 0 0 0)
			(layer "B.Fab")
			(hide yes)
			(effects
				(font
					(size 1 1)
					(thickness 0.15)
				)
				(justify mirror)
			)
		)
		(property "MPN" "CC0201KRX6S5BB104"
			(at 0 0 0)
			(layer "B.Fab")
			(hide yes)
			(effects
				(font
					(size 1 1)
					(thickness 0.15)
				)
				(justify mirror)
			)
		)
		(property "Manufacturer" "YAGEO"
			(at 0 0 0)
			(layer "B.Fab")
			(hide yes)
			(effects
				(font
					(size 1 1)
					(thickness 0.15)
				)
				(justify mirror)
			)
		)
		(property "Val" "100n"
			(at 0 0 0)
			(layer "B.Fab")
			(hide yes)
			(effects
				(font
					(size 1 1)
					(thickness 0.15)
				)
				(justify mirror)
			)
		)
		(property "Voltage" ""
			(at 0 0 0)
			(layer "B.Fab")
			(hide yes)
			(effects
				(font
					(size 1 1)
					(thickness 0.15)
				)
				(justify mirror)
			)
		)
		(sheetname "FPGA supply")
		(sheetfile "fpga-supply.kicad_sch")
		(attr smd)
		(fp_rect
			(start -0.7 0.35)
			(end 0.7 -0.35)
			(stroke
				(width 0.05)
				(type default)
			)
			(fill no)
			(layer "B.CrtYd")
		)
		(fp_rect
			(start 0.3 -0.15)
			(end -0.301 0.149)
			(stroke
				(width 0.15)
				(type solid)
			)
			(fill no)
			(layer "B.Fab")
		)
		(pad "" smd roundrect
			(at -0.349 0.002)
			(size 0.318 0.36)
			(layers "B.Paste")
			(roundrect_rratio 0.25)
		)
		(pad "" smd roundrect
			(at 0.341 0.002)
			(size 0.318 0.36)
			(layers "B.Paste")
			(roundrect_rratio 0.25)
		)
		(pad "1" smd roundrect
			(at -0.321 0.002)
			(size 0.46 0.4)
			(layers "B.Cu" "B.Mask")
			(roundrect_rratio 0.25)
			(net 1 "GND")
			(pintype "passive")
		)
		(pad "2" smd roundrect
			(at 0.32 0.002)
			(size 0.46 0.4)
			(layers "B.Cu" "B.Mask")
			(roundrect_rratio 0.25)
			(net 650 "+1V0")
			(pintype "passive")
		)
	)
	(footprint "antmicro-footprints:C_0402_1005Metric"
		(layer "B.Cu")
		(at 168.049999 148.924999 90)
		(descr "Capacitor SMD 0402")
		(tags "capacitor SMD 0402")
		(property "Reference" "C184"
			(at -0.775001 0.400001 270)
			(layer "B.SilkS")
			(effects
				(font
					(size 0.7 0.7)
					(thickness 0.15)
				)
				(justify left bottom mirror)
			)
		)
		(property "Value" "C_100n_0402"
			(at 0 -1.169 270)
			(layer "B.Fab")
			(effects
				(font
					(size 0.7 0.7)
					(thickness 0.15)
				)
				(justify left bottom mirror)
			)
		)
		(property "Description" "SMD Multilayer Ceramic Capacitor, 0.1 µF, 50 V, 0402 [1005 Metric], ± 10%, X5R, GRM Series"
			(at 0 0 90)
			(layer "F.Fab")
			(hide yes)
			(effects
				(font
					(size 1.27 1.27)
					(thickness 0.15)
				)
			)
		)
		(property "Author" "Antmicro"
			(at 316.974998 -19.125 0)
			(layer "B.Fab")
			(hide yes)
			(effects
				(font
					(size 1 1)
					(thickness 0.15)
				)
				(justify mirror)
			)
		)
		(property "Dielectric" "X5R"
			(at 316.974998 -19.125 0)
			(layer "B.Fab")
			(hide yes)
			(effects
				(font
					(size 1 1)
					(thickness 0.15)
				)
				(justify mirror)
			)
		)
		(property "License" "Apache-2.0"
			(at 316.974998 -19.125 0)
			(layer "B.Fab")
			(hide yes)
			(effects
				(font
					(size 1 1)
					(thickness 0.15)
				)
				(justify mirror)
			)
		)
		(property "MPN" "GRM155R61H104KE14D"
			(at 316.974998 -19.125 0)
			(layer "B.Fab")
			(hide yes)
			(effects
				(font
					(size 1 1)
					(thickness 0.15)
				)
				(justify mirror)
			)
		)
		(property "Manufacturer" "Murata"
			(at 316.974998 -19.125 0)
			(layer "B.Fab")
			(hide yes)
			(effects
				(font
					(size 1 1)
					(thickness 0.15)
				)
				(justify mirror)
			)
		)
		(property "Val" "100n"
			(at 316.974998 -19.125 0)
			(layer "B.Fab")
			(hide yes)
			(effects
				(font
					(size 1 1)
					(thickness 0.15)
				)
				(justify mirror)
			)
		)
		(property "Voltage" "50V"
			(at 316.974998 -19.125 0)
			(layer "B.Fab")
			(hide yes)
			(effects
				(font
					(size 1 1)
					(thickness 0.15)
				)
				(justify mirror)
			)
		)
		(sheetname "DRAM + SRAM")
		(sheetfile "ram.kicad_sch")
		(attr smd)
		(fp_rect
			(start -0.925 0.47)
			(end 0.925 -0.47)
			(stroke
				(width 0.05)
				(type default)
			)
			(fill no)
			(layer "B.CrtYd")
		)
		(fp_line
			(start 0.504 -0.248)
			(end -0.494 -0.248)
			(stroke
				(width 0.15)
				(type solid)
			)
			(layer "B.Fab")
		)
		(fp_line
			(start -0.494 -0.248)
			(end -0.494 0.25)
			(stroke
				(width 0.15)
				(type solid)
			)
			(layer "B.Fab")
		)
		(fp_line
			(start 0.504 0.25)
			(end 0.504 -0.248)
			(stroke
				(width 0.15)
				(type solid)
			)
			(layer "B.Fab")
		)
		(fp_line
			(start -0.494 0.25)
			(end 0.504 0.25)
			(stroke
				(width 0.15)
				(type solid)
			)
			(layer "B.Fab")
		)
		(pad "1" smd roundrect
			(at -0.48 0 90)
			(size 0.59 0.64)
			(layers "B.Cu" "B.Mask" "B.Paste")
			(roundrect_rratio 0.25)
			(net 1 "GND")
			(pintype "passive")
		)
		(pad "2" smd roundrect
			(at 0.48 0 90)
			(size 0.59 0.64)
			(layers "B.Cu" "B.Mask" "B.Paste")
			(roundrect_rratio 0.25)
			(net 11 "+0V675_VREF")
			(pintype "passive")
		)
	)
	(footprint "antmicro-footprints:R_0402_1005Metric"
		(layer "B.Cu")
		(at 156.4625 173.7 -90)
		(descr "Resistor SMD 0402")
		(tags "resistor SMD 0402")
		(property "Reference" "R312"
			(at 0.75 -0.3875 90)
			(layer "B.SilkS")
			(effects
				(font
					(size 0.7 0.7)
					(thickness 0.15)
				)
				(justify left bottom mirror)
			)
		)
		(property "Value" "R_0R_0402"
			(at 0 -1.4 90)
			(layer "B.Fab")
			(effects
				(font
					(size 0.7 0.7)
					(thickness 0.15)
				)
				(justify left bottom mirror)
			)
		)
		(property "Description" "SMD Chip Resistor, Jumper, 0 ohm, 100 mW, 0402 [1005 Metric], Thick Film, General Purpose"
			(at 0 0 270)
			(layer "F.Fab")
			(hide yes)
			(effects
				(font
					(size 1.27 1.27)
					(thickness 0.15)
				)
			)
		)
		(property "Author" "Antmicro"
			(at -17.2375 330.1625 0)
			(layer "B.Fab")
			(hide yes)
			(effects
				(font
					(size 1 1)
					(thickness 0.15)
				)
				(justify mirror)
			)
		)
		(property "Current" "1A"
			(at -17.2375 330.1625 0)
			(layer "B.Fab")
			(hide yes)
			(effects
				(font
					(size 1 1)
					(thickness 0.15)
				)
				(justify mirror)
			)
		)
		(property "DNP" "DNP"
			(at -17.2375 330.1625 0)
			(layer "B.Fab")
			(hide yes)
			(effects
				(font
					(size 1 1)
					(thickness 0.15)
				)
				(justify mirror)
			)
		)
		(property "License" "Apache-2.0"
			(at -17.2375 330.1625 0)
			(layer "B.Fab")
			(hide yes)
			(effects
				(font
					(size 1 1)
					(thickness 0.15)
				)
				(justify mirror)
			)
		)
		(property "MPN" "ERJ2GE0R00X"
			(at -17.2375 330.1625 0)
			(layer "B.Fab")
			(hide yes)
			(effects
				(font
					(size 1 1)
					(thickness 0.15)
				)
				(justify mirror)
			)
		)
		(property "Manufacturer" "Panasonic"
			(at -17.2375 330.1625 0)
			(layer "B.Fab")
			(hide yes)
			(effects
				(font
					(size 1 1)
					(thickness 0.15)
				)
				(justify mirror)
			)
		)
		(property "Tolerance" ""
			(at -17.2375 330.1625 0)
			(layer "B.Fab")
			(hide yes)
			(effects
				(font
					(size 1 1)
					(thickness 0.15)
				)
				(justify mirror)
			)
		)
		(property "Val" "0R"
			(at -17.2375 330.1625 0)
			(layer "B.Fab")
			(hide yes)
			(effects
				(font
					(size 1 1)
					(thickness 0.15)
				)
				(justify mirror)
			)
		)
		(property "dnp" ""
			(at -17.2375 330.1625 0)
			(layer "B.Fab")
			(hide yes)
			(effects
				(font
					(size 1 1)
					(thickness 0.15)
				)
				(justify mirror)
			)
		)
		(property "exclude_from_bom" ""
			(at -17.2375 330.1625 0)
			(layer "B.Fab")
			(hide yes)
			(effects
				(font
					(size 1 1)
					(thickness 0.15)
				)
				(justify mirror)
			)
		)
		(sheetname "DC-DC Converters")
		(sheetfile "dc-dc.kicad_sch")
		(attr smd exclude_from_bom)
		(fp_rect
			(start -0.925 0.47)
			(end 0.925 -0.47)
			(stroke
				(width 0.05)
				(type default)
			)
			(fill no)
			(layer "B.CrtYd")
		)
		(fp_rect
			(start -0.5 0.25)
			(end 0.5 -0.25)
			(stroke
				(width 0.15)
				(type solid)
			)
			(fill no)
			(layer "B.Fab")
		)
		(pad "1" smd roundrect
			(at -0.48 0 270)
			(size 0.59 0.64)
			(layers "B.Cu" "B.Mask" "B.Paste")
			(roundrect_rratio 0.25)
			(net 1 "GND")
			(pintype "passive")
		)
		(pad "2" smd roundrect
			(at 0.48 0 270)
			(size 0.59 0.64)
			(layers "B.Cu" "B.Mask" "B.Paste")
			(roundrect_rratio 0.25)
			(net 963 "/DC-DC Converters/FB4")
			(pintype "passive")
		)
	)
	(footprint "antmicro-footprints:C_0603_1608Metric"
		(layer "B.Cu")
		(at 210.25 130 180)
		(descr "Capacitor SMD 0603")
		(tags "capacitor 0603")
		(property "Reference" "C5"
			(at -1.175 -1.375 0)
			(layer "B.SilkS")
			(effects
				(font
					(size 0.7 0.7)
					(thickness 0.15)
				)
				(justify left bottom mirror)
			)
		)
		(property "Value" "C_47u_0603"
			(at 0 -1.6 0)
			(layer "B.Fab")
			(effects
				(font
					(size 0.7 0.7)
					(thickness 0.15)
				)
				(justify left bottom mirror)
			)
		)
		(property "Description" "SMD Multilayer Ceramic Capacitor, 47 µF, 6.3 V, 0603 [1608 Metric], ± 20%, X5R, GRM Series"
			(at 0 0 180)
			(layer "F.Fab")
			(hide yes)
			(effects
				(font
					(size 1.27 1.27)
					(thickness 0.15)
				)
			)
		)
		(property "Author" "Antmicro"
			(at 420.5 260 0)
			(layer "B.Fab")
			(hide yes)
			(effects
				(font
					(size 1 1)
					(thickness 0.15)
				)
				(justify mirror)
			)
		)
		(property "Dielectric" ""
			(at 420.5 260 0)
			(layer "B.Fab")
			(hide yes)
			(effects
				(font
					(size 1 1)
					(thickness 0.15)
				)
				(justify mirror)
			)
		)
		(property "License" "Apache-2.0"
			(at 420.5 260 0)
			(layer "B.Fab")
			(hide yes)
			(effects
				(font
					(size 1 1)
					(thickness 0.15)
				)
				(justify mirror)
			)
		)
		(property "MPN" "GRM188R60J476ME15D"
			(at 420.5 260 0)
			(layer "B.Fab")
			(hide yes)
			(effects
				(font
					(size 1 1)
					(thickness 0.15)
				)
				(justify mirror)
			)
		)
		(property "Manufacturer" "Murata"
			(at 420.5 260 0)
			(layer "B.Fab")
			(hide yes)
			(effects
				(font
					(size 1 1)
					(thickness 0.15)
				)
				(justify mirror)
			)
		)
		(property "Val" "47u"
			(at 420.5 260 0)
			(layer "B.Fab")
			(hide yes)
			(effects
				(font
					(size 1 1)
					(thickness 0.15)
				)
				(justify mirror)
			)
		)
		(property "Voltage" ""
			(at 420.5 260 0)
			(layer "B.Fab")
			(hide yes)
			(effects
				(font
					(size 1 1)
					(thickness 0.15)
				)
				(justify mirror)
			)
		)
		(sheetname "FPGA Bank 14 & 15")
		(sheetfile "fpga-bank-14-15.kicad_sch")
		(attr smd)
		(fp_line
			(start -0.15 0.4)
			(end 0.15 0.4)
			(stroke
				(width 0.15)
				(type solid)
			)
			(layer "B.SilkS")
		)
		(fp_line
			(start -0.15 -0.4)
			(end 0.15 -0.4)
			(stroke
				(width 0.15)
				(type solid)
			)
			(layer "B.SilkS")
		)
		(fp_rect
			(start -1.25 0.65)
			(end 1.25 -0.65)
			(stroke
				(width 0.05)
				(type solid)
			)
			(fill no)
			(layer "B.CrtYd")
		)
		(fp_rect
			(start -0.8 0.4)
			(end 0.8 -0.4)
			(stroke
				(width 0.15)
				(type solid)
			)
			(fill no)
			(layer "B.Fab")
		)
		(pad "1" smd roundrect
			(at -0.7 0 180)
			(size 0.8 1)
			(layers "B.Cu" "B.Mask" "B.Paste")
			(roundrect_rratio 0.2)
			(net 1 "GND")
			(pintype "passive")
		)
		(pad "2" smd roundrect
			(at 0.7 0 180)
			(size 0.8 1)
			(layers "B.Cu" "B.Mask" "B.Paste")
			(roundrect_rratio 0.2)
			(net 24 "+3V3")
			(pintype "passive")
		)
	)
	(footprint "antmicro-footprints:C_0402_1005Metric"
		(layer "B.Cu")
		(at 170.5 143.2 90)
		(descr "Capacitor SMD 0402")
		(tags "capacitor SMD 0402")
		(property "Reference" "C295"
			(at 1.075 2.35 270)
			(layer "B.SilkS")
			(effects
				(font
					(size 0.7 0.7)
					(thickness 0.15)
				)
				(justify left bottom mirror)
			)
		)
		(property "Value" "C_100n_0402"
			(at 0 -1.169 270)
			(layer "B.Fab")
			(effects
				(font
					(size 0.7 0.7)
					(thickness 0.15)
				)
				(justify left bottom mirror)
			)
		)
		(property "Description" "SMD Multilayer Ceramic Capacitor, 0.1 µF, 50 V, 0402 [1005 Metric], ± 10%, X5R, GRM Series"
			(at 0 0 90)
			(layer "F.Fab")
			(hide yes)
			(effects
				(font
					(size 1.27 1.27)
					(thickness 0.15)
				)
			)
		)
		(property "Author" "Antmicro"
			(at 313.7 -27.3 0)
			(layer "B.Fab")
			(hide yes)
			(effects
				(font
					(size 1 1)
					(thickness 0.15)
				)
				(justify mirror)
			)
		)
		(property "Dielectric" "X5R"
			(at 313.7 -27.3 0)
			(layer "B.Fab")
			(hide yes)
			(effects
				(font
					(size 1 1)
					(thickness 0.15)
				)
				(justify mirror)
			)
		)
		(property "License" "Apache-2.0"
			(at 313.7 -27.3 0)
			(layer "B.Fab")
			(hide yes)
			(effects
				(font
					(size 1 1)
					(thickness 0.15)
				)
				(justify mirror)
			)
		)
		(property "MPN" "GRM155R61H104KE14D"
			(at 313.7 -27.3 0)
			(layer "B.Fab")
			(hide yes)
			(effects
				(font
					(size 1 1)
					(thickness 0.15)
				)
				(justify mirror)
			)
		)
		(property "Manufacturer" "Murata"
			(at 313.7 -27.3 0)
			(layer "B.Fab")
			(hide yes)
			(effects
				(font
					(size 1 1)
					(thickness 0.15)
				)
				(justify mirror)
			)
		)
		(property "Val" "100n"
			(at 313.7 -27.3 0)
			(layer "B.Fab")
			(hide yes)
			(effects
				(font
					(size 1 1)
					(thickness 0.15)
				)
				(justify mirror)
			)
		)
		(property "Voltage" "50V"
			(at 313.7 -27.3 0)
			(layer "B.Fab")
			(hide yes)
			(effects
				(font
					(size 1 1)
					(thickness 0.15)
				)
				(justify mirror)
			)
		)
		(sheetname "DRAM + SRAM")
		(sheetfile "ram.kicad_sch")
		(attr smd)
		(fp_rect
			(start -0.925 0.47)
			(end 0.925 -0.47)
			(stroke
				(width 0.05)
				(type default)
			)
			(fill no)
			(layer "B.CrtYd")
		)
		(fp_line
			(start 0.504 -0.248)
			(end -0.494 -0.248)
			(stroke
				(width 0.15)
				(type solid)
			)
			(layer "B.Fab")
		)
		(fp_line
			(start -0.494 -0.248)
			(end -0.494 0.25)
			(stroke
				(width 0.15)
				(type solid)
			)
			(layer "B.Fab")
		)
		(fp_line
			(start 0.504 0.25)
			(end 0.504 -0.248)
			(stroke
				(width 0.15)
				(type solid)
			)
			(layer "B.Fab")
		)
		(fp_line
			(start -0.494 0.25)
			(end 0.504 0.25)
			(stroke
				(width 0.15)
				(type solid)
			)
			(layer "B.Fab")
		)
		(pad "1" smd roundrect
			(at -0.48 0 90)
			(size 0.59 0.64)
			(layers "B.Cu" "B.Mask" "B.Paste")
			(roundrect_rratio 0.25)
			(net 1 "GND")
			(pintype "passive")
		)
		(pad "2" smd roundrect
			(at 0.48 0 90)
			(size 0.59 0.64)
			(layers "B.Cu" "B.Mask" "B.Paste")
			(roundrect_rratio 0.25)
			(net 25 "+1V35")
			(pintype "passive")
		)
	)
	(footprint "antmicro-footprints:R_0402_1005Metric"
		(layer "B.Cu")
		(at 249.001 129.7 180)
		(descr "Resistor SMD 0402")
		(tags "resistor SMD 0402")
		(property "Reference" "R92"
			(at -1.099 -1.275 0)
			(layer "B.SilkS")
			(effects
				(font
					(size 0.7 0.7)
					(thickness 0.15)
				)
				(justify left bottom mirror)
			)
		)
		(property "Value" "R_10k_0402"
			(at 0 -1.4 0)
			(layer "B.Fab")
			(effects
				(font
					(size 0.7 0.7)
					(thickness 0.15)
				)
				(justify left bottom mirror)
			)
		)
		(property "Description" "SMD Chip Resistor, 10 kohm, ± 1%, 62.5 mW, 0402 [1005 Metric], Thick Film, General Purpose"
			(at 0 0 180)
			(layer "F.Fab")
			(hide yes)
			(effects
				(font
					(size 1.27 1.27)
					(thickness 0.15)
				)
			)
		)
		(property "Author" "Antmicro"
			(at 498.002 259.4 0)
			(layer "B.Fab")
			(hide yes)
			(effects
				(font
					(size 1 1)
					(thickness 0.15)
				)
				(justify mirror)
			)
		)
		(property "License" "Apache-2.0"
			(at 498.002 259.4 0)
			(layer "B.Fab")
			(hide yes)
			(effects
				(font
					(size 1 1)
					(thickness 0.15)
				)
				(justify mirror)
			)
		)
		(property "MPN" "CR0402-FX-1002GLF"
			(at 498.002 259.4 0)
			(layer "B.Fab")
			(hide yes)
			(effects
				(font
					(size 1 1)
					(thickness 0.15)
				)
				(justify mirror)
			)
		)
		(property "Manufacturer" "Bourns"
			(at 498.002 259.4 0)
			(layer "B.Fab")
			(hide yes)
			(effects
				(font
					(size 1 1)
					(thickness 0.15)
				)
				(justify mirror)
			)
		)
		(property "Tolerance" "1%"
			(at 498.002 259.4 0)
			(layer "B.Fab")
			(hide yes)
			(effects
				(font
					(size 1 1)
					(thickness 0.15)
				)
				(justify mirror)
			)
		)
		(property "Val" "10k"
			(at 498.002 259.4 0)
			(layer "B.Fab")
			(hide yes)
			(effects
				(font
					(size 1 1)
					(thickness 0.15)
				)
				(justify mirror)
			)
		)
		(sheetname "SPI Flash + SD Card")
		(sheetfile "spi-flash.kicad_sch")
		(attr smd)
		(fp_rect
			(start -0.925 0.47)
			(end 0.925 -0.47)
			(stroke
				(width 0.05)
				(type default)
			)
			(fill no)
			(layer "B.CrtYd")
		)
		(fp_rect
			(start -0.5 0.25)
			(end 0.5 -0.25)
			(stroke
				(width 0.15)
				(type solid)
			)
			(fill no)
			(layer "B.Fab")
		)
		(pad "1" smd roundrect
			(at -0.48 0 180)
			(size 0.59 0.64)
			(layers "B.Cu" "B.Mask" "B.Paste")
			(roundrect_rratio 0.25)
			(net 416 "/FPGA Bank 33 & 34/SD_CARD.~{CD}")
			(pintype "passive")
		)
		(pad "2" smd roundrect
			(at 0.48 0 180)
			(size 0.59 0.64)
			(layers "B.Cu" "B.Mask" "B.Paste")
			(roundrect_rratio 0.25)
			(net 24 "+3V3")
			(pintype "passive")
		)
	)
	(footprint "antmicro-footprints:USON-10_2.5x1mm_P0.5mm"
		(layer "B.Cu")
		(at 259.195 75.41 -90)
		(descr "USON-10 2.5x1mm_ Pitch 0.5mm")
		(tags "USON-10 2.5x1mm Pitch 0.5mm")
		(property "Reference" "U46"
			(at 1.69 -1.13 180)
			(layer "B.SilkS")
			(effects
				(font
					(size 0.7 0.7)
					(thickness 0.15)
				)
				(justify left bottom mirror)
			)
		)
		(property "Value" "TPD4E05U06QDQARQ1"
			(at 0.018 -2.499 90)
			(layer "B.Fab")
			(effects
				(font
					(size 0.7 0.7)
					(thickness 0.15)
				)
				(justify left bottom mirror)
			)
		)
		(property "Description" "ESD protection"
			(at 0 0 270)
			(layer "F.Fab")
			(hide yes)
			(effects
				(font
					(size 1.27 1.27)
					(thickness 0.15)
				)
			)
		)
		(property "Author" "Antmicro"
			(at 183.785 334.605 0)
			(layer "B.Fab")
			(hide yes)
			(effects
				(font
					(size 1 1)
					(thickness 0.15)
				)
				(justify mirror)
			)
		)
		(property "License" "Apache-2.0"
			(at 183.785 334.605 0)
			(layer "B.Fab")
			(hide yes)
			(effects
				(font
					(size 1 1)
					(thickness 0.15)
				)
				(justify mirror)
			)
		)
		(property "MPN" "TPD4E05U06QDQARQ1"
			(at 183.785 334.605 0)
			(layer "B.Fab")
			(hide yes)
			(effects
				(font
					(size 1 1)
					(thickness 0.15)
				)
				(justify mirror)
			)
		)
		(property "Manufacturer" "Texas Instruments"
			(at 183.785 334.605 0)
			(layer "B.Fab")
			(hide yes)
			(effects
				(font
					(size 1 1)
					(thickness 0.15)
				)
				(justify mirror)
			)
		)
		(sheetname "User GPIO + LED + button + DIP switch")
		(sheetfile "user-gpio.kicad_sch")
		(attr smd)
		(fp_line
			(start 0.498 1.401)
			(end -0.5 1.401)
			(stroke
				(width 0.15)
				(type solid)
			)
			(layer "B.SilkS")
		)
		(fp_line
			(start 0.498 -1.398)
			(end -0.5 -1.398)
			(stroke
				(width 0.15)
				(type solid)
			)
			(layer "B.SilkS")
		)
		(fp_circle
			(center -0.68 1.27)
			(end -0.63 1.27)
			(stroke
				(width 0.15)
				(type solid)
			)
			(fill yes)
			(layer "B.SilkS")
		)
		(fp_rect
			(start -0.8 1.5)
			(end 0.8 -1.499)
			(stroke
				(width 0.05)
				(type solid)
			)
			(fill no)
			(layer "B.CrtYd")
		)
		(fp_line
			(start -0.25 1.25)
			(end -0.5 1)
			(stroke
				(width 0.15)
				(type solid)
			)
			(layer "B.Fab")
		)
		(fp_line
			(start 0.498 1.25)
			(end -0.25 1.25)
			(stroke
				(width 0.15)
				(type solid)
			)
			(layer "B.Fab")
		)
		(fp_line
			(start 0.498 1.25)
			(end 0.498 -1.249)
			(stroke
				(width 0.15)
				(type solid)
			)
			(layer "B.Fab")
		)
		(fp_line
			(start -0.5 1)
			(end -0.5 -1.249)
			(stroke
				(width 0.15)
				(type solid)
			)
			(layer "B.Fab")
		)
		(fp_line
			(start -0.5 -1.249)
			(end 0.498 -1.249)
			(stroke
				(width 0.15)
				(type solid)
			)
			(layer "B.Fab")
		)
		(pad "1" smd roundrect
			(at -0.387 1)
			(size 0.25 0.55)
			(layers "B.Cu" "B.Mask" "B.Paste")
			(roundrect_rratio 0.25)
			(net 1324 "/USER_IO.DIP_SW4")
			(pintype "passive")
		)
		(pad "2" smd roundrect
			(at -0.387 0.5)
			(size 0.25 0.55)
			(layers "B.Cu" "B.Mask" "B.Paste")
			(roundrect_rratio 0.25)
			(net 1322 "/USER_IO.DIP_SW5")
			(pintype "passive")
		)
		(pad "3" smd roundrect
			(at -0.387 0)
			(size 0.4 0.55)
			(layers "B.Cu" "B.Mask" "B.Paste")
			(roundrect_rratio 0.25)
			(net 1 "GND")
			(pintype "power_in")
		)
		(pad "4" smd roundrect
			(at -0.387 -0.498)
			(size 0.25 0.55)
			(layers "B.Cu" "B.Mask" "B.Paste")
			(roundrect_rratio 0.25)
			(net 1320 "/USER_IO.DIP_SW6")
			(pintype "passive")
		)
		(pad "5" smd roundrect
			(at -0.387 -0.998)
			(size 0.25 0.55)
			(layers "B.Cu" "B.Mask" "B.Paste")
			(roundrect_rratio 0.25)
			(net 1318 "/USER_IO.DIP_SW7")
			(pintype "passive")
		)
		(pad "6" smd roundrect
			(at 0.385 -0.998)
			(size 0.25 0.55)
			(layers "B.Cu" "B.Mask" "B.Paste")
			(roundrect_rratio 0.25)
			(net 1318 "/USER_IO.DIP_SW7")
			(pintype "passive")
		)
		(pad "7" smd roundrect
			(at 0.385 -0.498)
			(size 0.25 0.55)
			(layers "B.Cu" "B.Mask" "B.Paste")
			(roundrect_rratio 0.25)
			(net 1320 "/USER_IO.DIP_SW6")
			(pintype "passive")
		)
		(pad "8" smd roundrect
			(at 0.385 0)
			(size 0.4 0.55)
			(layers "B.Cu" "B.Mask" "B.Paste")
			(roundrect_rratio 0.25)
			(net 1 "GND")
			(pintype "passive")
		)
		(pad "9" smd roundrect
			(at 0.385 0.5)
			(size 0.25 0.55)
			(layers "B.Cu" "B.Mask" "B.Paste")
			(roundrect_rratio 0.25)
			(net 1322 "/USER_IO.DIP_SW5")
			(pintype "passive")
		)
		(pad "10" smd roundrect
			(at 0.385 1)
			(size 0.25 0.55)
			(layers "B.Cu" "B.Mask" "B.Paste")
			(roundrect_rratio 0.25)
			(net 1324 "/USER_IO.DIP_SW4")
			(pintype "passive")
		)
	)
	(footprint "antmicro-footprints:USON-10_2.5x1mm_P0.5mm"
		(layer "B.Cu")
		(at 255.2 75.41 -90)
		(descr "USON-10 2.5x1mm_ Pitch 0.5mm")
		(tags "USON-10 2.5x1mm Pitch 0.5mm")
		(property "Reference" "U45"
			(at 1.69 -1.1 180)
			(layer "B.SilkS")
			(effects
				(font
					(size 0.7 0.7)
					(thickness 0.15)
				)
				(justify left bottom mirror)
			)
		)
		(property "Value" "TPD4E05U06QDQARQ1"
			(at 0.018 -2.499 90)
			(layer "B.Fab")
			(effects
				(font
					(size 0.7 0.7)
					(thickness 0.15)
				)
				(justify left bottom mirror)
			)
		)
		(property "Description" "ESD protection"
			(at 0 0 270)
			(layer "F.Fab")
			(hide yes)
			(effects
				(font
					(size 1.27 1.27)
					(thickness 0.15)
				)
			)
		)
		(property "Author" "Antmicro"
			(at 179.79 330.61 0)
			(layer "B.Fab")
			(hide yes)
			(effects
				(font
					(size 1 1)
					(thickness 0.15)
				)
				(justify mirror)
			)
		)
		(property "License" "Apache-2.0"
			(at 179.79 330.61 0)
			(layer "B.Fab")
			(hide yes)
			(effects
				(font
					(size 1 1)
					(thickness 0.15)
				)
				(justify mirror)
			)
		)
		(property "MPN" "TPD4E05U06QDQARQ1"
			(at 179.79 330.61 0)
			(layer "B.Fab")
			(hide yes)
			(effects
				(font
					(size 1 1)
					(thickness 0.15)
				)
				(justify mirror)
			)
		)
		(property "Manufacturer" "Texas Instruments"
			(at 179.79 330.61 0)
			(layer "B.Fab")
			(hide yes)
			(effects
				(font
					(size 1 1)
					(thickness 0.15)
				)
				(justify mirror)
			)
		)
		(sheetname "User GPIO + LED + button + DIP switch")
		(sheetfile "user-gpio.kicad_sch")
		(attr smd)
		(fp_line
			(start 0.498 1.401)
			(end -0.5 1.401)
			(stroke
				(width 0.15)
				(type solid)
			)
			(layer "B.SilkS")
		)
		(fp_line
			(start 0.498 -1.398)
			(end -0.5 -1.398)
			(stroke
				(width 0.15)
				(type solid)
			)
			(layer "B.SilkS")
		)
		(fp_circle
			(center -0.68 1.27)
			(end -0.63 1.27)
			(stroke
				(width 0.15)
				(type solid)
			)
			(fill yes)
			(layer "B.SilkS")
		)
		(fp_rect
			(start -0.8 1.5)
			(end 0.8 -1.499)
			(stroke
				(width 0.05)
				(type solid)
			)
			(fill no)
			(layer "B.CrtYd")
		)
		(fp_line
			(start -0.25 1.25)
			(end -0.5 1)
			(stroke
				(width 0.15)
				(type solid)
			)
			(layer "B.Fab")
		)
		(fp_line
			(start 0.498 1.25)
			(end -0.25 1.25)
			(stroke
				(width 0.15)
				(type solid)
			)
			(layer "B.Fab")
		)
		(fp_line
			(start 0.498 1.25)
			(end 0.498 -1.249)
			(stroke
				(width 0.15)
				(type solid)
			)
			(layer "B.Fab")
		)
		(fp_line
			(start -0.5 1)
			(end -0.5 -1.249)
			(stroke
				(width 0.15)
				(type solid)
			)
			(layer "B.Fab")
		)
		(fp_line
			(start -0.5 -1.249)
			(end 0.498 -1.249)
			(stroke
				(width 0.15)
				(type solid)
			)
			(layer "B.Fab")
		)
		(pad "1" smd roundrect
			(at -0.387 1)
			(size 0.25 0.55)
			(layers "B.Cu" "B.Mask" "B.Paste")
			(roundrect_rratio 0.25)
			(net 1311 "/USER_IO.DIP_SW0")
			(pintype "passive")
		)
		(pad "2" smd roundrect
			(at -0.387 0.5)
			(size 0.25 0.55)
			(layers "B.Cu" "B.Mask" "B.Paste")
			(roundrect_rratio 0.25)
			(net 1310 "/USER_IO.DIP_SW1")
			(pintype "passive")
		)
		(pad "3" smd roundrect
			(at -0.387 0)
			(size 0.4 0.55)
			(layers "B.Cu" "B.Mask" "B.Paste")
			(roundrect_rratio 0.25)
			(net 1 "GND")
			(pintype "power_in")
		)
		(pad "4" smd roundrect
			(at -0.387 -0.498)
			(size 0.25 0.55)
			(layers "B.Cu" "B.Mask" "B.Paste")
			(roundrect_rratio 0.25)
			(net 1309 "/USER_IO.DIP_SW2")
			(pintype "passive")
		)
		(pad "5" smd roundrect
			(at -0.387 -0.998)
			(size 0.25 0.55)
			(layers "B.Cu" "B.Mask" "B.Paste")
			(roundrect_rratio 0.25)
			(net 1308 "/USER_IO.DIP_SW3")
			(pintype "passive")
		)
		(pad "6" smd roundrect
			(at 0.385 -0.998)
			(size 0.25 0.55)
			(layers "B.Cu" "B.Mask" "B.Paste")
			(roundrect_rratio 0.25)
			(net 1308 "/USER_IO.DIP_SW3")
			(pintype "passive")
		)
		(pad "7" smd roundrect
			(at 0.385 -0.498)
			(size 0.25 0.55)
			(layers "B.Cu" "B.Mask" "B.Paste")
			(roundrect_rratio 0.25)
			(net 1309 "/USER_IO.DIP_SW2")
			(pintype "passive")
		)
		(pad "8" smd roundrect
			(at 0.385 0)
			(size 0.4 0.55)
			(layers "B.Cu" "B.Mask" "B.Paste")
			(roundrect_rratio 0.25)
			(net 1 "GND")
			(pintype "passive")
		)
		(pad "9" smd roundrect
			(at 0.385 0.5)
			(size 0.25 0.55)
			(layers "B.Cu" "B.Mask" "B.Paste")
			(roundrect_rratio 0.25)
			(net 1310 "/USER_IO.DIP_SW1")
			(pintype "passive")
		)
		(pad "10" smd roundrect
			(at 0.385 1)
			(size 0.25 0.55)
			(layers "B.Cu" "B.Mask" "B.Paste")
			(roundrect_rratio 0.25)
			(net 1311 "/USER_IO.DIP_SW0")
			(pintype "passive")
		)
	)
	(footprint "antmicro-footprints:NetTie-2_SMD_Pad0.127mm"
		(layer "B.Cu")
		(at 208.62 147.257001 90)
		(descr "Net tie, 2 pin, 0.127mm  SMD pads")
		(tags "net tie")
		(property "Reference" "NT32"
			(at -0.128 1.345 270)
			(layer "B.SilkS")
			(hide yes)
			(effects
				(font
					(size 0.7 0.7)
					(thickness 0.15)
				)
				(justify left bottom mirror)
			)
		)
		(property "Value" "Net-Tie_2"
			(at 0 -1.199 270)
			(layer "B.Fab")
			(effects
				(font
					(size 0.7 0.7)
					(thickness 0.15)
				)
				(justify left bottom mirror)
			)
		)
		(property "Description" "Net tie, 2 pins"
			(at 0 0 90)
			(layer "F.Fab")
			(hide yes)
			(effects
				(font
					(size 1.27 1.27)
					(thickness 0.15)
				)
			)
		)
		(property "Author" "Antmicro"
			(at 355.877001 -61.362999 0)
			(layer "B.Fab")
			(hide yes)
			(effects
				(font
					(size 1 1)
					(thickness 0.15)
				)
				(justify mirror)
			)
		)
		(property "License" "Apache-2.0"
			(at 355.877001 -61.362999 0)
			(layer "B.Fab")
			(hide yes)
			(effects
				(font
					(size 1 1)
					(thickness 0.15)
				)
				(justify mirror)
			)
		)
		(property "MPN" ""
			(at 355.877001 -61.362999 0)
			(layer "B.Fab")
			(hide yes)
			(effects
				(font
					(size 1 1)
					(thickness 0.15)
				)
				(justify mirror)
			)
		)
		(property "Manufacturer" ""
			(at 355.877001 -61.362999 0)
			(layer "B.Fab")
			(hide yes)
			(effects
				(font
					(size 1 1)
					(thickness 0.15)
				)
				(justify mirror)
			)
		)
		(sheetname "DC-DC Converters")
		(sheetfile "dc-dc.kicad_sch")
		(attr exclude_from_pos_files)
		(net_tie_pad_groups "1, 2")
		(fp_poly
			(pts
				(xy -0.0635 0.0635) (xy 0.0625 0.0635) (xy 0.0625 -0.0635) (xy -0.0635 -0.0635)
			)
			(stroke
				(width 0)
				(type solid)
			)
			(fill yes)
			(layer "B.Cu")
		)
		(pad "1" smd roundrect
			(at -0.127 0 270)
			(size 0.127 0.127)
			(layers "B.Cu")
			(roundrect_rratio 0.5)
			(chamfer_ratio 0)
			(chamfer top_left bottom_left)
			(net 1220 "/DC-DC Converters/SENSE_3V3_2_P")
			(pinfunction "1")
			(pintype "passive")
		)
		(pad "2" smd roundrect
			(at 0.126 0 90)
			(size 0.127 0.127)
			(layers "B.Cu")
			(roundrect_rratio 0.5)
			(chamfer_ratio 0)
			(chamfer top_left bottom_left)
			(net 24 "+3V3")
			(pinfunction "2")
			(pintype "passive")
		)
	)
	(footprint "antmicro-footprints:R_0402_1005Metric"
		(layer "B.Cu")
		(at 242.501 133.9)
		(descr "Resistor SMD 0402")
		(tags "resistor SMD 0402")
		(property "Reference" "R161"
			(at -0.751 0.4 180)
			(layer "B.SilkS")
			(effects
				(font
					(size 0.7 0.7)
					(thickness 0.15)
				)
				(justify left bottom mirror)
			)
		)
		(property "Value" "R_33R_0402"
			(at 0 -1.4 180)
			(layer "B.Fab")
			(effects
				(font
					(size 0.7 0.7)
					(thickness 0.15)
				)
				(justify left bottom mirror)
			)
		)
		(property "Description" "SMD Chip Resistor, 33 ohm, ± 1%, 62.5 mW, 0402 [1005 Metric], Thick Film, General Purpose"
			(at 0 0 0)
			(layer "F.Fab")
			(hide yes)
			(effects
				(font
					(size 1.27 1.27)
					(thickness 0.15)
				)
			)
		)
		(property "Author" "Antmicro"
			(at 0 0 0)
			(layer "B.Fab")
			(hide yes)
			(effects
				(font
					(size 1 1)
					(thickness 0.15)
				)
				(justify mirror)
			)
		)
		(property "License" "Apache-2.0"
			(at 0 0 0)
			(layer "B.Fab")
			(hide yes)
			(effects
				(font
					(size 1 1)
					(thickness 0.15)
				)
				(justify mirror)
			)
		)
		(property "MPN" "CR0402-FX-33R0GLF"
			(at 0 0 0)
			(layer "B.Fab")
			(hide yes)
			(effects
				(font
					(size 1 1)
					(thickness 0.15)
				)
				(justify mirror)
			)
		)
		(property "Manufacturer" "Bourns"
			(at 0 0 0)
			(layer "B.Fab")
			(hide yes)
			(effects
				(font
					(size 1 1)
					(thickness 0.15)
				)
				(justify mirror)
			)
		)
		(property "Tolerance" "1%"
			(at 0 0 0)
			(layer "B.Fab")
			(hide yes)
			(effects
				(font
					(size 1 1)
					(thickness 0.15)
				)
				(justify mirror)
			)
		)
		(property "Val" "33R"
			(at 0 0 0)
			(layer "B.Fab")
			(hide yes)
			(effects
				(font
					(size 1 1)
					(thickness 0.15)
				)
				(justify mirror)
			)
		)
		(sheetname "USB PHY")
		(sheetfile "usb-phy.kicad_sch")
		(attr smd)
		(fp_rect
			(start -0.925 0.47)
			(end 0.925 -0.47)
			(stroke
				(width 0.05)
				(type default)
			)
			(fill no)
			(layer "B.CrtYd")
		)
		(fp_rect
			(start -0.5 0.25)
			(end 0.5 -0.25)
			(stroke
				(width 0.15)
				(type solid)
			)
			(fill no)
			(layer "B.Fab")
		)
		(pad "1" smd roundrect
			(at -0.48 0)
			(size 0.59 0.64)
			(layers "B.Cu" "B.Mask" "B.Paste")
			(roundrect_rratio 0.25)
			(net 921 "/USB PHY/FTDI_UART0_TX")
			(pintype "passive")
		)
		(pad "2" smd roundrect
			(at 0.48 0)
			(size 0.59 0.64)
			(layers "B.Cu" "B.Mask" "B.Paste")
			(roundrect_rratio 0.25)
			(net 46 "/FPGA Bank 12 & 13/UART0.RX")
			(pintype "passive")
		)
	)
	(footprint "antmicro-footprints:R_0402_1005Metric"
		(layer "B.Cu")
		(at 233.8 147.9)
		(descr "Resistor SMD 0402")
		(tags "resistor SMD 0402")
		(property "Reference" "R194"
			(at -0.7 0.375 180)
			(layer "B.SilkS")
			(effects
				(font
					(size 0.7 0.7)
					(thickness 0.15)
				)
				(justify left bottom mirror)
			)
		)
		(property "Value" "R_10k_0402"
			(at 0 -1.4 180)
			(layer "B.Fab")
			(effects
				(font
					(size 0.7 0.7)
					(thickness 0.15)
				)
				(justify left bottom mirror)
			)
		)
		(property "Description" "SMD Chip Resistor, 10 kohm, ± 1%, 62.5 mW, 0402 [1005 Metric], Thick Film, General Purpose"
			(at 0 0 0)
			(layer "F.Fab")
			(hide yes)
			(effects
				(font
					(size 1.27 1.27)
					(thickness 0.15)
				)
			)
		)
		(property "Author" "Antmicro"
			(at 0 0 0)
			(layer "B.Fab")
			(hide yes)
			(effects
				(font
					(size 1 1)
					(thickness 0.15)
				)
				(justify mirror)
			)
		)
		(property "License" "Apache-2.0"
			(at 0 0 0)
			(layer "B.Fab")
			(hide yes)
			(effects
				(font
					(size 1 1)
					(thickness 0.15)
				)
				(justify mirror)
			)
		)
		(property "MPN" "CR0402-FX-1002GLF"
			(at 0 0 0)
			(layer "B.Fab")
			(hide yes)
			(effects
				(font
					(size 1 1)
					(thickness 0.15)
				)
				(justify mirror)
			)
		)
		(property "Manufacturer" "Bourns"
			(at 0 0 0)
			(layer "B.Fab")
			(hide yes)
			(effects
				(font
					(size 1 1)
					(thickness 0.15)
				)
				(justify mirror)
			)
		)
		(property "Tolerance" "1%"
			(at 0 0 0)
			(layer "B.Fab")
			(hide yes)
			(effects
				(font
					(size 1 1)
					(thickness 0.15)
				)
				(justify mirror)
			)
		)
		(property "Val" "10k"
			(at 0 0 0)
			(layer "B.Fab")
			(hide yes)
			(effects
				(font
					(size 1 1)
					(thickness 0.15)
				)
				(justify mirror)
			)
		)
		(sheetname "USB PHY")
		(sheetfile "usb-phy.kicad_sch")
		(attr smd)
		(fp_rect
			(start -0.925 0.47)
			(end 0.925 -0.47)
			(stroke
				(width 0.05)
				(type default)
			)
			(fill no)
			(layer "B.CrtYd")
		)
		(fp_rect
			(start -0.5 0.25)
			(end 0.5 -0.25)
			(stroke
				(width 0.15)
				(type solid)
			)
			(fill no)
			(layer "B.Fab")
		)
		(pad "1" smd roundrect
			(at -0.48 0)
			(size 0.59 0.64)
			(layers "B.Cu" "B.Mask" "B.Paste")
			(roundrect_rratio 0.25)
			(net 498 "/FPGA Bank 12 & 13/USB_USER.~{OE}")
			(pintype "passive")
		)
		(pad "2" smd roundrect
			(at 0.48 0)
			(size 0.59 0.64)
			(layers "B.Cu" "B.Mask" "B.Paste")
			(roundrect_rratio 0.25)
			(net 26 "+1V8")
			(pintype "passive")
		)
	)
	(footprint "antmicro-footprints:R_0402_1005Metric"
		(layer "B.Cu")
		(at 221.084 146.2 -90)
		(descr "Resistor SMD 0402")
		(tags "resistor SMD 0402")
		(property "Reference" "R235"
			(at -3.625 -0.375 90)
			(layer "B.SilkS")
			(effects
				(font
					(size 0.7 0.7)
					(thickness 0.15)
				)
				(justify left bottom mirror)
			)
		)
		(property "Value" "R_10R_0402"
			(at 0 -1.4 90)
			(layer "B.Fab")
			(effects
				(font
					(size 0.7 0.7)
					(thickness 0.15)
				)
				(justify left bottom mirror)
			)
		)
		(property "Description" "SMD Chip Resistor, 10 ohm, ± 1%, 62.5 mW, 0402 [1005 Metric], Thick Film, General Purpose"
			(at 0 0 270)
			(layer "F.Fab")
			(hide yes)
			(effects
				(font
					(size 1.27 1.27)
					(thickness 0.15)
				)
			)
		)
		(property "Author" "Antmicro"
			(at 74.884 367.284 0)
			(layer "B.Fab")
			(hide yes)
			(effects
				(font
					(size 1 1)
					(thickness 0.15)
				)
				(justify mirror)
			)
		)
		(property "License" "Apache-2.0"
			(at 74.884 367.284 0)
			(layer "B.Fab")
			(hide yes)
			(effects
				(font
					(size 1 1)
					(thickness 0.15)
				)
				(justify mirror)
			)
		)
		(property "MPN" "CR0402-FX-10R0GLF"
			(at 74.884 367.284 0)
			(layer "B.Fab")
			(hide yes)
			(effects
				(font
					(size 1 1)
					(thickness 0.15)
				)
				(justify mirror)
			)
		)
		(property "Manufacturer" "Bourns"
			(at 74.884 367.284 0)
			(layer "B.Fab")
			(hide yes)
			(effects
				(font
					(size 1 1)
					(thickness 0.15)
				)
				(justify mirror)
			)
		)
		(property "Tolerance" "1%"
			(at 74.884 367.284 0)
			(layer "B.Fab")
			(hide yes)
			(effects
				(font
					(size 1 1)
					(thickness 0.15)
				)
				(justify mirror)
			)
		)
		(property "Val" "10R"
			(at 74.884 367.284 0)
			(layer "B.Fab")
			(hide yes)
			(effects
				(font
					(size 1 1)
					(thickness 0.15)
				)
				(justify mirror)
			)
		)
		(sheetname "HDMI + Ethernet")
		(sheetfile "hdmi-ethernet.kicad_sch")
		(attr smd)
		(fp_rect
			(start -0.925 0.47)
			(end 0.925 -0.47)
			(stroke
				(width 0.05)
				(type default)
			)
			(fill no)
			(layer "B.CrtYd")
		)
		(fp_rect
			(start -0.5 0.25)
			(end 0.5 -0.25)
			(stroke
				(width 0.15)
				(type solid)
			)
			(fill no)
			(layer "B.Fab")
		)
		(pad "1" smd roundrect
			(at -0.48 0 270)
			(size 0.59 0.64)
			(layers "B.Cu" "B.Mask" "B.Paste")
			(roundrect_rratio 0.25)
			(net 517 "/FPGA Bank 18 & 32/ETH_RMII.RX_DV")
			(pintype "passive")
		)
		(pad "2" smd roundrect
			(at 0.48 0 270)
			(size 0.59 0.64)
			(layers "B.Cu" "B.Mask" "B.Paste")
			(roundrect_rratio 0.25)
			(net 944 "/HDMI + Ethernet/ETH_PHY_RX_DV")
			(pintype "passive")
		)
	)
	(footprint "antmicro-footprints:C_0402_1005Metric"
		(layer "B.Cu")
		(at 198.01 122.5)
		(descr "Capacitor SMD 0402")
		(tags "capacitor SMD 0402")
		(property "Reference" "C82"
			(at 25.075 -29.575 180)
			(layer "B.SilkS")
			(effects
				(font
					(size 0.7 0.7)
					(thickness 0.15)
				)
				(justify left bottom mirror)
			)
		)
		(property "Value" "C_100n_0402"
			(at 0 -1.169 180)
			(layer "B.Fab")
			(effects
				(font
					(size 0.7 0.7)
					(thickness 0.15)
				)
				(justify left bottom mirror)
			)
		)
		(property "Description" "SMD Multilayer Ceramic Capacitor, 0.1 µF, 50 V, 0402 [1005 Metric], ± 10%, X5R, GRM Series"
			(at 0 0 0)
			(layer "F.Fab")
			(hide yes)
			(effects
				(font
					(size 1.27 1.27)
					(thickness 0.15)
				)
			)
		)
		(property "Author" "Antmicro"
			(at 0 0 0)
			(layer "B.Fab")
			(hide yes)
			(effects
				(font
					(size 1 1)
					(thickness 0.15)
				)
				(justify mirror)
			)
		)
		(property "Dielectric" "X5R"
			(at 0 0 0)
			(layer "B.Fab")
			(hide yes)
			(effects
				(font
					(size 1 1)
					(thickness 0.15)
				)
				(justify mirror)
			)
		)
		(property "License" "Apache-2.0"
			(at 0 0 0)
			(layer "B.Fab")
			(hide yes)
			(effects
				(font
					(size 1 1)
					(thickness 0.15)
				)
				(justify mirror)
			)
		)
		(property "MPN" "GRM155R61H104KE14D"
			(at 0 0 0)
			(layer "B.Fab")
			(hide yes)
			(effects
				(font
					(size 1 1)
					(thickness 0.15)
				)
				(justify mirror)
			)
		)
		(property "Manufacturer" "Murata"
			(at 0 0 0)
			(layer "B.Fab")
			(hide yes)
			(effects
				(font
					(size 1 1)
					(thickness 0.15)
				)
				(justify mirror)
			)
		)
		(property "Val" "100n"
			(at 0 0 0)
			(layer "B.Fab")
			(hide yes)
			(effects
				(font
					(size 1 1)
					(thickness 0.15)
				)
				(justify mirror)
			)
		)
		(property "Voltage" "50V"
			(at 0 0 0)
			(layer "B.Fab")
			(hide yes)
			(effects
				(font
					(size 1 1)
					(thickness 0.15)
				)
				(justify mirror)
			)
		)
		(sheetname "FPGA Bank 18 & 32")
		(sheetfile "fpga-bank-18-32.kicad_sch")
		(attr smd)
		(fp_rect
			(start -0.925 0.47)
			(end 0.925 -0.47)
			(stroke
				(width 0.05)
				(type default)
			)
			(fill no)
			(layer "B.CrtYd")
		)
		(fp_line
			(start -0.494 -0.248)
			(end -0.494 0.25)
			(stroke
				(width 0.15)
				(type solid)
			)
			(layer "B.Fab")
		)
		(fp_line
			(start -0.494 0.25)
			(end 0.504 0.25)
			(stroke
				(width 0.15)
				(type solid)
			)
			(layer "B.Fab")
		)
		(fp_line
			(start 0.504 -0.248)
			(end -0.494 -0.248)
			(stroke
				(width 0.15)
				(type solid)
			)
			(layer "B.Fab")
		)
		(fp_line
			(start 0.504 0.25)
			(end 0.504 -0.248)
			(stroke
				(width 0.15)
				(type solid)
			)
			(layer "B.Fab")
		)
		(pad "1" smd roundrect
			(at -0.48 0)
			(size 0.59 0.64)
			(layers "B.Cu" "B.Mask" "B.Paste")
			(roundrect_rratio 0.25)
			(net 1 "GND")
			(pintype "passive")
		)
		(pad "2" smd roundrect
			(at 0.48 0)
			(size 0.59 0.64)
			(layers "B.Cu" "B.Mask" "B.Paste")
			(roundrect_rratio 0.25)
			(net 24 "+3V3")
			(pintype "passive")
		)
	)
	(footprint "antmicro-footprints:C_0402_1005Metric"
		(layer "B.Cu")
		(at 244.701 165)
		(descr "Capacitor SMD 0402")
		(tags "capacitor SMD 0402")
		(property "Reference" "C269"
			(at 1.374 2.275 0)
			(layer "B.SilkS")
			(effects
				(font
					(size 0.7 0.7)
					(thickness 0.15)
				)
				(justify left bottom mirror)
			)
		)
		(property "Value" "C_100n_0402"
			(at 0 -1.169 180)
			(layer "B.Fab")
			(effects
				(font
					(size 0.7 0.7)
					(thickness 0.15)
				)
				(justify left bottom mirror)
			)
		)
		(property "Description" "SMD Multilayer Ceramic Capacitor, 0.1 µF, 50 V, 0402 [1005 Metric], ± 10%, X5R, GRM Series"
			(at 0 0 0)
			(layer "F.Fab")
			(hide yes)
			(effects
				(font
					(size 1.27 1.27)
					(thickness 0.15)
				)
			)
		)
		(property "Author" "Antmicro"
			(at 0 0 0)
			(layer "B.Fab")
			(hide yes)
			(effects
				(font
					(size 1 1)
					(thickness 0.15)
				)
				(justify mirror)
			)
		)
		(property "Dielectric" "X5R"
			(at 0 0 0)
			(layer "B.Fab")
			(hide yes)
			(effects
				(font
					(size 1 1)
					(thickness 0.15)
				)
				(justify mirror)
			)
		)
		(property "License" "Apache-2.0"
			(at 0 0 0)
			(layer "B.Fab")
			(hide yes)
			(effects
				(font
					(size 1 1)
					(thickness 0.15)
				)
				(justify mirror)
			)
		)
		(property "MPN" "GRM155R61H104KE14D"
			(at 0 0 0)
			(layer "B.Fab")
			(hide yes)
			(effects
				(font
					(size 1 1)
					(thickness 0.15)
				)
				(justify mirror)
			)
		)
		(property "Manufacturer" "Murata"
			(at 0 0 0)
			(layer "B.Fab")
			(hide yes)
			(effects
				(font
					(size 1 1)
					(thickness 0.15)
				)
				(justify mirror)
			)
		)
		(property "Val" "100n"
			(at 0 0 0)
			(layer "B.Fab")
			(hide yes)
			(effects
				(font
					(size 1 1)
					(thickness 0.15)
				)
				(justify mirror)
			)
		)
		(property "Voltage" "50V"
			(at 0 0 0)
			(layer "B.Fab")
			(hide yes)
			(effects
				(font
					(size 1 1)
					(thickness 0.15)
				)
				(justify mirror)
			)
		)
		(sheetname "HDMI + Ethernet")
		(sheetfile "hdmi-ethernet.kicad_sch")
		(attr smd)
		(fp_rect
			(start -0.925 0.47)
			(end 0.925 -0.47)
			(stroke
				(width 0.05)
				(type default)
			)
			(fill no)
			(layer "B.CrtYd")
		)
		(fp_line
			(start -0.494 -0.248)
			(end -0.494 0.25)
			(stroke
				(width 0.15)
				(type solid)
			)
			(layer "B.Fab")
		)
		(fp_line
			(start -0.494 0.25)
			(end 0.504 0.25)
			(stroke
				(width 0.15)
				(type solid)
			)
			(layer "B.Fab")
		)
		(fp_line
			(start 0.504 -0.248)
			(end -0.494 -0.248)
			(stroke
				(width 0.15)
				(type solid)
			)
			(layer "B.Fab")
		)
		(fp_line
			(start 0.504 0.25)
			(end 0.504 -0.248)
			(stroke
				(width 0.15)
				(type solid)
			)
			(layer "B.Fab")
		)
		(pad "1" smd roundrect
			(at -0.48 0)
			(size 0.59 0.64)
			(layers "B.Cu" "B.Mask" "B.Paste")
			(roundrect_rratio 0.25)
			(net 1 "GND")
			(pintype "passive")
		)
		(pad "2" smd roundrect
			(at 0.48 0)
			(size 0.59 0.64)
			(layers "B.Cu" "B.Mask" "B.Paste")
			(roundrect_rratio 0.25)
			(net 12 "Net-(J15A-TRDCT1{slash}2{slash}3{slash}4_1)")
			(pintype "passive")
		)
	)
	(footprint "antmicro-footprints:C_0402_1005Metric"
		(layer "B.Cu")
		(at 196.85 132.225 180)
		(descr "Capacitor SMD 0402")
		(tags "capacitor SMD 0402")
		(property "Reference" "C117"
			(at -25.35 28.05 0)
			(layer "B.SilkS")
			(effects
				(font
					(size 0.7 0.7)
					(thickness 0.15)
				)
				(justify left bottom mirror)
			)
		)
		(property "Value" "C_100n_0402"
			(at 0 -1.169 0)
			(layer "B.Fab")
			(effects
				(font
					(size 0.7 0.7)
					(thickness 0.15)
				)
				(justify left bottom mirror)
			)
		)
		(property "Description" "SMD Multilayer Ceramic Capacitor, 0.1 µF, 50 V, 0402 [1005 Metric], ± 10%, X5R, GRM Series"
			(at 0 0 180)
			(layer "F.Fab")
			(hide yes)
			(effects
				(font
					(size 1.27 1.27)
					(thickness 0.15)
				)
			)
		)
		(property "Author" "Antmicro"
			(at 393.7 264.45 0)
			(layer "B.Fab")
			(hide yes)
			(effects
				(font
					(size 1 1)
					(thickness 0.15)
				)
				(justify mirror)
			)
		)
		(property "Dielectric" "X5R"
			(at 393.7 264.45 0)
			(layer "B.Fab")
			(hide yes)
			(effects
				(font
					(size 1 1)
					(thickness 0.15)
				)
				(justify mirror)
			)
		)
		(property "License" "Apache-2.0"
			(at 393.7 264.45 0)
			(layer "B.Fab")
			(hide yes)
			(effects
				(font
					(size 1 1)
					(thickness 0.15)
				)
				(justify mirror)
			)
		)
		(property "MPN" "GRM155R61H104KE14D"
			(at 393.7 264.45 0)
			(layer "B.Fab")
			(hide yes)
			(effects
				(font
					(size 1 1)
					(thickness 0.15)
				)
				(justify mirror)
			)
		)
		(property "Manufacturer" "Murata"
			(at 393.7 264.45 0)
			(layer "B.Fab")
			(hide yes)
			(effects
				(font
					(size 1 1)
					(thickness 0.15)
				)
				(justify mirror)
			)
		)
		(property "Val" "100n"
			(at 393.7 264.45 0)
			(layer "B.Fab")
			(hide yes)
			(effects
				(font
					(size 1 1)
					(thickness 0.15)
				)
				(justify mirror)
			)
		)
		(property "Voltage" "50V"
			(at 393.7 264.45 0)
			(layer "B.Fab")
			(hide yes)
			(effects
				(font
					(size 1 1)
					(thickness 0.15)
				)
				(justify mirror)
			)
		)
		(sheetname "FPGA supply")
		(sheetfile "fpga-supply.kicad_sch")
		(attr smd)
		(fp_rect
			(start -0.925 0.47)
			(end 0.925 -0.47)
			(stroke
				(width 0.05)
				(type default)
			)
			(fill no)
			(layer "B.CrtYd")
		)
		(fp_line
			(start 0.504 0.25)
			(end 0.504 -0.248)
			(stroke
				(width 0.15)
				(type solid)
			)
			(layer "B.Fab")
		)
		(fp_line
			(start 0.504 -0.248)
			(end -0.494 -0.248)
			(stroke
				(width 0.15)
				(type solid)
			)
			(layer "B.Fab")
		)
		(fp_line
			(start -0.494 0.25)
			(end 0.504 0.25)
			(stroke
				(width 0.15)
				(type solid)
			)
			(layer "B.Fab")
		)
		(fp_line
			(start -0.494 -0.248)
			(end -0.494 0.25)
			(stroke
				(width 0.15)
				(type solid)
			)
			(layer "B.Fab")
		)
		(pad "1" smd roundrect
			(at -0.48 0 180)
			(size 0.59 0.64)
			(layers "B.Cu" "B.Mask" "B.Paste")
			(roundrect_rratio 0.25)
			(net 1 "GND")
			(pintype "passive")
		)
		(pad "2" smd roundrect
			(at 0.48 0 180)
			(size 0.59 0.64)
			(layers "B.Cu" "B.Mask" "B.Paste")
			(roundrect_rratio 0.25)
			(net 650 "+1V0")
			(pintype "passive")
		)
	)
	(footprint "antmicro-footprints:C_0402_1005Metric"
		(layer "B.Cu")
		(at 196.325 126.825 180)
		(descr "Capacitor SMD 0402")
		(tags "capacitor SMD 0402")
		(property "Reference" "C128"
			(at -25.35 29.325 0)
			(layer "B.SilkS")
			(effects
				(font
					(size 0.7 0.7)
					(thickness 0.15)
				)
				(justify left bottom mirror)
			)
		)
		(property "Value" "C_100n_0402"
			(at 0 -1.169 0)
			(layer "B.Fab")
			(effects
				(font
					(size 0.7 0.7)
					(thickness 0.15)
				)
				(justify left bottom mirror)
			)
		)
		(property "Description" "SMD Multilayer Ceramic Capacitor, 0.1 µF, 50 V, 0402 [1005 Metric], ± 10%, X5R, GRM Series"
			(at 0 0 180)
			(layer "F.Fab")
			(hide yes)
			(effects
				(font
					(size 1.27 1.27)
					(thickness 0.15)
				)
			)
		)
		(property "Author" "Antmicro"
			(at 392.65 253.65 0)
			(layer "B.Fab")
			(hide yes)
			(effects
				(font
					(size 1 1)
					(thickness 0.15)
				)
				(justify mirror)
			)
		)
		(property "Dielectric" "X5R"
			(at 392.65 253.65 0)
			(layer "B.Fab")
			(hide yes)
			(effects
				(font
					(size 1 1)
					(thickness 0.15)
				)
				(justify mirror)
			)
		)
		(property "License" "Apache-2.0"
			(at 392.65 253.65 0)
			(layer "B.Fab")
			(hide yes)
			(effects
				(font
					(size 1 1)
					(thickness 0.15)
				)
				(justify mirror)
			)
		)
		(property "MPN" "GRM155R61H104KE14D"
			(at 392.65 253.65 0)
			(layer "B.Fab")
			(hide yes)
			(effects
				(font
					(size 1 1)
					(thickness 0.15)
				)
				(justify mirror)
			)
		)
		(property "Manufacturer" "Murata"
			(at 392.65 253.65 0)
			(layer "B.Fab")
			(hide yes)
			(effects
				(font
					(size 1 1)
					(thickness 0.15)
				)
				(justify mirror)
			)
		)
		(property "Val" "100n"
			(at 392.65 253.65 0)
			(layer "B.Fab")
			(hide yes)
			(effects
				(font
					(size 1 1)
					(thickness 0.15)
				)
				(justify mirror)
			)
		)
		(property "Voltage" "50V"
			(at 392.65 253.65 0)
			(layer "B.Fab")
			(hide yes)
			(effects
				(font
					(size 1 1)
					(thickness 0.15)
				)
				(justify mirror)
			)
		)
		(sheetname "FPGA supply")
		(sheetfile "fpga-supply.kicad_sch")
		(attr smd)
		(fp_rect
			(start -0.925 0.47)
			(end 0.925 -0.47)
			(stroke
				(width 0.05)
				(type default)
			)
			(fill no)
			(layer "B.CrtYd")
		)
		(fp_line
			(start 0.504 0.25)
			(end 0.504 -0.248)
			(stroke
				(width 0.15)
				(type solid)
			)
			(layer "B.Fab")
		)
		(fp_line
			(start 0.504 -0.248)
			(end -0.494 -0.248)
			(stroke
				(width 0.15)
				(type solid)
			)
			(layer "B.Fab")
		)
		(fp_line
			(start -0.494 0.25)
			(end 0.504 0.25)
			(stroke
				(width 0.15)
				(type solid)
			)
			(layer "B.Fab")
		)
		(fp_line
			(start -0.494 -0.248)
			(end -0.494 0.25)
			(stroke
				(width 0.15)
				(type solid)
			)
			(layer "B.Fab")
		)
		(pad "1" smd roundrect
			(at -0.48 0 180)
			(size 0.59 0.64)
			(layers "B.Cu" "B.Mask" "B.Paste")
			(roundrect_rratio 0.25)
			(net 1 "GND")
			(pintype "passive")
		)
		(pad "2" smd roundrect
			(at 0.48 0 180)
			(size 0.59 0.64)
			(layers "B.Cu" "B.Mask" "B.Paste")
			(roundrect_rratio 0.25)
			(net 650 "+1V0")
			(pintype "passive")
		)
	)
	(footprint "antmicro-footprints:R_0402_1005Metric"
		(layer "B.Cu")
		(at 220.699999 77.899999 90)
		(descr "Resistor SMD 0402")
		(tags "resistor SMD 0402")
		(property "Reference" "R115"
			(at 3.599999 0.375001 270)
			(layer "B.SilkS")
			(effects
				(font
					(size 0.7 0.7)
					(thickness 0.15)
				)
				(justify left bottom mirror)
			)
		)
		(property "Value" "R_100R_0402"
			(at 0 -1.4 270)
			(layer "B.Fab")
			(effects
				(font
					(size 0.7 0.7)
					(thickness 0.15)
				)
				(justify left bottom mirror)
			)
		)
		(property "Description" "SMD Chip Resistor, 100 ohm, ± 1%, 62.5 mW, 0402 [1005 Metric], Thick Film, General Purpose"
			(at 0 0 90)
			(layer "F.Fab")
			(hide yes)
			(effects
				(font
					(size 1.27 1.27)
					(thickness 0.15)
				)
			)
		)
		(property "Author" "Antmicro"
			(at 298.599998 -142.8 0)
			(layer "B.Fab")
			(hide yes)
			(effects
				(font
					(size 1 1)
					(thickness 0.15)
				)
				(justify mirror)
			)
		)
		(property "License" "Apache-2.0"
			(at 298.599998 -142.8 0)
			(layer "B.Fab")
			(hide yes)
			(effects
				(font
					(size 1 1)
					(thickness 0.15)
				)
				(justify mirror)
			)
		)
		(property "MPN" "CR0402-FX-1000GLF"
			(at 298.599998 -142.8 0)
			(layer "B.Fab")
			(hide yes)
			(effects
				(font
					(size 1 1)
					(thickness 0.15)
				)
				(justify mirror)
			)
		)
		(property "Manufacturer" "Bourns"
			(at 298.599998 -142.8 0)
			(layer "B.Fab")
			(hide yes)
			(effects
				(font
					(size 1 1)
					(thickness 0.15)
				)
				(justify mirror)
			)
		)
		(property "Tolerance" "1%"
			(at 298.599998 -142.8 0)
			(layer "B.Fab")
			(hide yes)
			(effects
				(font
					(size 1 1)
					(thickness 0.15)
				)
				(justify mirror)
			)
		)
		(property "Val" "100R"
			(at 298.599998 -142.8 0)
			(layer "B.Fab")
			(hide yes)
			(effects
				(font
					(size 1 1)
					(thickness 0.15)
				)
				(justify mirror)
			)
		)
		(sheetname "User GPIO + LED + button + DIP switch")
		(sheetfile "user-gpio.kicad_sch")
		(attr smd)
		(fp_rect
			(start -0.925 0.47)
			(end 0.925 -0.47)
			(stroke
				(width 0.05)
				(type default)
			)
			(fill no)
			(layer "B.CrtYd")
		)
		(fp_rect
			(start -0.5 0.25)
			(end 0.5 -0.25)
			(stroke
				(width 0.15)
				(type solid)
			)
			(fill no)
			(layer "B.Fab")
		)
		(pad "1" smd roundrect
			(at -0.48 0 90)
			(size 0.59 0.64)
			(layers "B.Cu" "B.Mask" "B.Paste")
			(roundrect_rratio 0.25)
			(net 802 "/User GPIO + LED + button + DIP switch/PMOD_A_10")
			(pintype "passive")
		)
		(pad "2" smd roundrect
			(at 0.48 0 90)
			(size 0.59 0.64)
			(layers "B.Cu" "B.Mask" "B.Paste")
			(roundrect_rratio 0.25)
			(net 439 "/FPGA Bank 12 & 13/PMOD_A.IO10")
			(pintype "passive")
		)
	)
	(footprint "antmicro-footprints:R_0402_1005Metric"
		(layer "B.Cu")
		(at 195.691252 97.85 180)
		(descr "Resistor SMD 0402")
		(tags "resistor SMD 0402")
		(property "Reference" "R213"
			(at 0.716252 -0.425 0)
			(layer "B.SilkS")
			(effects
				(font
					(size 0.7 0.7)
					(thickness 0.15)
				)
				(justify left bottom mirror)
			)
		)
		(property "Value" "R_2k2_0402"
			(at 0 -1.4 0)
			(layer "B.Fab")
			(effects
				(font
					(size 0.7 0.7)
					(thickness 0.15)
				)
				(justify left bottom mirror)
			)
		)
		(property "Description" "SMD Chip Resistor, 2.2 kohm, ± 1%, 62.5 mW, 0402 [1005 Metric], Thick Film, General Purpose"
			(at 0 0 180)
			(layer "F.Fab")
			(hide yes)
			(effects
				(font
					(size 1.27 1.27)
					(thickness 0.15)
				)
			)
		)
		(property "Author" "Antmicro"
			(at 391.382504 195.7 0)
			(layer "B.Fab")
			(hide yes)
			(effects
				(font
					(size 1 1)
					(thickness 0.15)
				)
				(justify mirror)
			)
		)
		(property "License" "Apache-2.0"
			(at 391.382504 195.7 0)
			(layer "B.Fab")
			(hide yes)
			(effects
				(font
					(size 1 1)
					(thickness 0.15)
				)
				(justify mirror)
			)
		)
		(property "MPN" "CR0402-FX-2201GLF"
			(at 391.382504 195.7 0)
			(layer "B.Fab")
			(hide yes)
			(effects
				(font
					(size 1 1)
					(thickness 0.15)
				)
				(justify mirror)
			)
		)
		(property "Manufacturer" "Bourns"
			(at 391.382504 195.7 0)
			(layer "B.Fab")
			(hide yes)
			(effects
				(font
					(size 1 1)
					(thickness 0.15)
				)
				(justify mirror)
			)
		)
		(property "Tolerance" "1%"
			(at 391.382504 195.7 0)
			(layer "B.Fab")
			(hide yes)
			(effects
				(font
					(size 1 1)
					(thickness 0.15)
				)
				(justify mirror)
			)
		)
		(property "Val" "2k2"
			(at 391.382504 195.7 0)
			(layer "B.Fab")
			(hide yes)
			(effects
				(font
					(size 1 1)
					(thickness 0.15)
				)
				(justify mirror)
			)
		)
		(sheetname "HDMI + Ethernet")
		(sheetfile "hdmi-ethernet.kicad_sch")
		(attr smd)
		(fp_rect
			(start -0.925 0.47)
			(end 0.925 -0.47)
			(stroke
				(width 0.05)
				(type default)
			)
			(fill no)
			(layer "B.CrtYd")
		)
		(fp_rect
			(start -0.5 0.25)
			(end 0.5 -0.25)
			(stroke
				(width 0.15)
				(type solid)
			)
			(fill no)
			(layer "B.Fab")
		)
		(pad "1" smd roundrect
			(at -0.48 0 180)
			(size 0.59 0.64)
			(layers "B.Cu" "B.Mask" "B.Paste")
			(roundrect_rratio 0.25)
			(net 507 "/FPGA Bank 16 & 17/GBE_RGMII.GTR_CLK")
			(pintype "passive")
		)
		(pad "2" smd roundrect
			(at 0.48 0 180)
			(size 0.59 0.64)
			(layers "B.Cu" "B.Mask" "B.Paste")
			(roundrect_rratio 0.25)
			(net 1 "GND")
			(pintype "passive")
		)
	)
	(footprint "antmicro-footprints:R_Array_4x0201_Panasonic_EXB18V"
		(layer "B.Cu")
		(at 251.251 133.3 90)
		(property "Reference" "R63"
			(at -1.1 -0.701 270)
			(layer "B.SilkS")
			(effects
				(font
					(size 0.7 0.7)
					(thickness 0.15)
				)
				(justify right bottom mirror)
			)
		)
		(property "Value" "R_4x33R_0201_array"
			(at -1.1 -1.8 270)
			(layer "B.Fab")
			(effects
				(font
					(size 0.7 0.7)
					(thickness 0.15)
				)
				(justify left bottom mirror)
			)
		)
		(property "Description" "Fixed Network Resistor, 33 ohm, Isolated, 4 Resistors, 0502 [1406 Metric], Flat, ± 5%"
			(at 0 0 90)
			(layer "F.Fab")
			(hide yes)
			(effects
				(font
					(size 1.27 1.27)
					(thickness 0.15)
				)
			)
		)
		(property "Author" "Antmicro"
			(at 384.551 -117.951 0)
			(layer "B.Fab")
			(hide yes)
			(effects
				(font
					(size 1 1)
					(thickness 0.15)
				)
				(justify mirror)
			)
		)
		(property "License" "Apache-2.0"
			(at 384.551 -117.951 0)
			(layer "B.Fab")
			(hide yes)
			(effects
				(font
					(size 1 1)
					(thickness 0.15)
				)
				(justify mirror)
			)
		)
		(property "MPN" "EXB-18V330JX"
			(at 384.551 -117.951 0)
			(layer "B.Fab")
			(hide yes)
			(effects
				(font
					(size 1 1)
					(thickness 0.15)
				)
				(justify mirror)
			)
		)
		(property "Manufacturer" "Panasonic"
			(at 384.551 -117.951 0)
			(layer "B.Fab")
			(hide yes)
			(effects
				(font
					(size 1 1)
					(thickness 0.15)
				)
				(justify mirror)
			)
		)
		(property "Val" "R_4x33R_0201"
			(at 384.551 -117.951 0)
			(layer "B.Fab")
			(hide yes)
			(effects
				(font
					(size 1 1)
					(thickness 0.15)
				)
				(justify mirror)
			)
		)
		(sheetname "SPI Flash + SD Card")
		(sheetfile "spi-flash.kicad_sch")
		(attr smd)
		(fp_line
			(start 0.8 0.45)
			(end 0.8 -0.45)
			(stroke
				(width 0.12)
				(type solid)
			)
			(layer "B.SilkS")
		)
		(fp_line
			(start -0.8 0.45)
			(end -0.8 -0.45)
			(stroke
				(width 0.12)
				(type solid)
			)
			(layer "B.SilkS")
		)
		(fp_rect
			(start -0.898 0.66)
			(end 0.898 -0.65)
			(stroke
				(width 0.05)
				(type solid)
			)
			(fill no)
			(layer "B.CrtYd")
		)
		(pad "1" smd roundrect
			(at -0.6 -0.298 90)
			(size 0.2 0.4)
			(layers "B.Cu" "B.Mask" "B.Paste")
			(roundrect_rratio 0.25)
			(net 394 "/FPGA Bank 33 & 34/SD_CARD.CLK")
			(pinfunction "R1.1")
			(pintype "passive")
		)
		(pad "2" smd roundrect
			(at -0.202 -0.298 90)
			(size 0.2 0.4)
			(layers "B.Cu" "B.Mask" "B.Paste")
			(roundrect_rratio 0.25)
			(net 366 "unconnected-(R63-R2.1-Pad2)")
			(pinfunction "R2.1")
			(pintype "passive+no_connect")
		)
		(pad "3" smd roundrect
			(at 0.2 -0.298 90)
			(size 0.2 0.4)
			(layers "B.Cu" "B.Mask" "B.Paste")
			(roundrect_rratio 0.25)
			(net 395 "/FPGA Bank 33 & 34/SD_CARD.DAT0")
			(pinfunction "R3.1")
			(pintype "passive")
		)
		(pad "4" smd roundrect
			(at 0.598 -0.298 90)
			(size 0.2 0.4)
			(layers "B.Cu" "B.Mask" "B.Paste")
			(roundrect_rratio 0.25)
			(net 397 "/FPGA Bank 33 & 34/SD_CARD.DAT1")
			(pinfunction "R4.1")
			(pintype "passive")
		)
		(pad "5" smd roundrect
			(at 0.598 0.3 90)
			(size 0.2 0.4)
			(layers "B.Cu" "B.Mask" "B.Paste")
			(roundrect_rratio 0.25)
			(net 332 "Net-(J23-DAT1)")
			(pinfunction "R4.2")
			(pintype "passive")
		)
		(pad "6" smd roundrect
			(at 0.2 0.3 90)
			(size 0.2 0.4)
			(layers "B.Cu" "B.Mask" "B.Paste")
			(roundrect_rratio 0.25)
			(net 331 "Net-(J23-DAT0)")
			(pinfunction "R3.2")
			(pintype "passive")
		)
		(pad "7" smd roundrect
			(at -0.202 0.3 90)
			(size 0.2 0.4)
			(layers "B.Cu" "B.Mask" "B.Paste")
			(roundrect_rratio 0.25)
			(net 367 "unconnected-(R63-R2.2-Pad7)")
			(pinfunction "R2.2")
			(pintype "passive+no_connect")
		)
		(pad "8" smd roundrect
			(at -0.6 0.3 90)
			(size 0.2 0.4)
			(layers "B.Cu" "B.Mask" "B.Paste")
			(roundrect_rratio 0.25)
			(net 330 "Net-(J23-CLK)")
			(pinfunction "R1.2")
			(pintype "passive")
		)
	)
	(footprint "antmicro-footprints:R_0402_1005Metric"
		(layer "B.Cu")
		(at 225.626 148.201)
		(descr "Resistor SMD 0402")
		(tags "resistor SMD 0402")
		(property "Reference" "R220"
			(at 3.599 0.358 180)
			(layer "B.SilkS")
			(effects
				(font
					(size 0.7 0.7)
					(thickness 0.15)
				)
				(justify left bottom mirror)
			)
		)
		(property "Value" "R_10k_0402"
			(at 0 -1.4 180)
			(layer "B.Fab")
			(effects
				(font
					(size 0.7 0.7)
					(thickness 0.15)
				)
				(justify left bottom mirror)
			)
		)
		(property "Description" "SMD Chip Resistor, 10 kohm, ± 1%, 62.5 mW, 0402 [1005 Metric], Thick Film, General Purpose"
			(at 0 0 0)
			(layer "F.Fab")
			(hide yes)
			(effects
				(font
					(size 1.27 1.27)
					(thickness 0.15)
				)
			)
		)
		(property "Author" "Antmicro"
			(at 0 0 0)
			(layer "B.Fab")
			(hide yes)
			(effects
				(font
					(size 1 1)
					(thickness 0.15)
				)
				(justify mirror)
			)
		)
		(property "License" "Apache-2.0"
			(at 0 0 0)
			(layer "B.Fab")
			(hide yes)
			(effects
				(font
					(size 1 1)
					(thickness 0.15)
				)
				(justify mirror)
			)
		)
		(property "MPN" "CR0402-FX-1002GLF"
			(at 0 0 0)
			(layer "B.Fab")
			(hide yes)
			(effects
				(font
					(size 1 1)
					(thickness 0.15)
				)
				(justify mirror)
			)
		)
		(property "Manufacturer" "Bourns"
			(at 0 0 0)
			(layer "B.Fab")
			(hide yes)
			(effects
				(font
					(size 1 1)
					(thickness 0.15)
				)
				(justify mirror)
			)
		)
		(property "Tolerance" "1%"
			(at 0 0 0)
			(layer "B.Fab")
			(hide yes)
			(effects
				(font
					(size 1 1)
					(thickness 0.15)
				)
				(justify mirror)
			)
		)
		(property "Val" "10k"
			(at 0 0 0)
			(layer "B.Fab")
			(hide yes)
			(effects
				(font
					(size 1 1)
					(thickness 0.15)
				)
				(justify mirror)
			)
		)
		(sheetname "HDMI + Ethernet")
		(sheetfile "hdmi-ethernet.kicad_sch")
		(attr smd)
		(fp_rect
			(start -0.925 0.47)
			(end 0.925 -0.47)
			(stroke
				(width 0.05)
				(type default)
			)
			(fill no)
			(layer "B.CrtYd")
		)
		(fp_rect
			(start -0.5 0.25)
			(end 0.5 -0.25)
			(stroke
				(width 0.15)
				(type solid)
			)
			(fill no)
			(layer "B.Fab")
		)
		(pad "1" smd roundrect
			(at -0.48 0)
			(size 0.59 0.64)
			(layers "B.Cu" "B.Mask" "B.Paste")
			(roundrect_rratio 0.25)
			(net 945 "/HDMI + Ethernet/ETH_PHY_RXD1")
			(pintype "passive")
		)
		(pad "2" smd roundrect
			(at 0.48 0)
			(size 0.59 0.64)
			(layers "B.Cu" "B.Mask" "B.Paste")
			(roundrect_rratio 0.25)
			(net 26 "+1V8")
			(pintype "passive")
		)
	)
	(footprint "antmicro-footprints:R_0402_1005Metric"
		(layer "B.Cu")
		(at 185.500001 79.800001 90)
		(descr "Resistor SMD 0402")
		(tags "resistor SMD 0402")
		(property "Reference" "R142"
			(at -0.725 0.4 270)
			(layer "B.SilkS")
			(effects
				(font
					(size 0.7 0.7)
					(thickness 0.15)
				)
				(justify left bottom mirror)
			)
		)
		(property "Value" "R_100R_0402"
			(at 0 -1.4 270)
			(layer "B.Fab")
			(effects
				(font
					(size 0.7 0.7)
					(thickness 0.15)
				)
				(justify left bottom mirror)
			)
		)
		(property "Description" "SMD Chip Resistor, 100 ohm, ± 1%, 62.5 mW, 0402 [1005 Metric], Thick Film, General Purpose"
			(at 0 0 90)
			(layer "F.Fab")
			(hide yes)
			(effects
				(font
					(size 1.27 1.27)
					(thickness 0.15)
				)
			)
		)
		(property "Author" "Antmicro"
			(at 265.300002 -105.7 0)
			(layer "B.Fab")
			(hide yes)
			(effects
				(font
					(size 1 1)
					(thickness 0.15)
				)
				(justify mirror)
			)
		)
		(property "License" "Apache-2.0"
			(at 265.300002 -105.7 0)
			(layer "B.Fab")
			(hide yes)
			(effects
				(font
					(size 1 1)
					(thickness 0.15)
				)
				(justify mirror)
			)
		)
		(property "MPN" "CR0402-FX-1000GLF"
			(at 265.300002 -105.7 0)
			(layer "B.Fab")
			(hide yes)
			(effects
				(font
					(size 1 1)
					(thickness 0.15)
				)
				(justify mirror)
			)
		)
		(property "Manufacturer" "Bourns"
			(at 265.300002 -105.7 0)
			(layer "B.Fab")
			(hide yes)
			(effects
				(font
					(size 1 1)
					(thickness 0.15)
				)
				(justify mirror)
			)
		)
		(property "Tolerance" "1%"
			(at 265.300002 -105.7 0)
			(layer "B.Fab")
			(hide yes)
			(effects
				(font
					(size 1 1)
					(thickness 0.15)
				)
				(justify mirror)
			)
		)
		(property "Val" "100R"
			(at 265.300002 -105.7 0)
			(layer "B.Fab")
			(hide yes)
			(effects
				(font
					(size 1 1)
					(thickness 0.15)
				)
				(justify mirror)
			)
		)
		(sheetname "User GPIO + LED + button + DIP switch")
		(sheetfile "user-gpio.kicad_sch")
		(attr smd)
		(fp_rect
			(start -0.925 0.47)
			(end 0.925 -0.47)
			(stroke
				(width 0.05)
				(type default)
			)
			(fill no)
			(layer "B.CrtYd")
		)
		(fp_rect
			(start -0.5 0.25)
			(end 0.5 -0.25)
			(stroke
				(width 0.15)
				(type solid)
			)
			(fill no)
			(layer "B.Fab")
		)
		(pad "1" smd roundrect
			(at -0.48 0 90)
			(size 0.59 0.64)
			(layers "B.Cu" "B.Mask" "B.Paste")
			(roundrect_rratio 0.25)
			(net 487 "/FPGA Bank 12 & 13/CW_HEADER.HS1")
			(pintype "passive")
		)
		(pad "2" smd roundrect
			(at 0.48 0 90)
			(size 0.59 0.64)
			(layers "B.Cu" "B.Mask" "B.Paste")
			(roundrect_rratio 0.25)
			(net 822 "/User GPIO + LED + button + DIP switch/CW_20PIN_HS1")
			(pintype "passive")
		)
	)
	(footprint "antmicro-footprints:R_0402_1005Metric"
		(layer "B.Cu")
		(at 207.1 128.6)
		(descr "Resistor SMD 0402")
		(tags "resistor SMD 0402")
		(property "Reference" "R338"
			(at 3.675 0.375 180)
			(layer "B.SilkS")
			(effects
				(font
					(size 0.7 0.7)
					(thickness 0.15)
				)
				(justify left bottom mirror)
			)
		)
		(property "Value" "R_1k_0402"
			(at 0 -1.4 180)
			(layer "B.Fab")
			(effects
				(font
					(size 0.7 0.7)
					(thickness 0.15)
				)
				(justify left bottom mirror)
			)
		)
		(property "Description" "SMD Chip Resistor, 1 kohm, ± 1%, 63 mW, 0402 [1005 Metric], Thick Film, General Purpose"
			(at 0 0 0)
			(layer "F.Fab")
			(hide yes)
			(effects
				(font
					(size 1.27 1.27)
					(thickness 0.15)
				)
			)
		)
		(property "Author" "Antmicro"
			(at 0 0 0)
			(layer "B.Fab")
			(hide yes)
			(effects
				(font
					(size 1 1)
					(thickness 0.15)
				)
				(justify mirror)
			)
		)
		(property "License" "Apache-2.0"
			(at 0 0 0)
			(layer "B.Fab")
			(hide yes)
			(effects
				(font
					(size 1 1)
					(thickness 0.15)
				)
				(justify mirror)
			)
		)
		(property "MPN" "CR0402-FX-1001GLF"
			(at 0 0 0)
			(layer "B.Fab")
			(hide yes)
			(effects
				(font
					(size 1 1)
					(thickness 0.15)
				)
				(justify mirror)
			)
		)
		(property "Manufacturer" "Bourns"
			(at 0 0 0)
			(layer "B.Fab")
			(hide yes)
			(effects
				(font
					(size 1 1)
					(thickness 0.15)
				)
				(justify mirror)
			)
		)
		(property "Tolerance" "1%"
			(at 0 0 0)
			(layer "B.Fab")
			(hide yes)
			(effects
				(font
					(size 1 1)
					(thickness 0.15)
				)
				(justify mirror)
			)
		)
		(property "Val" "1k"
			(at 0 0 0)
			(layer "B.Fab")
			(hide yes)
			(effects
				(font
					(size 1 1)
					(thickness 0.15)
				)
				(justify mirror)
			)
		)
		(sheetname "FPGA Bank 14 & 15")
		(sheetfile "fpga-bank-14-15.kicad_sch")
		(attr smd)
		(fp_rect
			(start -0.925 0.47)
			(end 0.925 -0.47)
			(stroke
				(width 0.05)
				(type default)
			)
			(fill no)
			(layer "B.CrtYd")
		)
		(fp_rect
			(start -0.5 0.25)
			(end 0.5 -0.25)
			(stroke
				(width 0.15)
				(type solid)
			)
			(fill no)
			(layer "B.Fab")
		)
		(pad "1" smd roundrect
			(at -0.48 0)
			(size 0.59 0.64)
			(layers "B.Cu" "B.Mask" "B.Paste")
			(roundrect_rratio 0.25)
			(net 1 "GND")
			(pintype "passive")
		)
		(pad "2" smd roundrect
			(at 0.48 0)
			(size 0.59 0.64)
			(layers "B.Cu" "B.Mask" "B.Paste")
			(roundrect_rratio 0.25)
			(net 566 "/FPGA Bank 14 & 15/CFG_PUDC")
			(pintype "passive")
		)
	)
	(footprint "antmicro-footprints:R_Array_4x0201_Panasonic_EXB18V"
		(layer "B.Cu")
		(at 253.901 127.9)
		(property "Reference" "R23"
			(at 1.174 -0.725 0)
			(layer "B.SilkS")
			(effects
				(font
					(size 0.7 0.7)
					(thickness 0.15)
				)
				(justify left bottom mirror)
			)
		)
		(property "Value" "R_4x33R_0201_array"
			(at -1.1 -1.8 0)
			(layer "B.Fab")
			(effects
				(font
					(size 0.7 0.7)
					(thickness 0.15)
				)
				(justify right bottom mirror)
			)
		)
		(property "Description" "Fixed Network Resistor, 33 ohm, Isolated, 4 Resistors, 0502 [1406 Metric], Flat, ± 5%"
			(at 0 0 0)
			(layer "F.Fab")
			(hide yes)
			(effects
				(font
					(size 1.27 1.27)
					(thickness 0.15)
				)
			)
		)
		(property "Author" "Antmicro"
			(at 0 0 0)
			(layer "B.Fab")
			(hide yes)
			(effects
				(font
					(size 1 1)
					(thickness 0.15)
				)
				(justify mirror)
			)
		)
		(property "License" "Apache-2.0"
			(at 0 0 0)
			(layer "B.Fab")
			(hide yes)
			(effects
				(font
					(size 1 1)
					(thickness 0.15)
				)
				(justify mirror)
			)
		)
		(property "MPN" "EXB-18V330JX"
			(at 0 0 0)
			(layer "B.Fab")
			(hide yes)
			(effects
				(font
					(size 1 1)
					(thickness 0.15)
				)
				(justify mirror)
			)
		)
		(property "Manufacturer" "Panasonic"
			(at 0 0 0)
			(layer "B.Fab")
			(hide yes)
			(effects
				(font
					(size 1 1)
					(thickness 0.15)
				)
				(justify mirror)
			)
		)
		(property "Val" "R_4x33R_0201"
			(at 0 0 0)
			(layer "B.Fab")
			(hide yes)
			(effects
				(font
					(size 1 1)
					(thickness 0.15)
				)
				(justify mirror)
			)
		)
		(sheetname "Supervisior MCU")
		(sheetfile "supervisor-mcu.kicad_sch")
		(attr smd)
		(fp_line
			(start -0.8 0.45)
			(end -0.8 -0.45)
			(stroke
				(width 0.12)
				(type solid)
			)
			(layer "B.SilkS")
		)
		(fp_line
			(start 0.8 0.45)
			(end 0.8 -0.45)
			(stroke
				(width 0.12)
				(type solid)
			)
			(layer "B.SilkS")
		)
		(fp_rect
			(start -0.898 0.66)
			(end 0.898 -0.65)
			(stroke
				(width 0.05)
				(type solid)
			)
			(fill no)
			(layer "B.CrtYd")
		)
		(pad "1" smd roundrect
			(at -0.6 -0.298)
			(size 0.2 0.4)
			(layers "B.Cu" "B.Mask" "B.Paste")
			(roundrect_rratio 0.25)
			(net 1359 "/SUP_MCU.A5")
			(pinfunction "R1.1")
			(pintype "passive")
		)
		(pad "2" smd roundrect
			(at -0.202 -0.298)
			(size 0.2 0.4)
			(layers "B.Cu" "B.Mask" "B.Paste")
			(roundrect_rratio 0.25)
			(net 1360 "/SUP_MCU.A3")
			(pinfunction "R2.1")
			(pintype "passive")
		)
		(pad "3" smd roundrect
			(at 0.2 -0.298)
			(size 0.2 0.4)
			(layers "B.Cu" "B.Mask" "B.Paste")
			(roundrect_rratio 0.25)
			(net 1337 "/SUP_MCU.SDA")
			(pinfunction "R3.1")
			(pintype "passive")
		)
		(pad "4" smd roundrect
			(at 0.598 -0.298)
			(size 0.2 0.4)
			(layers "B.Cu" "B.Mask" "B.Paste")
			(roundrect_rratio 0.25)
			(net 1361 "/SUP_MCU.A4")
			(pinfunction "R4.1")
			(pintype "passive")
		)
		(pad "5" smd roundrect
			(at 0.598 0.3)
			(size 0.2 0.4)
			(layers "B.Cu" "B.Mask" "B.Paste")
			(roundrect_rratio 0.25)
			(net 1065 "/Supervisior MCU/USB_A4")
			(pinfunction "R4.2")
			(pintype "passive")
		)
		(pad "6" smd roundrect
			(at 0.2 0.3)
			(size 0.2 0.4)
			(layers "B.Cu" "B.Mask" "B.Paste")
			(roundrect_rratio 0.25)
			(net 1101 "/Supervisior MCU/SDA0")
			(pinfunction "R3.2")
			(pintype "passive")
		)
		(pad "7" smd roundrect
			(at -0.202 0.3)
			(size 0.2 0.4)
			(layers "B.Cu" "B.Mask" "B.Paste")
			(roundrect_rratio 0.25)
			(net 1064 "/Supervisior MCU/USB_A3")
			(pinfunction "R2.2")
			(pintype "passive")
		)
		(pad "8" smd roundrect
			(at -0.6 0.3)
			(size 0.2 0.4)
			(layers "B.Cu" "B.Mask" "B.Paste")
			(roundrect_rratio 0.25)
			(net 1066 "/Supervisior MCU/USB_A5")
			(pinfunction "R1.2")
			(pintype "passive")
		)
	)
	(footprint "antmicro-footprints:R_0402_1005Metric"
		(layer "B.Cu")
		(at 159.515001 82.635001)
		(descr "Resistor SMD 0402")
		(tags "resistor SMD 0402")
		(property "Reference" "R275"
			(at -0.765001 0.389999 180)
			(layer "B.SilkS")
			(effects
				(font
					(size 0.7 0.7)
					(thickness 0.15)
				)
				(justify left bottom mirror)
			)
		)
		(property "Value" "R_33R_0402"
			(at 0 -1.4 180)
			(layer "B.Fab")
			(effects
				(font
					(size 0.7 0.7)
					(thickness 0.15)
				)
				(justify left bottom mirror)
			)
		)
		(property "Description" "SMD Chip Resistor, 33 ohm, ± 1%, 62.5 mW, 0402 [1005 Metric], Thick Film, General Purpose"
			(at 0 0 0)
			(layer "F.Fab")
			(hide yes)
			(effects
				(font
					(size 1.27 1.27)
					(thickness 0.15)
				)
			)
		)
		(property "Author" "Antmicro"
			(at 0 0 0)
			(layer "B.Fab")
			(hide yes)
			(effects
				(font
					(size 1 1)
					(thickness 0.15)
				)
				(justify mirror)
			)
		)
		(property "License" "Apache-2.0"
			(at 0 0 0)
			(layer "B.Fab")
			(hide yes)
			(effects
				(font
					(size 1 1)
					(thickness 0.15)
				)
				(justify mirror)
			)
		)
		(property "MPN" "CR0402-FX-33R0GLF"
			(at 0 0 0)
			(layer "B.Fab")
			(hide yes)
			(effects
				(font
					(size 1 1)
					(thickness 0.15)
				)
				(justify mirror)
			)
		)
		(property "Manufacturer" "Bourns"
			(at 0 0 0)
			(layer "B.Fab")
			(hide yes)
			(effects
				(font
					(size 1 1)
					(thickness 0.15)
				)
				(justify mirror)
			)
		)
		(property "Tolerance" "1%"
			(at 0 0 0)
			(layer "B.Fab")
			(hide yes)
			(effects
				(font
					(size 1 1)
					(thickness 0.15)
				)
				(justify mirror)
			)
		)
		(property "Val" "33R"
			(at 0 0 0)
			(layer "B.Fab")
			(hide yes)
			(effects
				(font
					(size 1 1)
					(thickness 0.15)
				)
				(justify mirror)
			)
		)
		(sheetname "FMC+ HSPC")
		(sheetfile "fmc-hspc.kicad_sch")
		(attr smd)
		(fp_rect
			(start -0.925 0.47)
			(end 0.925 -0.47)
			(stroke
				(width 0.05)
				(type default)
			)
			(fill no)
			(layer "B.CrtYd")
		)
		(fp_rect
			(start -0.5 0.25)
			(end 0.5 -0.25)
			(stroke
				(width 0.15)
				(type solid)
			)
			(fill no)
			(layer "B.Fab")
		)
		(pad "1" smd roundrect
			(at -0.48 0)
			(size 0.59 0.64)
			(layers "B.Cu" "B.Mask" "B.Paste")
			(roundrect_rratio 0.25)
			(net 597 "/FMC+ HSPC/GTR_REFCLK3_R_P")
			(pintype "passive")
		)
		(pad "2" smd roundrect
			(at 0.48 0)
			(size 0.59 0.64)
			(layers "B.Cu" "B.Mask" "B.Paste")
			(roundrect_rratio 0.25)
			(net 598 "/FMC+ HSPC/GTX116.REFCLK1_P")
			(pintype "passive")
		)
	)
	(footprint "antmicro-footprints:R_0402_1005Metric"
		(layer "B.Cu")
		(at 245.299999 84.599999 -90)
		(descr "Resistor SMD 0402")
		(tags "resistor SMD 0402")
		(property "Reference" "R119"
			(at 0.800001 -0.450001 90)
			(layer "B.SilkS")
			(effects
				(font
					(size 0.7 0.7)
					(thickness 0.15)
				)
				(justify left bottom mirror)
			)
		)
		(property "Value" "R_100R_0402"
			(at 0 -1.4 90)
			(layer "B.Fab")
			(effects
				(font
					(size 0.7 0.7)
					(thickness 0.15)
				)
				(justify left bottom mirror)
			)
		)
		(property "Description" "SMD Chip Resistor, 100 ohm, ± 1%, 62.5 mW, 0402 [1005 Metric], Thick Film, General Purpose"
			(at 0 0 270)
			(layer "F.Fab")
			(hide yes)
			(effects
				(font
					(size 1.27 1.27)
					(thickness 0.15)
				)
			)
		)
		(property "Author" "Antmicro"
			(at 160.7 329.899998 0)
			(layer "B.Fab")
			(hide yes)
			(effects
				(font
					(size 1 1)
					(thickness 0.15)
				)
				(justify mirror)
			)
		)
		(property "License" "Apache-2.0"
			(at 160.7 329.899998 0)
			(layer "B.Fab")
			(hide yes)
			(effects
				(font
					(size 1 1)
					(thickness 0.15)
				)
				(justify mirror)
			)
		)
		(property "MPN" "CR0402-FX-1000GLF"
			(at 160.7 329.899998 0)
			(layer "B.Fab")
			(hide yes)
			(effects
				(font
					(size 1 1)
					(thickness 0.15)
				)
				(justify mirror)
			)
		)
		(property "Manufacturer" "Bourns"
			(at 160.7 329.899998 0)
			(layer "B.Fab")
			(hide yes)
			(effects
				(font
					(size 1 1)
					(thickness 0.15)
				)
				(justify mirror)
			)
		)
		(property "Tolerance" "1%"
			(at 160.7 329.899998 0)
			(layer "B.Fab")
			(hide yes)
			(effects
				(font
					(size 1 1)
					(thickness 0.15)
				)
				(justify mirror)
			)
		)
		(property "Val" "100R"
			(at 160.7 329.899998 0)
			(layer "B.Fab")
			(hide yes)
			(effects
				(font
					(size 1 1)
					(thickness 0.15)
				)
				(justify mirror)
			)
		)
		(sheetname "User GPIO + LED + button + DIP switch")
		(sheetfile "user-gpio.kicad_sch")
		(attr smd)
		(fp_rect
			(start -0.925 0.47)
			(end 0.925 -0.47)
			(stroke
				(width 0.05)
				(type default)
			)
			(fill no)
			(layer "B.CrtYd")
		)
		(fp_rect
			(start -0.5 0.25)
			(end 0.5 -0.25)
			(stroke
				(width 0.15)
				(type solid)
			)
			(fill no)
			(layer "B.Fab")
		)
		(pad "1" smd roundrect
			(at -0.48 0 270)
			(size 0.59 0.64)
			(layers "B.Cu" "B.Mask" "B.Paste")
			(roundrect_rratio 0.25)
			(net 810 "/User GPIO + LED + button + DIP switch/PMOD_B_10")
			(pintype "passive")
		)
		(pad "2" smd roundrect
			(at 0.48 0 270)
			(size 0.59 0.64)
			(layers "B.Cu" "B.Mask" "B.Paste")
			(roundrect_rratio 0.25)
			(net 453 "/FPGA Bank 12 & 13/PMOD_B.IO10")
			(pintype "passive")
		)
	)
	(footprint "antmicro-footprints:R_0402_1005Metric"
		(layer "B.Cu")
		(at 215.499999 77.899999 90)
		(descr "Resistor SMD 0402")
		(tags "resistor SMD 0402")
		(property "Reference" "R113"
			(at 3.599999 0.350001 270)
			(layer "B.SilkS")
			(effects
				(font
					(size 0.7 0.7)
					(thickness 0.15)
				)
				(justify left bottom mirror)
			)
		)
		(property "Value" "R_100R_0402"
			(at 0 -1.4 270)
			(layer "B.Fab")
			(effects
				(font
					(size 0.7 0.7)
					(thickness 0.15)
				)
				(justify left bottom mirror)
			)
		)
		(property "Description" "SMD Chip Resistor, 100 ohm, ± 1%, 62.5 mW, 0402 [1005 Metric], Thick Film, General Purpose"
			(at 0 0 90)
			(layer "F.Fab")
			(hide yes)
			(effects
				(font
					(size 1.27 1.27)
					(thickness 0.15)
				)
			)
		)
		(property "Author" "Antmicro"
			(at 293.399998 -137.6 0)
			(layer "B.Fab")
			(hide yes)
			(effects
				(font
					(size 1 1)
					(thickness 0.15)
				)
				(justify mirror)
			)
		)
		(property "License" "Apache-2.0"
			(at 293.399998 -137.6 0)
			(layer "B.Fab")
			(hide yes)
			(effects
				(font
					(size 1 1)
					(thickness 0.15)
				)
				(justify mirror)
			)
		)
		(property "MPN" "CR0402-FX-1000GLF"
			(at 293.399998 -137.6 0)
			(layer "B.Fab")
			(hide yes)
			(effects
				(font
					(size 1 1)
					(thickness 0.15)
				)
				(justify mirror)
			)
		)
		(property "Manufacturer" "Bourns"
			(at 293.399998 -137.6 0)
			(layer "B.Fab")
			(hide yes)
			(effects
				(font
					(size 1 1)
					(thickness 0.15)
				)
				(justify mirror)
			)
		)
		(property "Tolerance" "1%"
			(at 293.399998 -137.6 0)
			(layer "B.Fab")
			(hide yes)
			(effects
				(font
					(size 1 1)
					(thickness 0.15)
				)
				(justify mirror)
			)
		)
		(property "Val" "100R"
			(at 293.399998 -137.6 0)
			(layer "B.Fab")
			(hide yes)
			(effects
				(font
					(size 1 1)
					(thickness 0.15)
				)
				(justify mirror)
			)
		)
		(sheetname "User GPIO + LED + button + DIP switch")
		(sheetfile "user-gpio.kicad_sch")
		(attr smd)
		(fp_rect
			(start -0.925 0.47)
			(end 0.925 -0.47)
			(stroke
				(width 0.05)
				(type default)
			)
			(fill no)
			(layer "B.CrtYd")
		)
		(fp_rect
			(start -0.5 0.25)
			(end 0.5 -0.25)
			(stroke
				(width 0.15)
				(type solid)
			)
			(fill no)
			(layer "B.Fab")
		)
		(pad "1" smd roundrect
			(at -0.48 0 90)
			(size 0.59 0.64)
			(layers "B.Cu" "B.Mask" "B.Paste")
			(roundrect_rratio 0.25)
			(net 806 "/User GPIO + LED + button + DIP switch/PMOD_A_8")
			(pintype "passive")
		)
		(pad "2" smd roundrect
			(at 0.48 0 90)
			(size 0.59 0.64)
			(layers "B.Cu" "B.Mask" "B.Paste")
			(roundrect_rratio 0.25)
			(net 434 "/FPGA Bank 12 & 13/PMOD_A.IO8")
			(pintype "passive")
		)
	)
	(footprint "antmicro-footprints:R_0402_1005Metric"
		(layer "B.Cu")
		(at 198.491252 95.55)
		(descr "Resistor SMD 0402")
		(tags "resistor SMD 0402")
		(property "Reference" "R217"
			(at 1.483748 -4.6 180)
			(layer "B.SilkS")
			(effects
				(font
					(size 0.7 0.7)
					(thickness 0.15)
				)
				(justify left bottom mirror)
			)
		)
		(property "Value" "R_2k2_0402"
			(at 0 -1.4 180)
			(layer "B.Fab")
			(effects
				(font
					(size 0.7 0.7)
					(thickness 0.15)
				)
				(justify left bottom mirror)
			)
		)
		(property "Description" "SMD Chip Resistor, 2.2 kohm, ± 1%, 62.5 mW, 0402 [1005 Metric], Thick Film, General Purpose"
			(at 0 0 0)
			(layer "F.Fab")
			(hide yes)
			(effects
				(font
					(size 1.27 1.27)
					(thickness 0.15)
				)
			)
		)
		(property "Author" "Antmicro"
			(at 0 0 0)
			(layer "B.Fab")
			(hide yes)
			(effects
				(font
					(size 1 1)
					(thickness 0.15)
				)
				(justify mirror)
			)
		)
		(property "License" "Apache-2.0"
			(at 0 0 0)
			(layer "B.Fab")
			(hide yes)
			(effects
				(font
					(size 1 1)
					(thickness 0.15)
				)
				(justify mirror)
			)
		)
		(property "MPN" "CR0402-FX-2201GLF"
			(at 0 0 0)
			(layer "B.Fab")
			(hide yes)
			(effects
				(font
					(size 1 1)
					(thickness 0.15)
				)
				(justify mirror)
			)
		)
		(property "Manufacturer" "Bourns"
			(at 0 0 0)
			(layer "B.Fab")
			(hide yes)
			(effects
				(font
					(size 1 1)
					(thickness 0.15)
				)
				(justify mirror)
			)
		)
		(property "Tolerance" "1%"
			(at 0 0 0)
			(layer "B.Fab")
			(hide yes)
			(effects
				(font
					(size 1 1)
					(thickness 0.15)
				)
				(justify mirror)
			)
		)
		(property "Val" "2k2"
			(at 0 0 0)
			(layer "B.Fab")
			(hide yes)
			(effects
				(font
					(size 1 1)
					(thickness 0.15)
				)
				(justify mirror)
			)
		)
		(sheetname "HDMI + Ethernet")
		(sheetfile "hdmi-ethernet.kicad_sch")
		(attr smd)
		(fp_rect
			(start -0.925 0.47)
			(end 0.925 -0.47)
			(stroke
				(width 0.05)
				(type default)
			)
			(fill no)
			(layer "B.CrtYd")
		)
		(fp_rect
			(start -0.5 0.25)
			(end 0.5 -0.25)
			(stroke
				(width 0.15)
				(type solid)
			)
			(fill no)
			(layer "B.Fab")
		)
		(pad "1" smd roundrect
			(at -0.48 0)
			(size 0.59 0.64)
			(layers "B.Cu" "B.Mask" "B.Paste")
			(roundrect_rratio 0.25)
			(net 509 "/FPGA Bank 16 & 17/GBE_RGMII.RX_DV")
			(pintype "passive")
		)
		(pad "2" smd roundrect
			(at 0.48 0)
			(size 0.59 0.64)
			(layers "B.Cu" "B.Mask" "B.Paste")
			(roundrect_rratio 0.25)
			(net 1 "GND")
			(pintype "passive")
		)
	)
	(footprint "antmicro-footprints:C_0402_1005Metric"
		(layer "B.Cu")
		(at 185.05 144.999999)
		(descr "Capacitor SMD 0402")
		(tags "capacitor SMD 0402")
		(property "Reference" "C96"
			(at 1.1 1.225001 180)
			(layer "B.SilkS")
			(effects
				(font
					(size 0.7 0.7)
					(thickness 0.15)
				)
				(justify left bottom mirror)
			)
		)
		(property "Value" "C_100n_0402"
			(at 0 -1.169 180)
			(layer "B.Fab")
			(effects
				(font
					(size 0.7 0.7)
					(thickness 0.15)
				)
				(justify left bottom mirror)
			)
		)
		(property "Description" "SMD Multilayer Ceramic Capacitor, 0.1 µF, 50 V, 0402 [1005 Metric], ± 10%, X5R, GRM Series"
			(at 0 0 0)
			(layer "F.Fab")
			(hide yes)
			(effects
				(font
					(size 1.27 1.27)
					(thickness 0.15)
				)
			)
		)
		(property "Author" "Antmicro"
			(at 0 0 0)
			(layer "B.Fab")
			(hide yes)
			(effects
				(font
					(size 1 1)
					(thickness 0.15)
				)
				(justify mirror)
			)
		)
		(property "Dielectric" "X5R"
			(at 0 0 0)
			(layer "B.Fab")
			(hide yes)
			(effects
				(font
					(size 1 1)
					(thickness 0.15)
				)
				(justify mirror)
			)
		)
		(property "License" "Apache-2.0"
			(at 0 0 0)
			(layer "B.Fab")
			(hide yes)
			(effects
				(font
					(size 1 1)
					(thickness 0.15)
				)
				(justify mirror)
			)
		)
		(property "MPN" "GRM155R61H104KE14D"
			(at 0 0 0)
			(layer "B.Fab")
			(hide yes)
			(effects
				(font
					(size 1 1)
					(thickness 0.15)
				)
				(justify mirror)
			)
		)
		(property "Manufacturer" "Murata"
			(at 0 0 0)
			(layer "B.Fab")
			(hide yes)
			(effects
				(font
					(size 1 1)
					(thickness 0.15)
				)
				(justify mirror)
			)
		)
		(property "Val" "100n"
			(at 0 0 0)
			(layer "B.Fab")
			(hide yes)
			(effects
				(font
					(size 1 1)
					(thickness 0.15)
				)
				(justify mirror)
			)
		)
		(property "Voltage" "50V"
			(at 0 0 0)
			(layer "B.Fab")
			(hide yes)
			(effects
				(font
					(size 1 1)
					(thickness 0.15)
				)
				(justify mirror)
			)
		)
		(sheetname "FPGA Bank 33 & 34")
		(sheetfile "fpga-bank-33-34.kicad_sch")
		(attr smd)
		(fp_rect
			(start -0.925 0.47)
			(end 0.925 -0.47)
			(stroke
				(width 0.05)
				(type default)
			)
			(fill no)
			(layer "B.CrtYd")
		)
		(fp_line
			(start -0.494 -0.248)
			(end -0.494 0.25)
			(stroke
				(width 0.15)
				(type solid)
			)
			(layer "B.Fab")
		)
		(fp_line
			(start -0.494 0.25)
			(end 0.504 0.25)
			(stroke
				(width 0.15)
				(type solid)
			)
			(layer "B.Fab")
		)
		(fp_line
			(start 0.504 -0.248)
			(end -0.494 -0.248)
			(stroke
				(width 0.15)
				(type solid)
			)
			(layer "B.Fab")
		)
		(fp_line
			(start 0.504 0.25)
			(end 0.504 -0.248)
			(stroke
				(width 0.15)
				(type solid)
			)
			(layer "B.Fab")
		)
		(pad "1" smd roundrect
			(at -0.48 0)
			(size 0.59 0.64)
			(layers "B.Cu" "B.Mask" "B.Paste")
			(roundrect_rratio 0.25)
			(net 1 "GND")
			(pintype "passive")
		)
		(pad "2" smd roundrect
			(at 0.48 0)
			(size 0.59 0.64)
			(layers "B.Cu" "B.Mask" "B.Paste")
			(roundrect_rratio 0.25)
			(net 25 "+1V35")
			(pintype "passive")
		)
	)
	(footprint "antmicro-footprints:C_0201"
		(layer "B.Cu")
		(at 189.8 127.5 180)
		(descr "Capacitor SMD 0201")
		(tags "capacitor SMD 0201")
		(property "Reference" "C156"
			(at 0.5 -0.375 0)
			(layer "B.SilkS")
			(effects
				(font
					(size 0.7 0.7)
					(thickness 0.15)
				)
				(justify left bottom mirror)
			)
		)
		(property "Value" "C_100n_0201"
			(at 0 -1.4 0)
			(layer "B.Fab")
			(effects
				(font
					(size 0.7 0.7)
					(thickness 0.15)
				)
				(justify left bottom mirror)
			)
		)
		(property "Description" "SMD Multilayer Ceramic Capacitor, 0.1 µF, 6.3 V, 0201 [0603 Metric], ± 10%, X6S, CC Series"
			(at 0 0 180)
			(layer "F.Fab")
			(hide yes)
			(effects
				(font
					(size 1.27 1.27)
					(thickness 0.15)
				)
			)
		)
		(property "Author" "Antmicro"
			(at 379.6 255 0)
			(layer "B.Fab")
			(hide yes)
			(effects
				(font
					(size 1 1)
					(thickness 0.15)
				)
				(justify mirror)
			)
		)
		(property "Dielectric" ""
			(at 379.6 255 0)
			(layer "B.Fab")
			(hide yes)
			(effects
				(font
					(size 1 1)
					(thickness 0.15)
				)
				(justify mirror)
			)
		)
		(property "License" "Apache-2.0"
			(at 379.6 255 0)
			(layer "B.Fab")
			(hide yes)
			(effects
				(font
					(size 1 1)
					(thickness 0.15)
				)
				(justify mirror)
			)
		)
		(property "MPN" "CC0201KRX6S5BB104"
			(at 379.6 255 0)
			(layer "B.Fab")
			(hide yes)
			(effects
				(font
					(size 1 1)
					(thickness 0.15)
				)
				(justify mirror)
			)
		)
		(property "Manufacturer" "YAGEO"
			(at 379.6 255 0)
			(layer "B.Fab")
			(hide yes)
			(effects
				(font
					(size 1 1)
					(thickness 0.15)
				)
				(justify mirror)
			)
		)
		(property "Val" "100n"
			(at 379.6 255 0)
			(layer "B.Fab")
			(hide yes)
			(effects
				(font
					(size 1 1)
					(thickness 0.15)
				)
				(justify mirror)
			)
		)
		(property "Voltage" ""
			(at 379.6 255 0)
			(layer "B.Fab")
			(hide yes)
			(effects
				(font
					(size 1 1)
					(thickness 0.15)
				)
				(justify mirror)
			)
		)
		(sheetname "FPGA supply")
		(sheetfile "fpga-supply.kicad_sch")
		(attr smd)
		(fp_rect
			(start -0.7 0.35)
			(end 0.7 -0.35)
			(stroke
				(width 0.05)
				(type default)
			)
			(fill no)
			(layer "B.CrtYd")
		)
		(fp_rect
			(start 0.3 -0.15)
			(end -0.301 0.149)
			(stroke
				(width 0.15)
				(type solid)
			)
			(fill no)
			(layer "B.Fab")
		)
		(pad "" smd roundrect
			(at -0.349 0.002 180)
			(size 0.318 0.36)
			(layers "B.Paste")
			(roundrect_rratio 0.25)
		)
		(pad "" smd roundrect
			(at 0.341 0.002 180)
			(size 0.318 0.36)
			(layers "B.Paste")
			(roundrect_rratio 0.25)
		)
		(pad "1" smd roundrect
			(at -0.321 0.002 180)
			(size 0.46 0.4)
			(layers "B.Cu" "B.Mask")
			(roundrect_rratio 0.25)
			(net 1 "GND")
			(pintype "passive")
		)
		(pad "2" smd roundrect
			(at 0.32 0.002 180)
			(size 0.46 0.4)
			(layers "B.Cu" "B.Mask")
			(roundrect_rratio 0.25)
			(net 8 "+1V2_MGTAVTT")
			(pintype "passive")
		)
	)
	(footprint "antmicro-footprints:C_0603_1608Metric"
		(layer "B.Cu")
		(at 212.85 130 180)
		(descr "Capacitor SMD 0603")
		(tags "capacitor 0603")
		(property "Reference" "C4"
			(at -0.21 -1.42 0)
			(layer "B.SilkS")
			(effects
				(font
					(size 0.7 0.7)
					(thickness 0.15)
				)
				(justify left bottom mirror)
			)
		)
		(property "Value" "C_47u_0603"
			(at 0 -1.6 0)
			(layer "B.Fab")
			(effects
				(font
					(size 0.7 0.7)
					(thickness 0.15)
				)
				(justify left bottom mirror)
			)
		)
		(property "Description" "SMD Multilayer Ceramic Capacitor, 47 µF, 6.3 V, 0603 [1608 Metric], ± 20%, X5R, GRM Series"
			(at 0 0 180)
			(layer "F.Fab")
			(hide yes)
			(effects
				(font
					(size 1.27 1.27)
					(thickness 0.15)
				)
			)
		)
		(property "Author" "Antmicro"
			(at 425.7 260 0)
			(layer "B.Fab")
			(hide yes)
			(effects
				(font
					(size 1 1)
					(thickness 0.15)
				)
				(justify mirror)
			)
		)
		(property "Dielectric" ""
			(at 425.7 260 0)
			(layer "B.Fab")
			(hide yes)
			(effects
				(font
					(size 1 1)
					(thickness 0.15)
				)
				(justify mirror)
			)
		)
		(property "License" "Apache-2.0"
			(at 425.7 260 0)
			(layer "B.Fab")
			(hide yes)
			(effects
				(font
					(size 1 1)
					(thickness 0.15)
				)
				(justify mirror)
			)
		)
		(property "MPN" "GRM188R60J476ME15D"
			(at 425.7 260 0)
			(layer "B.Fab")
			(hide yes)
			(effects
				(font
					(size 1 1)
					(thickness 0.15)
				)
				(justify mirror)
			)
		)
		(property "Manufacturer" "Murata"
			(at 425.7 260 0)
			(layer "B.Fab")
			(hide yes)
			(effects
				(font
					(size 1 1)
					(thickness 0.15)
				)
				(justify mirror)
			)
		)
		(property "Val" "47u"
			(at 425.7 260 0)
			(layer "B.Fab")
			(hide yes)
			(effects
				(font
					(size 1 1)
					(thickness 0.15)
				)
				(justify mirror)
			)
		)
		(property "Voltage" ""
			(at 425.7 260 0)
			(layer "B.Fab")
			(hide yes)
			(effects
				(font
					(size 1 1)
					(thickness 0.15)
				)
				(justify mirror)
			)
		)
		(sheetname "FPGA Bank 12 & 13")
		(sheetfile "fpga-bank-12-13.kicad_sch")
		(attr smd)
		(fp_line
			(start -0.15 0.4)
			(end 0.15 0.4)
			(stroke
				(width 0.15)
				(type solid)
			)
			(layer "B.SilkS")
		)
		(fp_line
			(start -0.15 -0.4)
			(end 0.15 -0.4)
			(stroke
				(width 0.15)
				(type solid)
			)
			(layer "B.SilkS")
		)
		(fp_rect
			(start -1.25 0.65)
			(end 1.25 -0.65)
			(stroke
				(width 0.05)
				(type solid)
			)
			(fill no)
			(layer "B.CrtYd")
		)
		(fp_rect
			(start -0.8 0.4)
			(end 0.8 -0.4)
			(stroke
				(width 0.15)
				(type solid)
			)
			(fill no)
			(layer "B.Fab")
		)
		(pad "1" smd roundrect
			(at -0.7 0 180)
			(size 0.8 1)
			(layers "B.Cu" "B.Mask" "B.Paste")
			(roundrect_rratio 0.2)
			(net 1 "GND")
			(pintype "passive")
		)
		(pad "2" smd roundrect
			(at 0.7 0 180)
			(size 0.8 1)
			(layers "B.Cu" "B.Mask" "B.Paste")
			(roundrect_rratio 0.2)
			(net 24 "+3V3")
			(pintype "passive")
		)
	)
	(footprint "antmicro-footprints:R_0402_1005Metric"
		(layer "B.Cu")
		(at 246.351 130.1 90)
		(descr "Resistor SMD 0402")
		(tags "resistor SMD 0402")
		(property "Reference" "R90"
			(at -0.8 0.374 270)
			(layer "B.SilkS")
			(effects
				(font
					(size 0.7 0.7)
					(thickness 0.15)
				)
				(justify left bottom mirror)
			)
		)
		(property "Value" "R_10k_0402"
			(at 0 -1.4 270)
			(layer "B.Fab")
			(effects
				(font
					(size 0.7 0.7)
					(thickness 0.15)
				)
				(justify left bottom mirror)
			)
		)
		(property "Description" "SMD Chip Resistor, 10 kohm, ± 1%, 62.5 mW, 0402 [1005 Metric], Thick Film, General Purpose"
			(at 0 0 90)
			(layer "F.Fab")
			(hide yes)
			(effects
				(font
					(size 1.27 1.27)
					(thickness 0.15)
				)
			)
		)
		(property "Author" "Antmicro"
			(at 376.451 -116.251 0)
			(layer "B.Fab")
			(hide yes)
			(effects
				(font
					(size 1 1)
					(thickness 0.15)
				)
				(justify mirror)
			)
		)
		(property "License" "Apache-2.0"
			(at 376.451 -116.251 0)
			(layer "B.Fab")
			(hide yes)
			(effects
				(font
					(size 1 1)
					(thickness 0.15)
				)
				(justify mirror)
			)
		)
		(property "MPN" "CR0402-FX-1002GLF"
			(at 376.451 -116.251 0)
			(layer "B.Fab")
			(hide yes)
			(effects
				(font
					(size 1 1)
					(thickness 0.15)
				)
				(justify mirror)
			)
		)
		(property "Manufacturer" "Bourns"
			(at 376.451 -116.251 0)
			(layer "B.Fab")
			(hide yes)
			(effects
				(font
					(size 1 1)
					(thickness 0.15)
				)
				(justify mirror)
			)
		)
		(property "Tolerance" "1%"
			(at 376.451 -116.251 0)
			(layer "B.Fab")
			(hide yes)
			(effects
				(font
					(size 1 1)
					(thickness 0.15)
				)
				(justify mirror)
			)
		)
		(property "Val" "10k"
			(at 376.451 -116.251 0)
			(layer "B.Fab")
			(hide yes)
			(effects
				(font
					(size 1 1)
					(thickness 0.15)
				)
				(justify mirror)
			)
		)
		(sheetname "SPI Flash + SD Card")
		(sheetfile "spi-flash.kicad_sch")
		(attr smd)
		(fp_rect
			(start -0.925 0.47)
			(end 0.925 -0.47)
			(stroke
				(width 0.05)
				(type default)
			)
			(fill no)
			(layer "B.CrtYd")
		)
		(fp_rect
			(start -0.5 0.25)
			(end 0.5 -0.25)
			(stroke
				(width 0.15)
				(type solid)
			)
			(fill no)
			(layer "B.Fab")
		)
		(pad "1" smd roundrect
			(at -0.48 0 90)
			(size 0.59 0.64)
			(layers "B.Cu" "B.Mask" "B.Paste")
			(roundrect_rratio 0.25)
			(net 395 "/FPGA Bank 33 & 34/SD_CARD.DAT0")
			(pintype "passive")
		)
		(pad "2" smd roundrect
			(at 0.48 0 90)
			(size 0.59 0.64)
			(layers "B.Cu" "B.Mask" "B.Paste")
			(roundrect_rratio 0.25)
			(net 24 "+3V3")
			(pintype "passive")
		)
	)
	(footprint "antmicro-footprints:QFN-2L_1.6x1x0.55mm"
		(layer "B.Cu")
		(at 264.75 84 90)
		(property "Reference" "D34"
			(at -2.1 -0.85 90)
			(layer "B.SilkS")
			(effects
				(font
					(size 0.7 0.7)
					(thickness 0.15)
				)
				(justify right bottom mirror)
			)
		)
		(property "Value" "ESDA25P35-1U1M"
			(at 0 -1.7 90)
			(layer "B.Fab")
			(effects
				(font
					(size 0.7 0.7)
					(thickness 0.15)
				)
				(justify right bottom mirror)
			)
		)
		(property "Description" "Unidirectional TVS, 30 kV, QFN-2L, 22 V, 195 pF"
			(at 0 0 90)
			(layer "F.Fab")
			(hide yes)
			(effects
				(font
					(size 1.27 1.27)
					(thickness 0.15)
				)
			)
		)
		(property "Author" "Antmicro"
			(at 348.75 -180.75 0)
			(layer "B.Fab")
			(hide yes)
			(effects
				(font
					(size 1 1)
					(thickness 0.15)
				)
				(justify mirror)
			)
		)
		(property "License" "Apache-2.0"
			(at 348.75 -180.75 0)
			(layer "B.Fab")
			(hide yes)
			(effects
				(font
					(size 1 1)
					(thickness 0.15)
				)
				(justify mirror)
			)
		)
		(property "MPN" "ESDA25P35-1U1M"
			(at 348.75 -180.75 0)
			(layer "B.Fab")
			(hide yes)
			(effects
				(font
					(size 1 1)
					(thickness 0.15)
				)
				(justify mirror)
			)
		)
		(property "Manufacturer" "STMicroelectronics"
			(at 348.75 -180.75 0)
			(layer "B.Fab")
			(hide yes)
			(effects
				(font
					(size 1 1)
					(thickness 0.15)
				)
				(justify mirror)
			)
		)
		(property "Public" "False"
			(at 348.75 -180.75 0)
			(layer "B.Fab")
			(hide yes)
			(effects
				(font
					(size 1 1)
					(thickness 0.15)
				)
				(justify mirror)
			)
		)
		(sheetname "User GPIO + LED + button + DIP switch")
		(sheetfile "user-gpio.kicad_sch")
		(attr smd)
		(fp_line
			(start 0.27 -0.3)
			(end -0.27 -0.3)
			(stroke
				(width 0.15)
				(type solid)
			)
			(layer "B.SilkS")
		)
		(fp_line
			(start 0.27 0.3)
			(end -0.27 0.3)
			(stroke
				(width 0.15)
				(type solid)
			)
			(layer "B.SilkS")
		)
		(fp_line
			(start -1.2 0.4)
			(end -1.2 -0.4)
			(stroke
				(width 0.15)
				(type solid)
			)
			(layer "B.SilkS")
		)
		(fp_rect
			(start 1.25 -0.65)
			(end -1.25 0.65)
			(stroke
				(width 0.05)
				(type solid)
			)
			(fill no)
			(layer "B.CrtYd")
		)
		(fp_line
			(start 0.201 -0.2)
			(end 0.201 0)
			(stroke
				(width 0.15)
				(type solid)
			)
			(layer "B.Fab")
		)
		(fp_line
			(start -0.199 -0.2)
			(end -0.199 -0.1)
			(stroke
				(width 0.15)
				(type solid)
			)
			(layer "B.Fab")
		)
		(fp_line
			(start 0.599 0)
			(end 0.201 0)
			(stroke
				(width 0.15)
				(type solid)
			)
			(layer "B.Fab")
		)
		(fp_line
			(start 0.201 0)
			(end 0.201 0.202)
			(stroke
				(width 0.15)
				(type solid)
			)
			(layer "B.Fab")
		)
		(fp_line
			(start -0.101 0)
			(end 0.201 -0.2)
			(stroke
				(width 0.15)
				(type solid)
			)
			(layer "B.Fab")
		)
		(fp_line
			(start -0.199 0)
			(end -0.597 0)
			(stroke
				(width 0.15)
				(type solid)
			)
			(layer "B.Fab")
		)
		(fp_line
			(start 0.201 0.202)
			(end -0.101 0)
			(stroke
				(width 0.15)
				(type solid)
			)
			(layer "B.Fab")
		)
		(fp_line
			(start -0.199 0.202)
			(end -0.199 -0.1)
			(stroke
				(width 0.15)
				(type solid)
			)
			(layer "B.Fab")
		)
		(fp_rect
			(start 0.848 -0.4)
			(end -0.85 0.402)
			(stroke
				(width 0.15)
				(type solid)
			)
			(fill no)
			(layer "B.Fab")
		)
		(pad "1" smd roundrect
			(at -0.7 0 270)
			(size 0.8 1)
			(layers "B.Cu" "B.Mask" "B.Paste")
			(roundrect_rratio 0.2)
			(net 13 "/USER_IO.BUTTON1")
			(pinfunction "C")
			(pintype "passive")
		)
		(pad "2" smd roundrect
			(at 0.7 0 270)
			(size 0.8 1)
			(layers "B.Cu" "B.Mask" "B.Paste")
			(roundrect_rratio 0.2)
			(net 1 "GND")
			(pinfunction "A")
			(pintype "passive")
		)
	)
	(footprint "antmicro-footprints:R_0402_1005Metric"
		(layer "B.Cu")
		(at 197.6 177.8 180)
		(descr "Resistor SMD 0402")
		(tags "resistor SMD 0402")
		(property "Reference" "R62"
			(at -1.025 0.5 0)
			(layer "B.SilkS")
			(effects
				(font
					(size 0.7 0.7)
					(thickness 0.15)
				)
				(justify left bottom mirror)
			)
		)
		(property "Value" "R_0R_0402"
			(at 0 -1.4 0)
			(layer "B.Fab")
			(effects
				(font
					(size 0.7 0.7)
					(thickness 0.15)
				)
				(justify left bottom mirror)
			)
		)
		(property "Description" "SMD Chip Resistor, Jumper, 0 ohm, 100 mW, 0402 [1005 Metric], Thick Film, General Purpose"
			(at 0 0 180)
			(layer "F.Fab")
			(hide yes)
			(effects
				(font
					(size 1.27 1.27)
					(thickness 0.15)
				)
			)
		)
		(property "Author" "Antmicro"
			(at 395.2 355.6 0)
			(layer "B.Fab")
			(hide yes)
			(effects
				(font
					(size 1 1)
					(thickness 0.15)
				)
				(justify mirror)
			)
		)
		(property "Current" "1A"
			(at 395.2 355.6 0)
			(layer "B.Fab")
			(hide yes)
			(effects
				(font
					(size 1 1)
					(thickness 0.15)
				)
				(justify mirror)
			)
		)
		(property "License" "Apache-2.0"
			(at 395.2 355.6 0)
			(layer "B.Fab")
			(hide yes)
			(effects
				(font
					(size 1 1)
					(thickness 0.15)
				)
				(justify mirror)
			)
		)
		(property "MPN" "ERJ2GE0R00X"
			(at 395.2 355.6 0)
			(layer "B.Fab")
			(hide yes)
			(effects
				(font
					(size 1 1)
					(thickness 0.15)
				)
				(justify mirror)
			)
		)
		(property "Manufacturer" "Panasonic"
			(at 395.2 355.6 0)
			(layer "B.Fab")
			(hide yes)
			(effects
				(font
					(size 1 1)
					(thickness 0.15)
				)
				(justify mirror)
			)
		)
		(property "Tolerance" ""
			(at 395.2 355.6 0)
			(layer "B.Fab")
			(hide yes)
			(effects
				(font
					(size 1 1)
					(thickness 0.15)
				)
				(justify mirror)
			)
		)
		(property "Val" "0R"
			(at 395.2 355.6 0)
			(layer "B.Fab")
			(hide yes)
			(effects
				(font
					(size 1 1)
					(thickness 0.15)
				)
				(justify mirror)
			)
		)
		(sheetname "Power supply")
		(sheetfile "power-supply.kicad_sch")
		(attr smd)
		(fp_rect
			(start -0.925 0.47)
			(end 0.925 -0.47)
			(stroke
				(width 0.05)
				(type default)
			)
			(fill no)
			(layer "B.CrtYd")
		)
		(fp_rect
			(start -0.5 0.25)
			(end 0.5 -0.25)
			(stroke
				(width 0.15)
				(type solid)
			)
			(fill no)
			(layer "B.Fab")
		)
		(pad "1" smd roundrect
			(at -0.48 0 180)
			(size 0.59 0.64)
			(layers "B.Cu" "B.Mask" "B.Paste")
			(roundrect_rratio 0.25)
			(net 365 "Net-(U8-TRIM)")
			(pintype "passive")
		)
		(pad "2" smd roundrect
			(at 0.48 0 180)
			(size 0.59 0.64)
			(layers "B.Cu" "B.Mask" "B.Paste")
			(roundrect_rratio 0.25)
			(net 891 "unconnected-(R62-Pad2)")
			(pintype "passive+no_connect")
		)
	)
	(footprint "antmicro-footprints:R_Array_4x0201_Panasonic_EXB18V"
		(layer "B.Cu")
		(at 249.901 149.15)
		(property "Reference" "R30"
			(at 1.074 -0.75 0)
			(layer "B.SilkS")
			(effects
				(font
					(size 0.7 0.7)
					(thickness 0.15)
				)
				(justify left bottom mirror)
			)
		)
		(property "Value" "R_4x33R_0201_array"
			(at -1.1 -1.8 0)
			(layer "B.Fab")
			(effects
				(font
					(size 0.7 0.7)
					(thickness 0.15)
				)
				(justify right bottom mirror)
			)
		)
		(property "Description" "Fixed Network Resistor, 33 ohm, Isolated, 4 Resistors, 0502 [1406 Metric], Flat, ± 5%"
			(at 0 0 0)
			(layer "F.Fab")
			(hide yes)
			(effects
				(font
					(size 1.27 1.27)
					(thickness 0.15)
				)
			)
		)
		(property "Author" "Antmicro"
			(at 0 0 0)
			(layer "B.Fab")
			(hide yes)
			(effects
				(font
					(size 1 1)
					(thickness 0.15)
				)
				(justify mirror)
			)
		)
		(property "License" "Apache-2.0"
			(at 0 0 0)
			(layer "B.Fab")
			(hide yes)
			(effects
				(font
					(size 1 1)
					(thickness 0.15)
				)
				(justify mirror)
			)
		)
		(property "MPN" "EXB-18V330JX"
			(at 0 0 0)
			(layer "B.Fab")
			(hide yes)
			(effects
				(font
					(size 1 1)
					(thickness 0.15)
				)
				(justify mirror)
			)
		)
		(property "Manufacturer" "Panasonic"
			(at 0 0 0)
			(layer "B.Fab")
			(hide yes)
			(effects
				(font
					(size 1 1)
					(thickness 0.15)
				)
				(justify mirror)
			)
		)
		(property "Val" "R_4x33R_0201"
			(at 0 0 0)
			(layer "B.Fab")
			(hide yes)
			(effects
				(font
					(size 1 1)
					(thickness 0.15)
				)
				(justify mirror)
			)
		)
		(sheetname "Supervisior MCU")
		(sheetfile "supervisor-mcu.kicad_sch")
		(attr smd)
		(fp_line
			(start -0.8 0.45)
			(end -0.8 -0.45)
			(stroke
				(width 0.12)
				(type solid)
			)
			(layer "B.SilkS")
		)
		(fp_line
			(start 0.8 0.45)
			(end 0.8 -0.45)
			(stroke
				(width 0.12)
				(type solid)
			)
			(layer "B.SilkS")
		)
		(fp_rect
			(start -0.898 0.66)
			(end 0.898 -0.65)
			(stroke
				(width 0.05)
				(type solid)
			)
			(fill no)
			(layer "B.CrtYd")
		)
		(pad "1" smd roundrect
			(at -0.6 -0.298)
			(size 0.2 0.4)
			(layers "B.Cu" "B.Mask" "B.Paste")
			(roundrect_rratio 0.25)
			(net 1315 "/SUP_MCU.DONE")
			(pinfunction "R1.1")
			(pintype "passive")
		)
		(pad "2" smd roundrect
			(at -0.202 -0.298)
			(size 0.2 0.4)
			(layers "B.Cu" "B.Mask" "B.Paste")
			(roundrect_rratio 0.25)
			(net 1317 "/SUP_MCU.PROGRAMB")
			(pinfunction "R2.1")
			(pintype "passive")
		)
		(pad "3" smd roundrect
			(at 0.2 -0.298)
			(size 0.2 0.4)
			(layers "B.Cu" "B.Mask" "B.Paste")
			(roundrect_rratio 0.25)
			(net 1326 "/SUP_MCU.FPGA_MISO")
			(pinfunction "R3.1")
			(pintype "passive")
		)
		(pad "4" smd roundrect
			(at 0.598 -0.298)
			(size 0.2 0.4)
			(layers "B.Cu" "B.Mask" "B.Paste")
			(roundrect_rratio 0.25)
			(net 1377 "/SUP_MCU.SPARE0")
			(pinfunction "R4.1")
			(pintype "passive")
		)
		(pad "5" smd roundrect
			(at 0.598 0.3)
			(size 0.2 0.4)
			(layers "B.Cu" "B.Mask" "B.Paste")
			(roundrect_rratio 0.25)
			(net 1114 "/Supervisior MCU/USB_SPARE0")
			(pinfunction "R4.2")
			(pintype "passive")
		)
		(pad "6" smd roundrect
			(at 0.2 0.3)
			(size 0.2 0.4)
			(layers "B.Cu" "B.Mask" "B.Paste")
			(roundrect_rratio 0.25)
			(net 975 "/Supervisior MCU/FPGA_CIPO")
			(pinfunction "R3.2")
			(pintype "passive")
		)
		(pad "7" smd roundrect
			(at -0.202 0.3)
			(size 0.2 0.4)
			(layers "B.Cu" "B.Mask" "B.Paste")
			(roundrect_rratio 0.25)
			(net 1054 "/Supervisior MCU/CFG_PROGRAMB")
			(pinfunction "R2.2")
			(pintype "passive")
		)
		(pad "8" smd roundrect
			(at -0.6 0.3)
			(size 0.2 0.4)
			(layers "B.Cu" "B.Mask" "B.Paste")
			(roundrect_rratio 0.25)
			(net 250 "/Supervisior MCU/CFG_DONE")
			(pinfunction "R1.2")
			(pintype "passive")
		)
	)
	(footprint "antmicro-footprints:Nexperia_SOD128"
		(layer "B.Cu")
		(at 155 133.4 180)
		(property "Reference" "D32"
			(at -0.025 2.225 0)
			(layer "B.SilkS")
			(effects
				(font
					(size 0.7 0.7)
					(thickness 0.15)
				)
				(justify mirror)
			)
		)
		(property "Value" "PMEG3050EP,115"
			(at 0 -2.4765 0)
			(layer "B.Fab")
			(effects
				(font
					(size 1 1)
					(thickness 0.15)
				)
				(justify mirror)
			)
		)
		(property "Description" "Schottky Rectifier, 30 V, 5 A, Single, SOD-128, 2 Pins, 360 mV"
			(at 0 0 180)
			(layer "F.Fab")
			(hide yes)
			(effects
				(font
					(size 1.27 1.27)
					(thickness 0.15)
				)
			)
		)
		(property "Author" "Antmicro"
			(at 310 266.8 0)
			(layer "B.Fab")
			(hide yes)
			(effects
				(font
					(size 1 1)
					(thickness 0.15)
				)
				(justify mirror)
			)
		)
		(property "DNP" "DNP"
			(at 310 266.8 0)
			(layer "B.Fab")
			(hide yes)
			(effects
				(font
					(size 1 1)
					(thickness 0.15)
				)
				(justify mirror)
			)
		)
		(property "License" "Apache-2.0"
			(at 310 266.8 0)
			(layer "B.Fab")
			(hide yes)
			(effects
				(font
					(size 1 1)
					(thickness 0.15)
				)
				(justify mirror)
			)
		)
		(property "MPN" "PMEG3050EP,115"
			(at 310 266.8 0)
			(layer "B.Fab")
			(hide yes)
			(effects
				(font
					(size 1 1)
					(thickness 0.15)
				)
				(justify mirror)
			)
		)
		(property "Manufacturer" "Nexperia"
			(at 310 266.8 0)
			(layer "B.Fab")
			(hide yes)
			(effects
				(font
					(size 1 1)
					(thickness 0.15)
				)
				(justify mirror)
			)
		)
		(property "dnp" ""
			(at 310 266.8 0)
			(layer "B.Fab")
			(hide yes)
			(effects
				(font
					(size 1 1)
					(thickness 0.15)
				)
				(justify mirror)
			)
		)
		(property "exclude_from_bom" ""
			(at 310 266.8 0)
			(layer "B.Fab")
			(hide yes)
			(effects
				(font
					(size 1 1)
					(thickness 0.15)
				)
				(justify mirror)
			)
		)
		(sheetname "FMC+ HSPC")
		(sheetfile "fmc-hspc.kicad_sch")
		(attr smd exclude_from_bom)
		(fp_line
			(start 2.12 1.474)
			(end -2.121 1.474)
			(stroke
				(width 0.15)
				(type solid)
			)
			(layer "B.SilkS")
		)
		(fp_line
			(start 2.12 1.287)
			(end 2.12 1.474)
			(stroke
				(width 0.15)
				(type solid)
			)
			(layer "B.SilkS")
		)
		(fp_line
			(start 2.12 -1.473)
			(end 2.12 -1.284)
			(stroke
				(width 0.15)
				(type solid)
			)
			(layer "B.SilkS")
		)
		(fp_line
			(start -1.6 1.4)
			(end -1.6 -1.4)
			(stroke
				(width 0.12)
				(type solid)
			)
			(layer "B.SilkS")
		)
		(fp_line
			(start -2.121 1.474)
			(end -2.121 1.287)
			(stroke
				(width 0.15)
				(type solid)
			)
			(layer "B.SilkS")
		)
		(fp_line
			(start -2.121 -1.284)
			(end -2.121 -1.473)
			(stroke
				(width 0.15)
				(type solid)
			)
			(layer "B.SilkS")
		)
		(fp_line
			(start -2.121 -1.473)
			(end 2.12 -1.473)
			(stroke
				(width 0.15)
				(type solid)
			)
			(layer "B.SilkS")
		)
		(fp_rect
			(start -2.8 1.6)
			(end 2.8 -1.6)
			(stroke
				(width 0.05)
				(type solid)
			)
			(fill no)
			(layer "B.CrtYd")
		)
		(fp_line
			(start 2.5 0.954)
			(end 1.993 0.954)
			(stroke
				(width 0.15)
				(type solid)
			)
			(layer "B.Fab")
		)
		(fp_line
			(start 2.5 -0.952)
			(end 2.5 0.954)
			(stroke
				(width 0.15)
				(type solid)
			)
			(layer "B.Fab")
		)
		(fp_line
			(start 1.993 1.347)
			(end -1.994 1.347)
			(stroke
				(width 0.15)
				(type solid)
			)
			(layer "B.Fab")
		)
		(fp_line
			(start 1.993 0.954)
			(end 1.993 -0.952)
			(stroke
				(width 0.15)
				(type solid)
			)
			(layer "B.Fab")
		)
		(fp_line
			(start 1.993 -0.952)
			(end 2.5 -0.952)
			(stroke
				(width 0.15)
				(type solid)
			)
			(layer "B.Fab")
		)
		(fp_line
			(start 1.993 -1.346)
			(end 1.993 1.347)
			(stroke
				(width 0.15)
				(type solid)
			)
			(layer "B.Fab")
		)
		(fp_line
			(start -1.994 1.347)
			(end -1.994 -1.346)
			(stroke
				(width 0.15)
				(type solid)
			)
			(layer "B.Fab")
		)
		(fp_line
			(start -1.994 0.954)
			(end -2.503 0.954)
			(stroke
				(width 0.15)
				(type solid)
			)
			(layer "B.Fab")
		)
		(fp_line
			(start -1.994 0.675)
			(end -1.321 1.347)
			(stroke
				(width 0.15)
				(type solid)
			)
			(layer "B.Fab")
		)
		(fp_line
			(start -1.994 -0.673)
			(end -1.321 -1.346)
			(stroke
				(width 0.15)
				(type solid)
			)
			(layer "B.Fab")
		)
		(fp_line
			(start -1.994 -0.952)
			(end -1.994 0.954)
			(stroke
				(width 0.15)
				(type solid)
			)
			(layer "B.Fab")
		)
		(fp_line
			(start -1.994 -1.346)
			(end 1.993 -1.346)
			(stroke
				(width 0.15)
				(type solid)
			)
			(layer "B.Fab")
		)
		(fp_line
			(start -2.503 0.954)
			(end -2.503 -0.952)
			(stroke
				(width 0.15)
				(type solid)
			)
			(layer "B.Fab")
		)
		(fp_line
			(start -2.503 -0.952)
			(end -1.994 -0.952)
			(stroke
				(width 0.15)
				(type solid)
			)
			(layer "B.Fab")
		)
		(pad "1" smd rect
			(at -2.298 0 180)
			(size 0.8096 1.905)
			(layers "B.Cu" "B.Mask" "B.Paste")
			(net 59 "12P0V")
			(pinfunction "1")
			(pintype "passive")
		)
		(pad "2" smd rect
			(at 2.297 0 180)
			(size 0.8096 1.905)
			(layers "B.Cu" "B.Mask" "B.Paste")
			(net 702 "VDC")
			(pinfunction "2")
			(pintype "passive")
		)
	)
	(footprint "antmicro-footprints:R_0402_1005Metric"
		(layer "B.Cu")
		(at 164 141.925 -90)
		(descr "Resistor SMD 0402")
		(tags "resistor SMD 0402")
		(property "Reference" "R34"
			(at -1.125 -1.275 90)
			(layer "B.SilkS")
			(effects
				(font
					(size 0.7 0.7)
					(thickness 0.15)
				)
				(justify left bottom mirror)
			)
		)
		(property "Value" "R_10k_0402"
			(at 0 -1.4 90)
			(layer "B.Fab")
			(effects
				(font
					(size 0.7 0.7)
					(thickness 0.15)
				)
				(justify left bottom mirror)
			)
		)
		(property "Description" "SMD Chip Resistor, 10 kohm, ± 1%, 62.5 mW, 0402 [1005 Metric], Thick Film, General Purpose"
			(at 0 0 270)
			(layer "F.Fab")
			(hide yes)
			(effects
				(font
					(size 1.27 1.27)
					(thickness 0.15)
				)
			)
		)
		(property "Author" "Antmicro"
			(at 22.075 305.925 0)
			(layer "B.Fab")
			(hide yes)
			(effects
				(font
					(size 1 1)
					(thickness 0.15)
				)
				(justify mirror)
			)
		)
		(property "License" "Apache-2.0"
			(at 22.075 305.925 0)
			(layer "B.Fab")
			(hide yes)
			(effects
				(font
					(size 1 1)
					(thickness 0.15)
				)
				(justify mirror)
			)
		)
		(property "MPN" "CR0402-FX-1002GLF"
			(at 22.075 305.925 0)
			(layer "B.Fab")
			(hide yes)
			(effects
				(font
					(size 1 1)
					(thickness 0.15)
				)
				(justify mirror)
			)
		)
		(property "Manufacturer" "Bourns"
			(at 22.075 305.925 0)
			(layer "B.Fab")
			(hide yes)
			(effects
				(font
					(size 1 1)
					(thickness 0.15)
				)
				(justify mirror)
			)
		)
		(property "Tolerance" "1%"
			(at 22.075 305.925 0)
			(layer "B.Fab")
			(hide yes)
			(effects
				(font
					(size 1 1)
					(thickness 0.15)
				)
				(justify mirror)
			)
		)
		(property "Val" "10k"
			(at 22.075 305.925 0)
			(layer "B.Fab")
			(hide yes)
			(effects
				(font
					(size 1 1)
					(thickness 0.15)
				)
				(justify mirror)
			)
		)
		(sheetname "DRAM + SRAM")
		(sheetfile "ram.kicad_sch")
		(attr smd)
		(fp_rect
			(start -0.925 0.47)
			(end 0.925 -0.47)
			(stroke
				(width 0.05)
				(type default)
			)
			(fill no)
			(layer "B.CrtYd")
		)
		(fp_rect
			(start -0.5 0.25)
			(end 0.5 -0.25)
			(stroke
				(width 0.15)
				(type solid)
			)
			(fill no)
			(layer "B.Fab")
		)
		(pad "1" smd roundrect
			(at -0.48 0 270)
			(size 0.59 0.64)
			(layers "B.Cu" "B.Mask" "B.Paste")
			(roundrect_rratio 0.25)
			(net 1 "GND")
			(pintype "passive")
		)
		(pad "2" smd roundrect
			(at 0.48 0 270)
			(size 0.59 0.64)
			(layers "B.Cu" "B.Mask" "B.Paste")
			(roundrect_rratio 0.25)
			(net 554 "/DRAM + SRAM/DDR.~{RESET}")
			(pintype "passive")
		)
	)
	(footprint "antmicro-footprints:QFN-2L_1.6x1x0.55mm"
		(layer "B.Cu")
		(at 264.75 88.6 90)
		(property "Reference" "D37"
			(at -2.2 -0.75 90)
			(layer "B.SilkS")
			(effects
				(font
					(size 0.7 0.7)
					(thickness 0.15)
				)
				(justify right bottom mirror)
			)
		)
		(property "Value" "ESDA25P35-1U1M"
			(at 0 -1.7 90)
			(layer "B.Fab")
			(effects
				(font
					(size 0.7 0.7)
					(thickness 0.15)
				)
				(justify right bottom mirror)
			)
		)
		(property "Description" "Unidirectional TVS, 30 kV, QFN-2L, 22 V, 195 pF"
			(at 0 0 90)
			(layer "F.Fab")
			(hide yes)
			(effects
				(font
					(size 1.27 1.27)
					(thickness 0.15)
				)
			)
		)
		(property "Author" "Antmicro"
			(at 353.35 -176.15 0)
			(layer "B.Fab")
			(hide yes)
			(effects
				(font
					(size 1 1)
					(thickness 0.15)
				)
				(justify mirror)
			)
		)
		(property "License" "Apache-2.0"
			(at 353.35 -176.15 0)
			(layer "B.Fab")
			(hide yes)
			(effects
				(font
					(size 1 1)
					(thickness 0.15)
				)
				(justify mirror)
			)
		)
		(property "MPN" "ESDA25P35-1U1M"
			(at 353.35 -176.15 0)
			(layer "B.Fab")
			(hide yes)
			(effects
				(font
					(size 1 1)
					(thickness 0.15)
				)
				(justify mirror)
			)
		)
		(property "Manufacturer" "STMicroelectronics"
			(at 353.35 -176.15 0)
			(layer "B.Fab")
			(hide yes)
			(effects
				(font
					(size 1 1)
					(thickness 0.15)
				)
				(justify mirror)
			)
		)
		(property "Public" "False"
			(at 353.35 -176.15 0)
			(layer "B.Fab")
			(hide yes)
			(effects
				(font
					(size 1 1)
					(thickness 0.15)
				)
				(justify mirror)
			)
		)
		(sheetname "User GPIO + LED + button + DIP switch")
		(sheetfile "user-gpio.kicad_sch")
		(attr smd)
		(fp_line
			(start 0.27 -0.3)
			(end -0.27 -0.3)
			(stroke
				(width 0.15)
				(type solid)
			)
			(layer "B.SilkS")
		)
		(fp_line
			(start 0.27 0.3)
			(end -0.27 0.3)
			(stroke
				(width 0.15)
				(type solid)
			)
			(layer "B.SilkS")
		)
		(fp_line
			(start -1.2 0.4)
			(end -1.2 -0.4)
			(stroke
				(width 0.15)
				(type solid)
			)
			(layer "B.SilkS")
		)
		(fp_rect
			(start 1.25 -0.65)
			(end -1.25 0.65)
			(stroke
				(width 0.05)
				(type solid)
			)
			(fill no)
			(layer "B.CrtYd")
		)
		(fp_line
			(start 0.201 -0.2)
			(end 0.201 0)
			(stroke
				(width 0.15)
				(type solid)
			)
			(layer "B.Fab")
		)
		(fp_line
			(start -0.199 -0.2)
			(end -0.199 -0.1)
			(stroke
				(width 0.15)
				(type solid)
			)
			(layer "B.Fab")
		)
		(fp_line
			(start 0.599 0)
			(end 0.201 0)
			(stroke
				(width 0.15)
				(type solid)
			)
			(layer "B.Fab")
		)
		(fp_line
			(start 0.201 0)
			(end 0.201 0.202)
			(stroke
				(width 0.15)
				(type solid)
			)
			(layer "B.Fab")
		)
		(fp_line
			(start -0.101 0)
			(end 0.201 -0.2)
			(stroke
				(width 0.15)
				(type solid)
			)
			(layer "B.Fab")
		)
		(fp_line
			(start -0.199 0)
			(end -0.597 0)
			(stroke
				(width 0.15)
				(type solid)
			)
			(layer "B.Fab")
		)
		(fp_line
			(start 0.201 0.202)
			(end -0.101 0)
			(stroke
				(width 0.15)
				(type solid)
			)
			(layer "B.Fab")
		)
		(fp_line
			(start -0.199 0.202)
			(end -0.199 -0.1)
			(stroke
				(width 0.15)
				(type solid)
			)
			(layer "B.Fab")
		)
		(fp_rect
			(start 0.848 -0.4)
			(end -0.85 0.402)
			(stroke
				(width 0.15)
				(type solid)
			)
			(fill no)
			(layer "B.Fab")
		)
		(pad "1" smd roundrect
			(at -0.7 0 270)
			(size 0.8 1)
			(layers "B.Cu" "B.Mask" "B.Paste")
			(roundrect_rratio 0.2)
			(net 1233 "/USER_IO.BUTTON2")
			(pinfunction "C")
			(pintype "passive")
		)
		(pad "2" smd roundrect
			(at 0.7 0 270)
			(size 0.8 1)
			(layers "B.Cu" "B.Mask" "B.Paste")
			(roundrect_rratio 0.2)
			(net 1 "GND")
			(pinfunction "A")
			(pintype "passive")
		)
	)
	(footprint "antmicro-footprints:R_Array_4x0201_Panasonic_EXB18V"
		(layer "B.Cu")
		(at 253.901 149.15)
		(property "Reference" "R33"
			(at 1.049 -0.725 0)
			(layer "B.SilkS")
			(effects
				(font
					(size 0.7 0.7)
					(thickness 0.15)
				)
				(justify left bottom mirror)
			)
		)
		(property "Value" "R_4x33R_0201_array"
			(at -1.1 -1.8 0)
			(layer "B.Fab")
			(effects
				(font
					(size 0.7 0.7)
					(thickness 0.15)
				)
				(justify right bottom mirror)
			)
		)
		(property "Description" "Fixed Network Resistor, 33 ohm, Isolated, 4 Resistors, 0502 [1406 Metric], Flat, ± 5%"
			(at 0 0 0)
			(layer "F.Fab")
			(hide yes)
			(effects
				(font
					(size 1.27 1.27)
					(thickness 0.15)
				)
			)
		)
		(property "Author" "Antmicro"
			(at 0 0 0)
			(layer "B.Fab")
			(hide yes)
			(effects
				(font
					(size 1 1)
					(thickness 0.15)
				)
				(justify mirror)
			)
		)
		(property "License" "Apache-2.0"
			(at 0 0 0)
			(layer "B.Fab")
			(hide yes)
			(effects
				(font
					(size 1 1)
					(thickness 0.15)
				)
				(justify mirror)
			)
		)
		(property "MPN" "EXB-18V330JX"
			(at 0 0 0)
			(layer "B.Fab")
			(hide yes)
			(effects
				(font
					(size 1 1)
					(thickness 0.15)
				)
				(justify mirror)
			)
		)
		(property "Manufacturer" "Panasonic"
			(at 0 0 0)
			(layer "B.Fab")
			(hide yes)
			(effects
				(font
					(size 1 1)
					(thickness 0.15)
				)
				(justify mirror)
			)
		)
		(property "Val" "R_4x33R_0201"
			(at 0 0 0)
			(layer "B.Fab")
			(hide yes)
			(effects
				(font
					(size 1 1)
					(thickness 0.15)
				)
				(justify mirror)
			)
		)
		(sheetname "Supervisior MCU")
		(sheetfile "supervisor-mcu.kicad_sch")
		(attr smd)
		(fp_line
			(start -0.8 0.45)
			(end -0.8 -0.45)
			(stroke
				(width 0.12)
				(type solid)
			)
			(layer "B.SilkS")
		)
		(fp_line
			(start 0.8 0.45)
			(end 0.8 -0.45)
			(stroke
				(width 0.12)
				(type solid)
			)
			(layer "B.SilkS")
		)
		(fp_rect
			(start -0.898 0.66)
			(end 0.898 -0.65)
			(stroke
				(width 0.05)
				(type solid)
			)
			(fill no)
			(layer "B.CrtYd")
		)
		(pad "1" smd roundrect
			(at -0.6 -0.298)
			(size 0.2 0.4)
			(layers "B.Cu" "B.Mask" "B.Paste")
			(roundrect_rratio 0.25)
			(net 1319 "/SUP_MCU.MISO")
			(pinfunction "R1.1")
			(pintype "passive")
		)
		(pad "2" smd roundrect
			(at -0.202 -0.298)
			(size 0.2 0.4)
			(layers "B.Cu" "B.Mask" "B.Paste")
			(roundrect_rratio 0.25)
			(net 1325 "/SUP_MCU.~{SCS}")
			(pinfunction "R2.1")
			(pintype "passive")
		)
		(pad "3" smd roundrect
			(at 0.2 -0.298)
			(size 0.2 0.4)
			(layers "B.Cu" "B.Mask" "B.Paste")
			(roundrect_rratio 0.25)
			(net 1323 "/SUP_MCU.SCLK0")
			(pinfunction "R3.1")
			(pintype "passive")
		)
		(pad "4" smd roundrect
			(at 0.598 -0.298)
			(size 0.2 0.4)
			(layers "B.Cu" "B.Mask" "B.Paste")
			(roundrect_rratio 0.25)
			(net 1379 "/SUP_MCU.D2")
			(pinfunction "R4.1")
			(pintype "passive")
		)
		(pad "5" smd roundrect
			(at 0.598 0.3)
			(size 0.2 0.4)
			(layers "B.Cu" "B.Mask" "B.Paste")
			(roundrect_rratio 0.25)
			(net 1097 "/Supervisior MCU/USB_D2")
			(pinfunction "R4.2")
			(pintype "passive")
		)
		(pad "6" smd roundrect
			(at 0.2 0.3)
			(size 0.2 0.4)
			(layers "B.Cu" "B.Mask" "B.Paste")
			(roundrect_rratio 0.25)
			(net 1089 "/Supervisior MCU/USB_SPI_SCK")
			(pinfunction "R3.2")
			(pintype "passive")
		)
		(pad "7" smd roundrect
			(at -0.202 0.3)
			(size 0.2 0.4)
			(layers "B.Cu" "B.Mask" "B.Paste")
			(roundrect_rratio 0.25)
			(net 1096 "/Supervisior MCU/USB_SPI_CS")
			(pinfunction "R2.2")
			(pintype "passive")
		)
		(pad "8" smd roundrect
			(at -0.6 0.3)
			(size 0.2 0.4)
			(layers "B.Cu" "B.Mask" "B.Paste")
			(roundrect_rratio 0.25)
			(net 1091 "/Supervisior MCU/USB_SPI_CIPO")
			(pinfunction "R1.2")
			(pintype "passive")
		)
	)
	(footprint "antmicro-footprints:C_0402_1005Metric"
		(layer "B.Cu")
		(at 183.2 142.2)
		(descr "Capacitor SMD 0402")
		(tags "capacitor SMD 0402")
		(property "Reference" "C85"
			(at 1.125 1.225 180)
			(layer "B.SilkS")
			(effects
				(font
					(size 0.7 0.7)
					(thickness 0.15)
				)
				(justify left bottom mirror)
			)
		)
		(property "Value" "C_100n_0402"
			(at 0 -1.169 180)
			(layer "B.Fab")
			(effects
				(font
					(size 0.7 0.7)
					(thickness 0.15)
				)
				(justify left bottom mirror)
			)
		)
		(property "Description" "SMD Multilayer Ceramic Capacitor, 0.1 µF, 50 V, 0402 [1005 Metric], ± 10%, X5R, GRM Series"
			(at 0 0 0)
			(layer "F.Fab")
			(hide yes)
			(effects
				(font
					(size 1.27 1.27)
					(thickness 0.15)
				)
			)
		)
		(property "Author" "Antmicro"
			(at 0 0 0)
			(layer "B.Fab")
			(hide yes)
			(effects
				(font
					(size 1 1)
					(thickness 0.15)
				)
				(justify mirror)
			)
		)
		(property "Dielectric" "X5R"
			(at 0 0 0)
			(layer "B.Fab")
			(hide yes)
			(effects
				(font
					(size 1 1)
					(thickness 0.15)
				)
				(justify mirror)
			)
		)
		(property "License" "Apache-2.0"
			(at 0 0 0)
			(layer "B.Fab")
			(hide yes)
			(effects
				(font
					(size 1 1)
					(thickness 0.15)
				)
				(justify mirror)
			)
		)
		(property "MPN" "GRM155R61H104KE14D"
			(at 0 0 0)
			(layer "B.Fab")
			(hide yes)
			(effects
				(font
					(size 1 1)
					(thickness 0.15)
				)
				(justify mirror)
			)
		)
		(property "Manufacturer" "Murata"
			(at 0 0 0)
			(layer "B.Fab")
			(hide yes)
			(effects
				(font
					(size 1 1)
					(thickness 0.15)
				)
				(justify mirror)
			)
		)
		(property "Val" "100n"
			(at 0 0 0)
			(layer "B.Fab")
			(hide yes)
			(effects
				(font
					(size 1 1)
					(thickness 0.15)
				)
				(justify mirror)
			)
		)
		(property "Voltage" "50V"
			(at 0 0 0)
			(layer "B.Fab")
			(hide yes)
			(effects
				(font
					(size 1 1)
					(thickness 0.15)
				)
				(justify mirror)
			)
		)
		(sheetname "FPGA Bank 33 & 34")
		(sheetfile "fpga-bank-33-34.kicad_sch")
		(attr smd)
		(fp_rect
			(start -0.925 0.47)
			(end 0.925 -0.47)
			(stroke
				(width 0.05)
				(type default)
			)
			(fill no)
			(layer "B.CrtYd")
		)
		(fp_line
			(start -0.494 -0.248)
			(end -0.494 0.25)
			(stroke
				(width 0.15)
				(type solid)
			)
			(layer "B.Fab")
		)
		(fp_line
			(start -0.494 0.25)
			(end 0.504 0.25)
			(stroke
				(width 0.15)
				(type solid)
			)
			(layer "B.Fab")
		)
		(fp_line
			(start 0.504 -0.248)
			(end -0.494 -0.248)
			(stroke
				(width 0.15)
				(type solid)
			)
			(layer "B.Fab")
		)
		(fp_line
			(start 0.504 0.25)
			(end 0.504 -0.248)
			(stroke
				(width 0.15)
				(type solid)
			)
			(layer "B.Fab")
		)
		(pad "1" smd roundrect
			(at -0.48 0)
			(size 0.59 0.64)
			(layers "B.Cu" "B.Mask" "B.Paste")
			(roundrect_rratio 0.25)
			(net 1 "GND")
			(pintype "passive")
		)
		(pad "2" smd roundrect
			(at 0.48 0)
			(size 0.59 0.64)
			(layers "B.Cu" "B.Mask" "B.Paste")
			(roundrect_rratio 0.25)
			(net 25 "+1V35")
			(pintype "passive")
		)
	)
	(footprint "antmicro-footprints:C_0603_1608Metric"
		(layer "B.Cu")
		(at 205.05 130 180)
		(descr "Capacitor SMD 0603")
		(tags "capacitor 0603")
		(property "Reference" "C382"
			(at -29.725 28.375 0)
			(layer "B.SilkS")
			(effects
				(font
					(size 0.7 0.7)
					(thickness 0.15)
				)
				(justify left bottom mirror)
			)
		)
		(property "Value" "C_47u_0603"
			(at 0 -1.6 0)
			(layer "B.Fab")
			(effects
				(font
					(size 0.7 0.7)
					(thickness 0.15)
				)
				(justify left bottom mirror)
			)
		)
		(property "Description" "SMD Multilayer Ceramic Capacitor, 47 µF, 6.3 V, 0603 [1608 Metric], ± 20%, X5R, GRM Series"
			(at 0 0 180)
			(layer "F.Fab")
			(hide yes)
			(effects
				(font
					(size 1.27 1.27)
					(thickness 0.15)
				)
			)
		)
		(property "Author" "Antmicro"
			(at 410.1 260 0)
			(layer "B.Fab")
			(hide yes)
			(effects
				(font
					(size 1 1)
					(thickness 0.15)
				)
				(justify mirror)
			)
		)
		(property "Dielectric" ""
			(at 410.1 260 0)
			(layer "B.Fab")
			(hide yes)
			(effects
				(font
					(size 1 1)
					(thickness 0.15)
				)
				(justify mirror)
			)
		)
		(property "License" "Apache-2.0"
			(at 410.1 260 0)
			(layer "B.Fab")
			(hide yes)
			(effects
				(font
					(size 1 1)
					(thickness 0.15)
				)
				(justify mirror)
			)
		)
		(property "MPN" "GRM188R60J476ME15D"
			(at 410.1 260 0)
			(layer "B.Fab")
			(hide yes)
			(effects
				(font
					(size 1 1)
					(thickness 0.15)
				)
				(justify mirror)
			)
		)
		(property "Manufacturer" "Murata"
			(at 410.1 260 0)
			(layer "B.Fab")
			(hide yes)
			(effects
				(font
					(size 1 1)
					(thickness 0.15)
				)
				(justify mirror)
			)
		)
		(property "Val" "47u"
			(at 410.1 260 0)
			(layer "B.Fab")
			(hide yes)
			(effects
				(font
					(size 1 1)
					(thickness 0.15)
				)
				(justify mirror)
			)
		)
		(property "Voltage" ""
			(at 410.1 260 0)
			(layer "B.Fab")
			(hide yes)
			(effects
				(font
					(size 1 1)
					(thickness 0.15)
				)
				(justify mirror)
			)
		)
		(sheetname "FPGA supply")
		(sheetfile "fpga-supply.kicad_sch")
		(attr smd)
		(fp_line
			(start -0.15 0.4)
			(end 0.15 0.4)
			(stroke
				(width 0.15)
				(type solid)
			)
			(layer "B.SilkS")
		)
		(fp_line
			(start -0.15 -0.4)
			(end 0.15 -0.4)
			(stroke
				(width 0.15)
				(type solid)
			)
			(layer "B.SilkS")
		)
		(fp_rect
			(start -1.25 0.65)
			(end 1.25 -0.65)
			(stroke
				(width 0.05)
				(type solid)
			)
			(fill no)
			(layer "B.CrtYd")
		)
		(fp_rect
			(start -0.8 0.4)
			(end 0.8 -0.4)
			(stroke
				(width 0.15)
				(type solid)
			)
			(fill no)
			(layer "B.Fab")
		)
		(pad "1" smd roundrect
			(at -0.7 0 180)
			(size 0.8 1)
			(layers "B.Cu" "B.Mask" "B.Paste")
			(roundrect_rratio 0.2)
			(net 1 "GND")
			(pintype "passive")
		)
		(pad "2" smd roundrect
			(at 0.7 0 180)
			(size 0.8 1)
			(layers "B.Cu" "B.Mask" "B.Paste")
			(roundrect_rratio 0.2)
			(net 650 "+1V0")
			(pintype "passive")
		)
	)
	(footprint "antmicro-footprints:C_0402_1005Metric"
		(layer "B.Cu")
		(at 192.01 141.5 180)
		(descr "Capacitor SMD 0402")
		(tags "capacitor SMD 0402")
		(property "Reference" "C374"
			(at -1.875 0.475 0)
			(layer "B.SilkS")
			(effects
				(font
					(size 0.7 0.7)
					(thickness 0.15)
				)
				(justify left bottom mirror)
			)
		)
		(property "Value" "C_100n_0402"
			(at 0 -1.169 0)
			(layer "B.Fab")
			(effects
				(font
					(size 0.7 0.7)
					(thickness 0.15)
				)
				(justify left bottom mirror)
			)
		)
		(property "Description" "SMD Multilayer Ceramic Capacitor, 0.1 µF, 50 V, 0402 [1005 Metric], ± 10%, X5R, GRM Series"
			(at 0 0 180)
			(layer "F.Fab")
			(hide yes)
			(effects
				(font
					(size 1.27 1.27)
					(thickness 0.15)
				)
			)
		)
		(property "Author" "Antmicro"
			(at 384.02 283 0)
			(layer "B.Fab")
			(hide yes)
			(effects
				(font
					(size 1 1)
					(thickness 0.15)
				)
				(justify mirror)
			)
		)
		(property "Dielectric" "X5R"
			(at 384.02 283 0)
			(layer "B.Fab")
			(hide yes)
			(effects
				(font
					(size 1 1)
					(thickness 0.15)
				)
				(justify mirror)
			)
		)
		(property "License" "Apache-2.0"
			(at 384.02 283 0)
			(layer "B.Fab")
			(hide yes)
			(effects
				(font
					(size 1 1)
					(thickness 0.15)
				)
				(justify mirror)
			)
		)
		(property "MPN" "GRM155R61H104KE14D"
			(at 384.02 283 0)
			(layer "B.Fab")
			(hide yes)
			(effects
				(font
					(size 1 1)
					(thickness 0.15)
				)
				(justify mirror)
			)
		)
		(property "Manufacturer" "Murata"
			(at 384.02 283 0)
			(layer "B.Fab")
			(hide yes)
			(effects
				(font
					(size 1 1)
					(thickness 0.15)
				)
				(justify mirror)
			)
		)
		(property "Val" "100n"
			(at 384.02 283 0)
			(layer "B.Fab")
			(hide yes)
			(effects
				(font
					(size 1 1)
					(thickness 0.15)
				)
				(justify mirror)
			)
		)
		(property "Voltage" "50V"
			(at 384.02 283 0)
			(layer "B.Fab")
			(hide yes)
			(effects
				(font
					(size 1 1)
					(thickness 0.15)
				)
				(justify mirror)
			)
		)
		(sheetname "FPGA Bank 33 & 34")
		(sheetfile "fpga-bank-33-34.kicad_sch")
		(attr smd)
		(fp_rect
			(start -0.925 0.47)
			(end 0.925 -0.47)
			(stroke
				(width 0.05)
				(type default)
			)
			(fill no)
			(layer "B.CrtYd")
		)
		(fp_line
			(start 0.504 0.25)
			(end 0.504 -0.248)
			(stroke
				(width 0.15)
				(type solid)
			)
			(layer "B.Fab")
		)
		(fp_line
			(start 0.504 -0.248)
			(end -0.494 -0.248)
			(stroke
				(width 0.15)
				(type solid)
			)
			(layer "B.Fab")
		)
		(fp_line
			(start -0.494 0.25)
			(end 0.504 0.25)
			(stroke
				(width 0.15)
				(type solid)
			)
			(layer "B.Fab")
		)
		(fp_line
			(start -0.494 -0.248)
			(end -0.494 0.25)
			(stroke
				(width 0.15)
				(type solid)
			)
			(layer "B.Fab")
		)
		(pad "1" smd roundrect
			(at -0.48 0 180)
			(size 0.59 0.64)
			(layers "B.Cu" "B.Mask" "B.Paste")
			(roundrect_rratio 0.25)
			(net 1 "GND")
			(pintype "passive")
		)
		(pad "2" smd roundrect
			(at 0.48 0 180)
			(size 0.59 0.64)
			(layers "B.Cu" "B.Mask" "B.Paste")
			(roundrect_rratio 0.25)
			(net 11 "+0V675_VREF")
			(pintype "passive")
		)
	)
	(footprint "antmicro-footprints:NetTie-2_SMD_Pad0.127mm"
		(layer "B.Cu")
		(at 193.59 145.72)
		(descr "Net tie, 2 pin, 0.127mm  SMD pads")
		(tags "net tie")
		(property "Reference" "NT36"
			(at -0.128 1.345 180)
			(layer "B.SilkS")
			(hide yes)
			(effects
				(font
					(size 0.7 0.7)
					(thickness 0.15)
				)
				(justify left bottom mirror)
			)
		)
		(property "Value" "Net-Tie_2"
			(at 0 -1.199 180)
			(layer "B.Fab")
			(effects
				(font
					(size 0.7 0.7)
					(thickness 0.15)
				)
				(justify left bottom mirror)
			)
		)
		(property "Description" "Net tie, 2 pins"
			(at 0 0 0)
			(layer "F.Fab")
			(hide yes)
			(effects
				(font
					(size 1.27 1.27)
					(thickness 0.15)
				)
			)
		)
		(property "Author" "Antmicro"
			(at 0 0 0)
			(layer "B.Fab")
			(hide yes)
			(effects
				(font
					(size 1 1)
					(thickness 0.15)
				)
				(justify mirror)
			)
		)
		(property "License" "Apache-2.0"
			(at 0 0 0)
			(layer "B.Fab")
			(hide yes)
			(effects
				(font
					(size 1 1)
					(thickness 0.15)
				)
				(justify mirror)
			)
		)
		(property "MPN" ""
			(at 0 0 0)
			(layer "B.Fab")
			(hide yes)
			(effects
				(font
					(size 1 1)
					(thickness 0.15)
				)
				(justify mirror)
			)
		)
		(property "Manufacturer" ""
			(at 0 0 0)
			(layer "B.Fab")
			(hide yes)
			(effects
				(font
					(size 1 1)
					(thickness 0.15)
				)
				(justify mirror)
			)
		)
		(sheetname "DC-DC Converters")
		(sheetfile "dc-dc.kicad_sch")
		(attr exclude_from_pos_files)
		(net_tie_pad_groups "1, 2")
		(fp_poly
			(pts
				(xy -0.0635 0.0635) (xy 0.0625 0.0635) (xy 0.0625 -0.0635) (xy -0.0635 -0.0635)
			)
			(stroke
				(width 0)
				(type solid)
			)
			(fill yes)
			(layer "B.Cu")
		)
		(pad "1" smd roundrect
			(at -0.127 0 180)
			(size 0.127 0.127)
			(layers "B.Cu")
			(roundrect_rratio 0.5)
			(chamfer_ratio 0)
			(chamfer top_left bottom_left)
			(net 1224 "/DC-DC Converters/SENSE_1V8_P")
			(pinfunction "1")
			(pintype "passive")
		)
		(pad "2" smd roundrect
			(at 0.126 0)
			(size 0.127 0.127)
			(layers "B.Cu")
			(roundrect_rratio 0.5)
			(chamfer_ratio 0)
			(chamfer top_left bottom_left)
			(net 26 "+1V8")
			(pinfunction "2")
			(pintype "passive")
		)
	)
	(footprint "antmicro-footprints:C_0402_1005Metric"
		(layer "B.Cu")
		(at 208.5 121 90)
		(descr "Capacitor SMD 0402")
		(tags "capacitor SMD 0402")
		(property "Reference" "C39"
			(at 1.1 1.225 270)
			(layer "B.SilkS")
			(effects
				(font
					(size 0.7 0.7)
					(thickness 0.15)
				)
				(justify left bottom mirror)
			)
		)
		(property "Value" "C_100n_0402"
			(at 0 -1.169 270)
			(layer "B.Fab")
			(effects
				(font
					(size 0.7 0.7)
					(thickness 0.15)
				)
				(justify left bottom mirror)
			)
		)
		(property "Description" "SMD Multilayer Ceramic Capacitor, 0.1 µF, 50 V, 0402 [1005 Metric], ± 10%, X5R, GRM Series"
			(at 0 0 90)
			(layer "F.Fab")
			(hide yes)
			(effects
				(font
					(size 1.27 1.27)
					(thickness 0.15)
				)
			)
		)
		(property "Author" "Antmicro"
			(at 329.5 -87.5 0)
			(layer "B.Fab")
			(hide yes)
			(effects
				(font
					(size 1 1)
					(thickness 0.15)
				)
				(justify mirror)
			)
		)
		(property "Dielectric" "X5R"
			(at 329.5 -87.5 0)
			(layer "B.Fab")
			(hide yes)
			(effects
				(font
					(size 1 1)
					(thickness 0.15)
				)
				(justify mirror)
			)
		)
		(property "License" "Apache-2.0"
			(at 329.5 -87.5 0)
			(layer "B.Fab")
			(hide yes)
			(effects
				(font
					(size 1 1)
					(thickness 0.15)
				)
				(justify mirror)
			)
		)
		(property "MPN" "GRM155R61H104KE14D"
			(at 329.5 -87.5 0)
			(layer "B.Fab")
			(hide yes)
			(effects
				(font
					(size 1 1)
					(thickness 0.15)
				)
				(justify mirror)
			)
		)
		(property "Manufacturer" "Murata"
			(at 329.5 -87.5 0)
			(layer "B.Fab")
			(hide yes)
			(effects
				(font
					(size 1 1)
					(thickness 0.15)
				)
				(justify mirror)
			)
		)
		(property "Val" "100n"
			(at 329.5 -87.5 0)
			(layer "B.Fab")
			(hide yes)
			(effects
				(font
					(size 1 1)
					(thickness 0.15)
				)
				(justify mirror)
			)
		)
		(property "Voltage" "50V"
			(at 329.5 -87.5 0)
			(layer "B.Fab")
			(hide yes)
			(effects
				(font
					(size 1 1)
					(thickness 0.15)
				)
				(justify mirror)
			)
		)
		(sheetname "FPGA Bank 16 & 17")
		(sheetfile "fpga-bank-16-17.kicad_sch")
		(attr smd)
		(fp_rect
			(start -0.925 0.47)
			(end 0.925 -0.47)
			(stroke
				(width 0.05)
				(type default)
			)
			(fill no)
			(layer "B.CrtYd")
		)
		(fp_line
			(start 0.504 -0.248)
			(end -0.494 -0.248)
			(stroke
				(width 0.15)
				(type solid)
			)
			(layer "B.Fab")
		)
		(fp_line
			(start -0.494 -0.248)
			(end -0.494 0.25)
			(stroke
				(width 0.15)
				(type solid)
			)
			(layer "B.Fab")
		)
		(fp_line
			(start 0.504 0.25)
			(end 0.504 -0.248)
			(stroke
				(width 0.15)
				(type solid)
			)
			(layer "B.Fab")
		)
		(fp_line
			(start -0.494 0.25)
			(end 0.504 0.25)
			(stroke
				(width 0.15)
				(type solid)
			)
			(layer "B.Fab")
		)
		(pad "1" smd roundrect
			(at -0.48 0 90)
			(size 0.59 0.64)
			(layers "B.Cu" "B.Mask" "B.Paste")
			(roundrect_rratio 0.25)
			(net 1 "GND")
			(pintype "passive")
		)
		(pad "2" smd roundrect
			(at 0.48 0 90)
			(size 0.59 0.64)
			(layers "B.Cu" "B.Mask" "B.Paste")
			(roundrect_rratio 0.25)
			(net 3 "VCC_USR_B")
			(pintype "passive")
		)
	)
	(footprint "antmicro-footprints:R_Array_4x0201_Panasonic_EXB18V"
		(layer "B.Cu")
		(at 165.999999 146.199999 180)
		(property "Reference" "R15"
			(at 6.474999 -6.125001 0)
			(layer "B.SilkS")
			(effects
				(font
					(size 0.7 0.7)
					(thickness 0.15)
				)
				(justify right bottom mirror)
			)
		)
		(property "Value" "4x39R_0201_array"
			(at -1.1 -1.8 0)
			(layer "B.Fab")
			(effects
				(font
					(size 0.7 0.7)
					(thickness 0.15)
				)
				(justify left bottom mirror)
			)
		)
		(property "Description" "Fixed Network Resistor, 39 ohm, Isolated, 4 Resistors, 0502 [1406 Metric], Flat, ± 5%"
			(at 0 0 180)
			(layer "F.Fab")
			(hide yes)
			(effects
				(font
					(size 1.27 1.27)
					(thickness 0.15)
				)
			)
		)
		(property "Author" "Antmicro"
			(at 331.999998 292.399998 0)
			(layer "B.Fab")
			(hide yes)
			(effects
				(font
					(size 1 1)
					(thickness 0.15)
				)
				(justify mirror)
			)
		)
		(property "License" "Apache-2.0"
			(at 331.999998 292.399998 0)
			(layer "B.Fab")
			(hide yes)
			(effects
				(font
					(size 1 1)
					(thickness 0.15)
				)
				(justify mirror)
			)
		)
		(property "MPN" "EXB-18V390JX"
			(at 331.999998 292.399998 0)
			(layer "B.Fab")
			(hide yes)
			(effects
				(font
					(size 1 1)
					(thickness 0.15)
				)
				(justify mirror)
			)
		)
		(property "Manufacturer" "Panasonic"
			(at 331.999998 292.399998 0)
			(layer "B.Fab")
			(hide yes)
			(effects
				(font
					(size 1 1)
					(thickness 0.15)
				)
				(justify mirror)
			)
		)
		(property "Val" "4x39R_0201"
			(at 331.999998 292.399998 0)
			(layer "B.Fab")
			(hide yes)
			(effects
				(font
					(size 1 1)
					(thickness 0.15)
				)
				(justify mirror)
			)
		)
		(sheetname "DRAM + SRAM")
		(sheetfile "ram.kicad_sch")
		(attr smd)
		(fp_line
			(start 0.8 0.45)
			(end 0.8 -0.45)
			(stroke
				(width 0.12)
				(type solid)
			)
			(layer "B.SilkS")
		)
		(fp_line
			(start -0.8 0.45)
			(end -0.8 -0.45)
			(stroke
				(width 0.12)
				(type solid)
			)
			(layer "B.SilkS")
		)
		(fp_rect
			(start -0.898 0.66)
			(end 0.898 -0.65)
			(stroke
				(width 0.05)
				(type solid)
			)
			(fill no)
			(layer "B.CrtYd")
		)
		(pad "1" smd roundrect
			(at -0.6 -0.298 180)
			(size 0.2 0.4)
			(layers "B.Cu" "B.Mask" "B.Paste")
			(roundrect_rratio 0.25)
			(net 543 "/DRAM + SRAM/DDR.A12")
			(pinfunction "R1.1")
			(pintype "passive")
		)
		(pad "2" smd roundrect
			(at -0.202 -0.298 180)
			(size 0.2 0.4)
			(layers "B.Cu" "B.Mask" "B.Paste")
			(roundrect_rratio 0.25)
			(net 548 "/DRAM + SRAM/DDR.BA1")
			(pinfunction "R2.1")
			(pintype "passive")
		)
		(pad "3" smd roundrect
			(at 0.2 -0.298 180)
			(size 0.2 0.4)
			(layers "B.Cu" "B.Mask" "B.Paste")
			(roundrect_rratio 0.25)
			(net 532 "/DRAM + SRAM/DDR.A1")
			(pinfunction "R3.1")
			(pintype "passive")
		)
		(pad "4" smd roundrect
			(at 0.598 -0.298 180)
			(size 0.2 0.4)
			(layers "B.Cu" "B.Mask" "B.Paste")
			(roundrect_rratio 0.25)
			(net 535 "/DRAM + SRAM/DDR.A4")
			(pinfunction "R4.1")
			(pintype "passive")
		)
		(pad "5" smd roundrect
			(at 0.598 0.3 180)
			(size 0.2 0.4)
			(layers "B.Cu" "B.Mask" "B.Paste")
			(roundrect_rratio 0.25)
			(net 7 "+0V675_VTT")
			(pinfunction "R4.2")
			(pintype "passive")
		)
		(pad "6" smd roundrect
			(at 0.2 0.3 180)
			(size 0.2 0.4)
			(layers "B.Cu" "B.Mask" "B.Paste")
			(roundrect_rratio 0.25)
			(net 7 "+0V675_VTT")
			(pinfunction "R3.2")
			(pintype "passive")
		)
		(pad "7" smd roundrect
			(at -0.202 0.3 180)
			(size 0.2 0.4)
			(layers "B.Cu" "B.Mask" "B.Paste")
			(roundrect_rratio 0.25)
			(net 7 "+0V675_VTT")
			(pinfunction "R2.2")
			(pintype "passive")
		)
		(pad "8" smd roundrect
			(at -0.6 0.3 180)
			(size 0.2 0.4)
			(layers "B.Cu" "B.Mask" "B.Paste")
			(roundrect_rratio 0.25)
			(net 7 "+0V675_VTT")
			(pinfunction "R1.2")
			(pintype "passive")
		)
	)
	(footprint "antmicro-footprints:C_0402_1005Metric"
		(layer "B.Cu")
		(at 196.4 133.2)
		(descr "Capacitor SMD 0402")
		(tags "capacitor SMD 0402")
		(property "Reference" "C73"
			(at 25.15 -28.025 180)
			(layer "B.SilkS")
			(effects
				(font
					(size 0.7 0.7)
					(thickness 0.15)
				)
				(justify left bottom mirror)
			)
		)
		(property "Value" "C_100n_0402"
			(at 0 -1.169 180)
			(layer "B.Fab")
			(effects
				(font
					(size 0.7 0.7)
					(thickness 0.15)
				)
				(justify left bottom mirror)
			)
		)
		(property "Description" "SMD Multilayer Ceramic Capacitor, 0.1 µF, 50 V, 0402 [1005 Metric], ± 10%, X5R, GRM Series"
			(at 0 0 0)
			(layer "F.Fab")
			(hide yes)
			(effects
				(font
					(size 1.27 1.27)
					(thickness 0.15)
				)
			)
		)
		(property "Author" "Antmicro"
			(at 0 0 0)
			(layer "B.Fab")
			(hide yes)
			(effects
				(font
					(size 1 1)
					(thickness 0.15)
				)
				(justify mirror)
			)
		)
		(property "Dielectric" "X5R"
			(at 0 0 0)
			(layer "B.Fab")
			(hide yes)
			(effects
				(font
					(size 1 1)
					(thickness 0.15)
				)
				(justify mirror)
			)
		)
		(property "License" "Apache-2.0"
			(at 0 0 0)
			(layer "B.Fab")
			(hide yes)
			(effects
				(font
					(size 1 1)
					(thickness 0.15)
				)
				(justify mirror)
			)
		)
		(property "MPN" "GRM155R61H104KE14D"
			(at 0 0 0)
			(layer "B.Fab")
			(hide yes)
			(effects
				(font
					(size 1 1)
					(thickness 0.15)
				)
				(justify mirror)
			)
		)
		(property "Manufacturer" "Murata"
			(at 0 0 0)
			(layer "B.Fab")
			(hide yes)
			(effects
				(font
					(size 1 1)
					(thickness 0.15)
				)
				(justify mirror)
			)
		)
		(property "Val" "100n"
			(at 0 0 0)
			(layer "B.Fab")
			(hide yes)
			(effects
				(font
					(size 1 1)
					(thickness 0.15)
				)
				(justify mirror)
			)
		)
		(property "Voltage" "50V"
			(at 0 0 0)
			(layer "B.Fab")
			(hide yes)
			(effects
				(font
					(size 1 1)
					(thickness 0.15)
				)
				(justify mirror)
			)
		)
		(sheetname "FPGA supply")
		(sheetfile "fpga-supply.kicad_sch")
		(attr smd)
		(fp_rect
			(start -0.925 0.47)
			(end 0.925 -0.47)
			(stroke
				(width 0.05)
				(type default)
			)
			(fill no)
			(layer "B.CrtYd")
		)
		(fp_line
			(start -0.494 -0.248)
			(end -0.494 0.25)
			(stroke
				(width 0.15)
				(type solid)
			)
			(layer "B.Fab")
		)
		(fp_line
			(start -0.494 0.25)
			(end 0.504 0.25)
			(stroke
				(width 0.15)
				(type solid)
			)
			(layer "B.Fab")
		)
		(fp_line
			(start 0.504 -0.248)
			(end -0.494 -0.248)
			(stroke
				(width 0.15)
				(type solid)
			)
			(layer "B.Fab")
		)
		(fp_line
			(start 0.504 0.25)
			(end 0.504 -0.248)
			(stroke
				(width 0.15)
				(type solid)
			)
			(layer "B.Fab")
		)
		(pad "1" smd roundrect
			(at -0.48 0)
			(size 0.59 0.64)
			(layers "B.Cu" "B.Mask" "B.Paste")
			(roundrect_rratio 0.25)
			(net 1 "GND")
			(pintype "passive")
		)
		(pad "2" smd roundrect
			(at 0.48 0)
			(size 0.59 0.64)
			(layers "B.Cu" "B.Mask" "B.Paste")
			(roundrect_rratio 0.25)
			(net 26 "+1V8")
			(pintype "passive")
		)
	)
	(footprint "antmicro-footprints:C_0402_1005Metric"
		(layer "B.Cu")
		(at 204.5 124 -90)
		(descr "Capacitor SMD 0402")
		(tags "capacitor SMD 0402")
		(property "Reference" "C81"
			(at -30.975 -28.65 90)
			(layer "B.SilkS")
			(effects
				(font
					(size 0.7 0.7)
					(thickness 0.15)
				)
				(justify left bottom mirror)
			)
		)
		(property "Value" "C_100n_0402"
			(at 0 -1.169 90)
			(layer "B.Fab")
			(effects
				(font
					(size 0.7 0.7)
					(thickness 0.15)
				)
				(justify left bottom mirror)
			)
		)
		(property "Description" "SMD Multilayer Ceramic Capacitor, 0.1 µF, 50 V, 0402 [1005 Metric], ± 10%, X5R, GRM Series"
			(at 0 0 270)
			(layer "F.Fab")
			(hide yes)
			(effects
				(font
					(size 1.27 1.27)
					(thickness 0.15)
				)
			)
		)
		(property "Author" "Antmicro"
			(at 80.5 328.5 0)
			(layer "B.Fab")
			(hide yes)
			(effects
				(font
					(size 1 1)
					(thickness 0.15)
				)
				(justify mirror)
			)
		)
		(property "Dielectric" "X5R"
			(at 80.5 328.5 0)
			(layer "B.Fab")
			(hide yes)
			(effects
				(font
					(size 1 1)
					(thickness 0.15)
				)
				(justify mirror)
			)
		)
		(property "License" "Apache-2.0"
			(at 80.5 328.5 0)
			(layer "B.Fab")
			(hide yes)
			(effects
				(font
					(size 1 1)
					(thickness 0.15)
				)
				(justify mirror)
			)
		)
		(property "MPN" "GRM155R61H104KE14D"
			(at 80.5 328.5 0)
			(layer "B.Fab")
			(hide yes)
			(effects
				(font
					(size 1 1)
					(thickness 0.15)
				)
				(justify mirror)
			)
		)
		(property "Manufacturer" "Murata"
			(at 80.5 328.5 0)
			(layer "B.Fab")
			(hide yes)
			(effects
				(font
					(size 1 1)
					(thickness 0.15)
				)
				(justify mirror)
			)
		)
		(property "Val" "100n"
			(at 80.5 328.5 0)
			(layer "B.Fab")
			(hide yes)
			(effects
				(font
					(size 1 1)
					(thickness 0.15)
				)
				(justify mirror)
			)
		)
		(property "Voltage" "50V"
			(at 80.5 328.5 0)
			(layer "B.Fab")
			(hide yes)
			(effects
				(font
					(size 1 1)
					(thickness 0.15)
				)
				(justify mirror)
			)
		)
		(sheetname "FPGA Bank 16 & 17")
		(sheetfile "fpga-bank-16-17.kicad_sch")
		(attr smd)
		(fp_rect
			(start -0.925 0.47)
			(end 0.925 -0.47)
			(stroke
				(width 0.05)
				(type default)
			)
			(fill no)
			(layer "B.CrtYd")
		)
		(fp_line
			(start -0.494 0.25)
			(end 0.504 0.25)
			(stroke
				(width 0.15)
				(type solid)
			)
			(layer "B.Fab")
		)
		(fp_line
			(start 0.504 0.25)
			(end 0.504 -0.248)
			(stroke
				(width 0.15)
				(type solid)
			)
			(layer "B.Fab")
		)
		(fp_line
			(start -0.494 -0.248)
			(end -0.494 0.25)
			(stroke
				(width 0.15)
				(type solid)
			)
			(layer "B.Fab")
		)
		(fp_line
			(start 0.504 -0.248)
			(end -0.494 -0.248)
			(stroke
				(width 0.15)
				(type solid)
			)
			(layer "B.Fab")
		)
		(pad "1" smd roundrect
			(at -0.48 0 270)
			(size 0.59 0.64)
			(layers "B.Cu" "B.Mask" "B.Paste")
			(roundrect_rratio 0.25)
			(net 1 "GND")
			(pintype "passive")
		)
		(pad "2" smd roundrect
			(at 0.48 0 270)
			(size 0.59 0.64)
			(layers "B.Cu" "B.Mask" "B.Paste")
			(roundrect_rratio 0.25)
			(net 24 "+3V3")
			(pintype "passive")
		)
	)
	(footprint "antmicro-footprints:R_0402_1005Metric"
		(layer "B.Cu")
		(at 166.55 185.95 -90)
		(descr "Resistor SMD 0402")
		(tags "resistor SMD 0402")
		(property "Reference" "R318"
			(at -3.625 -0.525 90)
			(layer "B.SilkS")
			(effects
				(font
					(size 0.7 0.7)
					(thickness 0.15)
				)
				(justify left bottom mirror)
			)
		)
		(property "Value" "R_47k_0402"
			(at 0 -1.4 90)
			(layer "B.Fab")
			(effects
				(font
					(size 0.7 0.7)
					(thickness 0.15)
				)
				(justify left bottom mirror)
			)
		)
		(property "Description" "SMD Chip Resistor, 47 kohm, ± 1%, 62.5 mW, 0402 [1005 Metric], Thick Film, General Purpose"
			(at 0 0 270)
			(layer "F.Fab")
			(hide yes)
			(effects
				(font
					(size 1.27 1.27)
					(thickness 0.15)
				)
			)
		)
		(property "Author" "Antmicro"
			(at -19.4 352.5 0)
			(layer "B.Fab")
			(hide yes)
			(effects
				(font
					(size 1 1)
					(thickness 0.15)
				)
				(justify mirror)
			)
		)
		(property "License" "Apache-2.0"
			(at -19.4 352.5 0)
			(layer "B.Fab")
			(hide yes)
			(effects
				(font
					(size 1 1)
					(thickness 0.15)
				)
				(justify mirror)
			)
		)
		(property "MPN" "CR0402-FX-4702GLF"
			(at -19.4 352.5 0)
			(layer "B.Fab")
			(hide yes)
			(effects
				(font
					(size 1 1)
					(thickness 0.15)
				)
				(justify mirror)
			)
		)
		(property "Manufacturer" "Bourns"
			(at -19.4 352.5 0)
			(layer "B.Fab")
			(hide yes)
			(effects
				(font
					(size 1 1)
					(thickness 0.15)
				)
				(justify mirror)
			)
		)
		(property "Tolerance" "1%"
			(at -19.4 352.5 0)
			(layer "B.Fab")
			(hide yes)
			(effects
				(font
					(size 1 1)
					(thickness 0.15)
				)
				(justify mirror)
			)
		)
		(property "Val" "47k"
			(at -19.4 352.5 0)
			(layer "B.Fab")
			(hide yes)
			(effects
				(font
					(size 1 1)
					(thickness 0.15)
				)
				(justify mirror)
			)
		)
		(sheetname "DC-DC Converters")
		(sheetfile "dc-dc.kicad_sch")
		(attr smd)
		(fp_rect
			(start -0.925 0.47)
			(end 0.925 -0.47)
			(stroke
				(width 0.05)
				(type default)
			)
			(fill no)
			(layer "B.CrtYd")
		)
		(fp_rect
			(start -0.5 0.25)
			(end 0.5 -0.25)
			(stroke
				(width 0.15)
				(type solid)
			)
			(fill no)
			(layer "B.Fab")
		)
		(pad "1" smd roundrect
			(at -0.48 0 270)
			(size 0.59 0.64)
			(layers "B.Cu" "B.Mask" "B.Paste")
			(roundrect_rratio 0.25)
			(net 966 "/DC-DC Converters/EN1")
			(pintype "passive")
		)
		(pad "2" smd roundrect
			(at 0.48 0 270)
			(size 0.59 0.64)
			(layers "B.Cu" "B.Mask" "B.Paste")
			(roundrect_rratio 0.25)
			(net 37 "+3V3_AON")
			(pintype "passive")
		)
	)
	(footprint "antmicro-footprints:C_0201"
		(layer "B.Cu")
		(at 186.723727 121.723727 -45)
		(descr "Capacitor SMD 0201")
		(tags "capacitor SMD 0201")
		(property "Reference" "C162"
			(at -0.493174 0.883883 180)
			(layer "B.SilkS")
			(effects
				(font
					(size 0.7 0.7)
					(thickness 0.15)
				)
				(justify left bottom mirror)
			)
		)
		(property "Value" "C_4u7_0201"
			(at 0 -1.399999 135)
			(layer "B.Fab")
			(effects
				(font
					(size 0.7 0.7)
					(thickness 0.15)
				)
				(justify left bottom mirror)
			)
		)
		(property "Description" "SMD Multilayer Ceramic Capacitor, 4.7 µF, 6.3 V, 0201 [0603 Metric], ± 20%, X5R, GRM Series"
			(at 0 0 315)
			(layer "F.Fab")
			(hide yes)
			(effects
				(font
					(size 1.27 1.27)
					(thickness 0.15)
				)
			)
		)
		(property "Author" "Antmicro"
			(at -31.381559 167.685667 0)
			(layer "B.Fab")
			(hide yes)
			(effects
				(font
					(size 1 1)
					(thickness 0.15)
				)
				(justify mirror)
			)
		)
		(property "Dielectric" ""
			(at -31.381559 167.685667 0)
			(layer "B.Fab")
			(hide yes)
			(effects
				(font
					(size 1 1)
					(thickness 0.15)
				)
				(justify mirror)
			)
		)
		(property "License" "Apache-2.0"
			(at -31.381559 167.685667 0)
			(layer "B.Fab")
			(hide yes)
			(effects
				(font
					(size 1 1)
					(thickness 0.15)
				)
				(justify mirror)
			)
		)
		(property "MPN" "GRM035R60J475ME15D"
			(at -31.381559 167.685667 0)
			(layer "B.Fab")
			(hide yes)
			(effects
				(font
					(size 1 1)
					(thickness 0.15)
				)
				(justify mirror)
			)
		)
		(property "Manufacturer" "Murata"
			(at -31.381559 167.685667 0)
			(layer "B.Fab")
			(hide yes)
			(effects
				(font
					(size 1 1)
					(thickness 0.15)
				)
				(justify mirror)
			)
		)
		(property "Val" "4u7"
			(at -31.381559 167.685667 0)
			(layer "B.Fab")
			(hide yes)
			(effects
				(font
					(size 1 1)
					(thickness 0.15)
				)
				(justify mirror)
			)
		)
		(property "Voltage" ""
			(at -31.381559 167.685667 0)
			(layer "B.Fab")
			(hide yes)
			(effects
				(font
					(size 1 1)
					(thickness 0.15)
				)
				(justify mirror)
			)
		)
		(sheetname "FPGA supply")
		(sheetfile "fpga-supply.kicad_sch")
		(attr smd)
		(fp_poly
			(pts
				(xy -0.7 0.35) (xy 0.7 0.35) (xy 0.7 -0.35) (xy -0.7 -0.35)
			)
			(stroke
				(width 0.05)
				(type default)
			)
			(fill no)
			(layer "B.CrtYd")
		)
		(fp_poly
			(pts
				(xy 0.3 -0.15) (xy -0.301 -0.15) (xy -0.301 0.149) (xy 0.3 0.149)
			)
			(stroke
				(width 0.15)
				(type solid)
			)
			(fill no)
			(layer "B.Fab")
		)
		(pad "" smd roundrect
			(at -0.349 0.002 315)
			(size 0.318 0.36)
			(layers "B.Paste")
			(roundrect_rratio 0.25)
		)
		(pad "" smd roundrect
			(at 0.341 0.002 315)
			(size 0.318 0.36)
			(layers "B.Paste")
			(roundrect_rratio 0.25)
		)
		(pad "1" smd roundrect
			(at -0.321 0.002 315)
			(size 0.46 0.4)
			(layers "B.Cu" "B.Mask")
			(roundrect_rratio 0.25)
			(net 1 "GND")
			(pintype "passive")
		)
		(pad "2" smd roundrect
			(at 0.32 0.002 315)
			(size 0.46 0.4)
			(layers "B.Cu" "B.Mask")
			(roundrect_rratio 0.25)
			(net 8 "+1V2_MGTAVTT")
			(pintype "passive")
		)
	)
	(footprint "antmicro-footprints:NetTie-2_SMD_Pad0.127mm"
		(layer "B.Cu")
		(at 253.301 148.4 -90)
		(descr "Net tie, 2 pin, 0.127mm  SMD pads")
		(tags "net tie")
		(property "Reference" "NT9"
			(at -0.128 1.345 90)
			(layer "B.SilkS")
			(hide yes)
			(effects
				(font
					(size 0.7 0.7)
					(thickness 0.15)
				)
				(justify left bottom mirror)
			)
		)
		(property "Value" "Net-Tie_2"
			(at 0 -1.199 90)
			(layer "B.Fab")
			(effects
				(font
					(size 0.7 0.7)
					(thickness 0.15)
				)
				(justify left bottom mirror)
			)
		)
		(property "Description" "Net tie, 2 pins"
			(at 0 0 270)
			(layer "F.Fab")
			(hide yes)
			(effects
				(font
					(size 1.27 1.27)
					(thickness 0.15)
				)
			)
		)
		(property "Author" "Antmicro"
			(at 104.901 401.701 0)
			(layer "B.Fab")
			(hide yes)
			(effects
				(font
					(size 1 1)
					(thickness 0.15)
				)
				(justify mirror)
			)
		)
		(property "License" "Apache-2.0"
			(at 104.901 401.701 0)
			(layer "B.Fab")
			(hide yes)
			(effects
				(font
					(size 1 1)
					(thickness 0.15)
				)
				(justify mirror)
			)
		)
		(property "MPN" ""
			(at 104.901 401.701 0)
			(layer "B.Fab")
			(hide yes)
			(effects
				(font
					(size 1 1)
					(thickness 0.15)
				)
				(justify mirror)
			)
		)
		(property "Manufacturer" ""
			(at 104.901 401.701 0)
			(layer "B.Fab")
			(hide yes)
			(effects
				(font
					(size 1 1)
					(thickness 0.15)
				)
				(justify mirror)
			)
		)
		(sheetname "FPGA Bank 14 & 15")
		(sheetfile "fpga-bank-14-15.kicad_sch")
		(attr exclude_from_pos_files)
		(net_tie_pad_groups "1, 2")
		(fp_poly
			(pts
				(xy -0.0635 0.0635) (xy 0.0625 0.0635) (xy 0.0625 -0.0635) (xy -0.0635 -0.0635)
			)
			(stroke
				(width 0)
				(type solid)
			)
			(fill yes)
			(layer "B.Cu")
		)
		(pad "1" smd roundrect
			(at -0.127 0 90)
			(size 0.127 0.127)
			(layers "B.Cu")
			(roundrect_rratio 0.5)
			(chamfer_ratio 0)
			(chamfer top_left bottom_left)
			(net 1294 "/USB_SPI.MISO")
			(pinfunction "1")
			(pintype "passive")
		)
		(pad "2" smd roundrect
			(at 0.126 0 270)
			(size 0.127 0.127)
			(layers "B.Cu")
			(roundrect_rratio 0.5)
			(chamfer_ratio 0)
			(chamfer top_left bottom_left)
			(net 1319 "/SUP_MCU.MISO")
			(pinfunction "2")
			(pintype "passive")
		)
	)
	(footprint "antmicro-footprints:C_0402_1005Metric"
		(layer "B.Cu")
		(at 198.325 133.2)
		(descr "Capacitor SMD 0402")
		(tags "capacitor SMD 0402")
		(property "Reference" "C58"
			(at 26.05 -28.1 180)
			(layer "B.SilkS")
			(effects
				(font
					(size 0.7 0.7)
					(thickness 0.15)
				)
				(justify left bottom mirror)
			)
		)
		(property "Value" "C_100n_0402"
			(at 0 -1.169 180)
			(layer "B.Fab")
			(effects
				(font
					(size 0.7 0.7)
					(thickness 0.15)
				)
				(justify left bottom mirror)
			)
		)
		(property "Description" "SMD Multilayer Ceramic Capacitor, 0.1 µF, 50 V, 0402 [1005 Metric], ± 10%, X5R, GRM Series"
			(at 0 0 0)
			(layer "F.Fab")
			(hide yes)
			(effects
				(font
					(size 1.27 1.27)
					(thickness 0.15)
				)
			)
		)
		(property "Author" "Antmicro"
			(at 0 0 0)
			(layer "B.Fab")
			(hide yes)
			(effects
				(font
					(size 1 1)
					(thickness 0.15)
				)
				(justify mirror)
			)
		)
		(property "Dielectric" "X5R"
			(at 0 0 0)
			(layer "B.Fab")
			(hide yes)
			(effects
				(font
					(size 1 1)
					(thickness 0.15)
				)
				(justify mirror)
			)
		)
		(property "License" "Apache-2.0"
			(at 0 0 0)
			(layer "B.Fab")
			(hide yes)
			(effects
				(font
					(size 1 1)
					(thickness 0.15)
				)
				(justify mirror)
			)
		)
		(property "MPN" "GRM155R61H104KE14D"
			(at 0 0 0)
			(layer "B.Fab")
			(hide yes)
			(effects
				(font
					(size 1 1)
					(thickness 0.15)
				)
				(justify mirror)
			)
		)
		(property "Manufacturer" "Murata"
			(at 0 0 0)
			(layer "B.Fab")
			(hide yes)
			(effects
				(font
					(size 1 1)
					(thickness 0.15)
				)
				(justify mirror)
			)
		)
		(property "Val" "100n"
			(at 0 0 0)
			(layer "B.Fab")
			(hide yes)
			(effects
				(font
					(size 1 1)
					(thickness 0.15)
				)
				(justify mirror)
			)
		)
		(property "Voltage" "50V"
			(at 0 0 0)
			(layer "B.Fab")
			(hide yes)
			(effects
				(font
					(size 1 1)
					(thickness 0.15)
				)
				(justify mirror)
			)
		)
		(sheetname "FPGA supply")
		(sheetfile "fpga-supply.kicad_sch")
		(attr smd)
		(fp_rect
			(start -0.925 0.47)
			(end 0.925 -0.47)
			(stroke
				(width 0.05)
				(type default)
			)
			(fill no)
			(layer "B.CrtYd")
		)
		(fp_line
			(start -0.494 -0.248)
			(end -0.494 0.25)
			(stroke
				(width 0.15)
				(type solid)
			)
			(layer "B.Fab")
		)
		(fp_line
			(start -0.494 0.25)
			(end 0.504 0.25)
			(stroke
				(width 0.15)
				(type solid)
			)
			(layer "B.Fab")
		)
		(fp_line
			(start 0.504 -0.248)
			(end -0.494 -0.248)
			(stroke
				(width 0.15)
				(type solid)
			)
			(layer "B.Fab")
		)
		(fp_line
			(start 0.504 0.25)
			(end 0.504 -0.248)
			(stroke
				(width 0.15)
				(type solid)
			)
			(layer "B.Fab")
		)
		(pad "1" smd roundrect
			(at -0.48 0)
			(size 0.59 0.64)
			(layers "B.Cu" "B.Mask" "B.Paste")
			(roundrect_rratio 0.25)
			(net 1 "GND")
			(pintype "passive")
		)
		(pad "2" smd roundrect
			(at 0.48 0)
			(size 0.59 0.64)
			(layers "B.Cu" "B.Mask" "B.Paste")
			(roundrect_rratio 0.25)
			(net 26 "+1V8")
			(pintype "passive")
		)
	)
	(footprint "antmicro-footprints:C_0201"
		(layer "B.Cu")
		(at 201.5 129.65 180)
		(descr "Capacitor SMD 0201")
		(tags "capacitor SMD 0201")
		(property "Reference" "C52"
			(at -26.875 28.875 0)
			(layer "B.SilkS")
			(effects
				(font
					(size 0.7 0.7)
					(thickness 0.15)
				)
				(justify left bottom mirror)
			)
		)
		(property "Value" "C_4u7_0201"
			(at 0 -1.4 0)
			(layer "B.Fab")
			(effects
				(font
					(size 0.7 0.7)
					(thickness 0.15)
				)
				(justify left bottom mirror)
			)
		)
		(property "Description" "SMD Multilayer Ceramic Capacitor, 4.7 µF, 6.3 V, 0201 [0603 Metric], ± 20%, X5R, GRM Series"
			(at 0 0 180)
			(layer "F.Fab")
			(hide yes)
			(effects
				(font
					(size 1.27 1.27)
					(thickness 0.15)
				)
			)
		)
		(property "Author" "Antmicro"
			(at 403 259.3 0)
			(layer "B.Fab")
			(hide yes)
			(effects
				(font
					(size 1 1)
					(thickness 0.15)
				)
				(justify mirror)
			)
		)
		(property "Dielectric" ""
			(at 403 259.3 0)
			(layer "B.Fab")
			(hide yes)
			(effects
				(font
					(size 1 1)
					(thickness 0.15)
				)
				(justify mirror)
			)
		)
		(property "License" "Apache-2.0"
			(at 403 259.3 0)
			(layer "B.Fab")
			(hide yes)
			(effects
				(font
					(size 1 1)
					(thickness 0.15)
				)
				(justify mirror)
			)
		)
		(property "MPN" "GRM035R60J475ME15D"
			(at 403 259.3 0)
			(layer "B.Fab")
			(hide yes)
			(effects
				(font
					(size 1 1)
					(thickness 0.15)
				)
				(justify mirror)
			)
		)
		(property "Manufacturer" "Murata"
			(at 403 259.3 0)
			(layer "B.Fab")
			(hide yes)
			(effects
				(font
					(size 1 1)
					(thickness 0.15)
				)
				(justify mirror)
			)
		)
		(property "Val" "4u7"
			(at 403 259.3 0)
			(layer "B.Fab")
			(hide yes)
			(effects
				(font
					(size 1 1)
					(thickness 0.15)
				)
				(justify mirror)
			)
		)
		(property "Voltage" ""
			(at 403 259.3 0)
			(layer "B.Fab")
			(hide yes)
			(effects
				(font
					(size 1 1)
					(thickness 0.15)
				)
				(justify mirror)
			)
		)
		(sheetname "FPGA supply")
		(sheetfile "fpga-supply.kicad_sch")
		(attr smd)
		(fp_rect
			(start -0.7 0.35)
			(end 0.7 -0.35)
			(stroke
				(width 0.05)
				(type default)
			)
			(fill no)
			(layer "B.CrtYd")
		)
		(fp_rect
			(start 0.3 -0.15)
			(end -0.301 0.149)
			(stroke
				(width 0.15)
				(type solid)
			)
			(fill no)
			(layer "B.Fab")
		)
		(pad "" smd roundrect
			(at -0.349 0.002 180)
			(size 0.318 0.36)
			(layers "B.Paste")
			(roundrect_rratio 0.25)
		)
		(pad "" smd roundrect
			(at 0.341 0.002 180)
			(size 0.318 0.36)
			(layers "B.Paste")
			(roundrect_rratio 0.25)
		)
		(pad "1" smd roundrect
			(at -0.321 0.002 180)
			(size 0.46 0.4)
			(layers "B.Cu" "B.Mask")
			(roundrect_rratio 0.25)
			(net 1 "GND")
			(pintype "passive")
		)
		(pad "2" smd roundrect
			(at 0.32 0.002 180)
			(size 0.46 0.4)
			(layers "B.Cu" "B.Mask")
			(roundrect_rratio 0.25)
			(net 650 "+1V0")
			(pintype "passive")
		)
	)
	(footprint "antmicro-footprints:C_0201"
		(layer "B.Cu")
		(at 188.000001 126.500001 180)
		(descr "Capacitor SMD 0201")
		(tags "capacitor SMD 0201")
		(property "Reference" "C145"
			(at 0.525001 -0.424999 0)
			(layer "B.SilkS")
			(effects
				(font
					(size 0.7 0.7)
					(thickness 0.15)
				)
				(justify left bottom mirror)
			)
		)
		(property "Value" "C_100n_0201"
			(at 0 -1.4 0)
			(layer "B.Fab")
			(effects
				(font
					(size 0.7 0.7)
					(thickness 0.15)
				)
				(justify left bottom mirror)
			)
		)
		(property "Description" "SMD Multilayer Ceramic Capacitor, 0.1 µF, 6.3 V, 0201 [0603 Metric], ± 10%, X6S, CC Series"
			(at 0 0 180)
			(layer "F.Fab")
			(hide yes)
			(effects
				(font
					(size 1.27 1.27)
					(thickness 0.15)
				)
			)
		)
		(property "Author" "Antmicro"
			(at 376.000002 253.000002 0)
			(layer "B.Fab")
			(hide yes)
			(effects
				(font
					(size 1 1)
					(thickness 0.15)
				)
				(justify mirror)
			)
		)
		(property "Dielectric" ""
			(at 376.000002 253.000002 0)
			(layer "B.Fab")
			(hide yes)
			(effects
				(font
					(size 1 1)
					(thickness 0.15)
				)
				(justify mirror)
			)
		)
		(property "License" "Apache-2.0"
			(at 376.000002 253.000002 0)
			(layer "B.Fab")
			(hide yes)
			(effects
				(font
					(size 1 1)
					(thickness 0.15)
				)
				(justify mirror)
			)
		)
		(property "MPN" "CC0201KRX6S5BB104"
			(at 376.000002 253.000002 0)
			(layer "B.Fab")
			(hide yes)
			(effects
				(font
					(size 1 1)
					(thickness 0.15)
				)
				(justify mirror)
			)
		)
		(property "Manufacturer" "YAGEO"
			(at 376.000002 253.000002 0)
			(layer "B.Fab")
			(hide yes)
			(effects
				(font
					(size 1 1)
					(thickness 0.15)
				)
				(justify mirror)
			)
		)
		(property "Val" "100n"
			(at 376.000002 253.000002 0)
			(layer "B.Fab")
			(hide yes)
			(effects
				(font
					(size 1 1)
					(thickness 0.15)
				)
				(justify mirror)
			)
		)
		(property "Voltage" ""
			(at 376.000002 253.000002 0)
			(layer "B.Fab")
			(hide yes)
			(effects
				(font
					(size 1 1)
					(thickness 0.15)
				)
				(justify mirror)
			)
		)
		(sheetname "FPGA supply")
		(sheetfile "fpga-supply.kicad_sch")
		(attr smd)
		(fp_rect
			(start -0.7 0.35)
			(end 0.7 -0.35)
			(stroke
				(width 0.05)
				(type default)
			)
			(fill no)
			(layer "B.CrtYd")
		)
		(fp_rect
			(start 0.3 -0.15)
			(end -0.301 0.149)
			(stroke
				(width 0.15)
				(type solid)
			)
			(fill no)
			(layer "B.Fab")
		)
		(pad "" smd roundrect
			(at -0.349 0.002 180)
			(size 0.318 0.36)
			(layers "B.Paste")
			(roundrect_rratio 0.25)
		)
		(pad "" smd roundrect
			(at 0.341 0.002 180)
			(size 0.318 0.36)
			(layers "B.Paste")
			(roundrect_rratio 0.25)
		)
		(pad "1" smd roundrect
			(at -0.321 0.002 180)
			(size 0.46 0.4)
			(layers "B.Cu" "B.Mask")
			(roundrect_rratio 0.25)
			(net 1 "GND")
			(pintype "passive")
		)
		(pad "2" smd roundrect
			(at 0.32 0.002 180)
			(size 0.46 0.4)
			(layers "B.Cu" "B.Mask")
			(roundrect_rratio 0.25)
			(net 8 "+1V2_MGTAVTT")
			(pintype "passive")
		)
	)
	(footprint "antmicro-footprints:C_0402_1005Metric"
		(layer "B.Cu")
		(at 197 119.5)
		(descr "Capacitor SMD 0402")
		(tags "capacitor SMD 0402")
		(property "Reference" "C88"
			(at 1.125 -0.5 180)
			(layer "B.SilkS")
			(effects
				(font
					(size 0.7 0.7)
					(thickness 0.15)
				)
				(justify left bottom mirror)
			)
		)
		(property "Value" "C_100n_0402"
			(at 0 -1.169 180)
			(layer "B.Fab")
			(effects
				(font
					(size 0.7 0.7)
					(thickness 0.15)
				)
				(justify left bottom mirror)
			)
		)
		(property "Description" "SMD Multilayer Ceramic Capacitor, 0.1 µF, 50 V, 0402 [1005 Metric], ± 10%, X5R, GRM Series"
			(at 0 0 0)
			(layer "F.Fab")
			(hide yes)
			(effects
				(font
					(size 1.27 1.27)
					(thickness 0.15)
				)
			)
		)
		(property "Author" "Antmicro"
			(at 0 0 0)
			(layer "B.Fab")
			(hide yes)
			(effects
				(font
					(size 1 1)
					(thickness 0.15)
				)
				(justify mirror)
			)
		)
		(property "Dielectric" "X5R"
			(at 0 0 0)
			(layer "B.Fab")
			(hide yes)
			(effects
				(font
					(size 1 1)
					(thickness 0.15)
				)
				(justify mirror)
			)
		)
		(property "License" "Apache-2.0"
			(at 0 0 0)
			(layer "B.Fab")
			(hide yes)
			(effects
				(font
					(size 1 1)
					(thickness 0.15)
				)
				(justify mirror)
			)
		)
		(property "MPN" "GRM155R61H104KE14D"
			(at 0 0 0)
			(layer "B.Fab")
			(hide yes)
			(effects
				(font
					(size 1 1)
					(thickness 0.15)
				)
				(justify mirror)
			)
		)
		(property "Manufacturer" "Murata"
			(at 0 0 0)
			(layer "B.Fab")
			(hide yes)
			(effects
				(font
					(size 1 1)
					(thickness 0.15)
				)
				(justify mirror)
			)
		)
		(property "Val" "100n"
			(at 0 0 0)
			(layer "B.Fab")
			(hide yes)
			(effects
				(font
					(size 1 1)
					(thickness 0.15)
				)
				(justify mirror)
			)
		)
		(property "Voltage" "50V"
			(at 0 0 0)
			(layer "B.Fab")
			(hide yes)
			(effects
				(font
					(size 1 1)
					(thickness 0.15)
				)
				(justify mirror)
			)
		)
		(sheetname "FPGA Bank 18 & 32")
		(sheetfile "fpga-bank-18-32.kicad_sch")
		(attr smd)
		(fp_rect
			(start -0.925 0.47)
			(end 0.925 -0.47)
			(stroke
				(width 0.05)
				(type default)
			)
			(fill no)
			(layer "B.CrtYd")
		)
		(fp_line
			(start -0.494 -0.248)
			(end -0.494 0.25)
			(stroke
				(width 0.15)
				(type solid)
			)
			(layer "B.Fab")
		)
		(fp_line
			(start -0.494 0.25)
			(end 0.504 0.25)
			(stroke
				(width 0.15)
				(type solid)
			)
			(layer "B.Fab")
		)
		(fp_line
			(start 0.504 -0.248)
			(end -0.494 -0.248)
			(stroke
				(width 0.15)
				(type solid)
			)
			(layer "B.Fab")
		)
		(fp_line
			(start 0.504 0.25)
			(end 0.504 -0.248)
			(stroke
				(width 0.15)
				(type solid)
			)
			(layer "B.Fab")
		)
		(pad "1" smd roundrect
			(at -0.48 0)
			(size 0.59 0.64)
			(layers "B.Cu" "B.Mask" "B.Paste")
			(roundrect_rratio 0.25)
			(net 1 "GND")
			(pintype "passive")
		)
		(pad "2" smd roundrect
			(at 0.48 0)
			(size 0.59 0.64)
			(layers "B.Cu" "B.Mask" "B.Paste")
			(roundrect_rratio 0.25)
			(net 24 "+3V3")
			(pintype "passive")
		)
	)
	(footprint "antmicro-footprints:R_0402_1005Metric"
		(layer "B.Cu")
		(at 233.8 148.9)
		(descr "Resistor SMD 0402")
		(tags "resistor SMD 0402")
		(property "Reference" "R195"
			(at -0.7 0.375 180)
			(layer "B.SilkS")
			(effects
				(font
					(size 0.7 0.7)
					(thickness 0.15)
				)
				(justify left bottom mirror)
			)
		)
		(property "Value" "R_10k_0402"
			(at 0 -1.4 180)
			(layer "B.Fab")
			(effects
				(font
					(size 0.7 0.7)
					(thickness 0.15)
				)
				(justify left bottom mirror)
			)
		)
		(property "Description" "SMD Chip Resistor, 10 kohm, ± 1%, 62.5 mW, 0402 [1005 Metric], Thick Film, General Purpose"
			(at 0 0 0)
			(layer "F.Fab")
			(hide yes)
			(effects
				(font
					(size 1.27 1.27)
					(thickness 0.15)
				)
			)
		)
		(property "Author" "Antmicro"
			(at 0 0 0)
			(layer "B.Fab")
			(hide yes)
			(effects
				(font
					(size 1 1)
					(thickness 0.15)
				)
				(justify mirror)
			)
		)
		(property "License" "Apache-2.0"
			(at 0 0 0)
			(layer "B.Fab")
			(hide yes)
			(effects
				(font
					(size 1 1)
					(thickness 0.15)
				)
				(justify mirror)
			)
		)
		(property "MPN" "CR0402-FX-1002GLF"
			(at 0 0 0)
			(layer "B.Fab")
			(hide yes)
			(effects
				(font
					(size 1 1)
					(thickness 0.15)
				)
				(justify mirror)
			)
		)
		(property "Manufacturer" "Bourns"
			(at 0 0 0)
			(layer "B.Fab")
			(hide yes)
			(effects
				(font
					(size 1 1)
					(thickness 0.15)
				)
				(justify mirror)
			)
		)
		(property "Tolerance" "1%"
			(at 0 0 0)
			(layer "B.Fab")
			(hide yes)
			(effects
				(font
					(size 1 1)
					(thickness 0.15)
				)
				(justify mirror)
			)
		)
		(property "Val" "10k"
			(at 0 0 0)
			(layer "B.Fab")
			(hide yes)
			(effects
				(font
					(size 1 1)
					(thickness 0.15)
				)
				(justify mirror)
			)
		)
		(sheetname "USB PHY")
		(sheetfile "usb-phy.kicad_sch")
		(attr smd)
		(fp_rect
			(start -0.925 0.47)
			(end 0.925 -0.47)
			(stroke
				(width 0.05)
				(type default)
			)
			(fill no)
			(layer "B.CrtYd")
		)
		(fp_rect
			(start -0.5 0.25)
			(end 0.5 -0.25)
			(stroke
				(width 0.15)
				(type solid)
			)
			(fill no)
			(layer "B.Fab")
		)
		(pad "1" smd roundrect
			(at -0.48 0)
			(size 0.59 0.64)
			(layers "B.Cu" "B.Mask" "B.Paste")
			(roundrect_rratio 0.25)
			(net 500 "/FPGA Bank 12 & 13/USB_USER.SUS")
			(pintype "passive")
		)
		(pad "2" smd roundrect
			(at 0.48 0)
			(size 0.59 0.64)
			(layers "B.Cu" "B.Mask" "B.Paste")
			(roundrect_rratio 0.25)
			(net 26 "+1V8")
			(pintype "passive")
		)
	)
	(footprint "antmicro-footprints:C_0402_1005Metric"
		(layer "B.Cu")
		(at 205 141.5)
		(descr "Capacitor SMD 0402")
		(tags "capacitor SMD 0402")
		(property "Reference" "C17"
			(at 1.1 -0.425 180)
			(layer "B.SilkS")
			(effects
				(font
					(size 0.7 0.7)
					(thickness 0.15)
				)
				(justify left bottom mirror)
			)
		)
		(property "Value" "C_100n_0402"
			(at 0 -1.169 180)
			(layer "B.Fab")
			(effects
				(font
					(size 0.7 0.7)
					(thickness 0.15)
				)
				(justify left bottom mirror)
			)
		)
		(property "Description" "SMD Multilayer Ceramic Capacitor, 0.1 µF, 50 V, 0402 [1005 Metric], ± 10%, X5R, GRM Series"
			(at 0 0 0)
			(layer "F.Fab")
			(hide yes)
			(effects
				(font
					(size 1.27 1.27)
					(thickness 0.15)
				)
			)
		)
		(property "Author" "Antmicro"
			(at 0 0 0)
			(layer "B.Fab")
			(hide yes)
			(effects
				(font
					(size 1 1)
					(thickness 0.15)
				)
				(justify mirror)
			)
		)
		(property "Dielectric" "X5R"
			(at 0 0 0)
			(layer "B.Fab")
			(hide yes)
			(effects
				(font
					(size 1 1)
					(thickness 0.15)
				)
				(justify mirror)
			)
		)
		(property "License" "Apache-2.0"
			(at 0 0 0)
			(layer "B.Fab")
			(hide yes)
			(effects
				(font
					(size 1 1)
					(thickness 0.15)
				)
				(justify mirror)
			)
		)
		(property "MPN" "GRM155R61H104KE14D"
			(at 0 0 0)
			(layer "B.Fab")
			(hide yes)
			(effects
				(font
					(size 1 1)
					(thickness 0.15)
				)
				(justify mirror)
			)
		)
		(property "Manufacturer" "Murata"
			(at 0 0 0)
			(layer "B.Fab")
			(hide yes)
			(effects
				(font
					(size 1 1)
					(thickness 0.15)
				)
				(justify mirror)
			)
		)
		(property "Val" "100n"
			(at 0 0 0)
			(layer "B.Fab")
			(hide yes)
			(effects
				(font
					(size 1 1)
					(thickness 0.15)
				)
				(justify mirror)
			)
		)
		(property "Voltage" "50V"
			(at 0 0 0)
			(layer "B.Fab")
			(hide yes)
			(effects
				(font
					(size 1 1)
					(thickness 0.15)
				)
				(justify mirror)
			)
		)
		(sheetname "FPGA Bank 12 & 13")
		(sheetfile "fpga-bank-12-13.kicad_sch")
		(attr smd)
		(fp_rect
			(start -0.925 0.47)
			(end 0.925 -0.47)
			(stroke
				(width 0.05)
				(type default)
			)
			(fill no)
			(layer "B.CrtYd")
		)
		(fp_line
			(start -0.494 -0.248)
			(end -0.494 0.25)
			(stroke
				(width 0.15)
				(type solid)
			)
			(layer "B.Fab")
		)
		(fp_line
			(start -0.494 0.25)
			(end 0.504 0.25)
			(stroke
				(width 0.15)
				(type solid)
			)
			(layer "B.Fab")
		)
		(fp_line
			(start 0.504 -0.248)
			(end -0.494 -0.248)
			(stroke
				(width 0.15)
				(type solid)
			)
			(layer "B.Fab")
		)
		(fp_line
			(start 0.504 0.25)
			(end 0.504 -0.248)
			(stroke
				(width 0.15)
				(type solid)
			)
			(layer "B.Fab")
		)
		(pad "1" smd roundrect
			(at -0.48 0)
			(size 0.59 0.64)
			(layers "B.Cu" "B.Mask" "B.Paste")
			(roundrect_rratio 0.25)
			(net 1 "GND")
			(pintype "passive")
		)
		(pad "2" smd roundrect
			(at 0.48 0)
			(size 0.59 0.64)
			(layers "B.Cu" "B.Mask" "B.Paste")
			(roundrect_rratio 0.25)
			(net 24 "+3V3")
			(pintype "passive")
		)
	)
	(footprint "antmicro-footprints:R_0603_1608Metric"
		(layer "B.Cu")
		(at 262.401 152.5 180)
		(descr "Resistor SMD 0603")
		(tags "resistor SMD 0603")
		(property "Reference" "R252"
			(at -1.374 0.55 0)
			(layer "B.SilkS")
			(effects
				(font
					(size 0.7 0.7)
					(thickness 0.15)
				)
				(justify left bottom mirror)
			)
		)
		(property "Value" "R_220R_0603"
			(at 0 -1.6 0)
			(layer "B.Fab")
			(effects
				(font
					(size 0.7 0.7)
					(thickness 0.15)
				)
				(justify left bottom mirror)
			)
		)
		(property "Description" "SMD Chip Resistor, 220 ohm, ± 1%, 100 mW, 0603 [1608 Metric], Thick Film, General Purpose"
			(at 0 0 180)
			(layer "F.Fab")
			(hide yes)
			(effects
				(font
					(size 1.27 1.27)
					(thickness 0.15)
				)
			)
		)
		(property "Author" "Antmicro"
			(at 524.802 305 0)
			(layer "B.Fab")
			(hide yes)
			(effects
				(font
					(size 1 1)
					(thickness 0.15)
				)
				(justify mirror)
			)
		)
		(property "License" "Apache-2.0"
			(at 524.802 305 0)
			(layer "B.Fab")
			(hide yes)
			(effects
				(font
					(size 1 1)
					(thickness 0.15)
				)
				(justify mirror)
			)
		)
		(property "MPN" "CR0603-FX-2200ELF"
			(at 524.802 305 0)
			(layer "B.Fab")
			(hide yes)
			(effects
				(font
					(size 1 1)
					(thickness 0.15)
				)
				(justify mirror)
			)
		)
		(property "Manufacturer" "Bourns"
			(at 524.802 305 0)
			(layer "B.Fab")
			(hide yes)
			(effects
				(font
					(size 1 1)
					(thickness 0.15)
				)
				(justify mirror)
			)
		)
		(property "Tolerance" "1%"
			(at 524.802 305 0)
			(layer "B.Fab")
			(hide yes)
			(effects
				(font
					(size 1 1)
					(thickness 0.15)
				)
				(justify mirror)
			)
		)
		(property "Val" "220R"
			(at 524.802 305 0)
			(layer "B.Fab")
			(hide yes)
			(effects
				(font
					(size 1 1)
					(thickness 0.15)
				)
				(justify mirror)
			)
		)
		(sheetname "HDMI + Ethernet")
		(sheetfile "hdmi-ethernet.kicad_sch")
		(attr smd)
		(fp_line
			(start -0.15 0.4)
			(end 0.15 0.4)
			(stroke
				(width 0.15)
				(type solid)
			)
			(layer "B.SilkS")
		)
		(fp_line
			(start -0.15 -0.4)
			(end 0.15 -0.4)
			(stroke
				(width 0.15)
				(type solid)
			)
			(layer "B.SilkS")
		)
		(fp_rect
			(start -1.25 0.65)
			(end 1.25 -0.65)
			(stroke
				(width 0.05)
				(type solid)
			)
			(fill no)
			(layer "B.CrtYd")
		)
		(fp_rect
			(start -0.8 0.4)
			(end 0.8 -0.4)
			(stroke
				(width 0.15)
				(type solid)
			)
			(fill no)
			(layer "B.Fab")
		)
		(pad "1" smd roundrect
			(at -0.7 0 180)
			(size 0.8 1)
			(layers "B.Cu" "B.Mask" "B.Paste")
			(roundrect_rratio 0.2)
			(net 848 "/HDMI + Ethernet/ETH_LED_SPD+")
			(pintype "passive")
		)
		(pad "2" smd roundrect
			(at 0.7 0 180)
			(size 0.8 1)
			(layers "B.Cu" "B.Mask" "B.Paste")
			(roundrect_rratio 0.2)
			(net 24 "+3V3")
			(pintype "passive")
		)
	)
	(footprint "antmicro-footprints:R_0402_1005Metric"
		(layer "B.Cu")
		(at 191.9 84.8 90)
		(descr "Resistor SMD 0402")
		(tags "resistor SMD 0402")
		(property "Reference" "R138"
			(at -0.725 0.4 270)
			(layer "B.SilkS")
			(effects
				(font
					(size 0.7 0.7)
					(thickness 0.15)
				)
				(justify left bottom mirror)
			)
		)
		(property "Value" "R_100R_0402"
			(at 0 -1.4 270)
			(layer "B.Fab")
			(effects
				(font
					(size 0.7 0.7)
					(thickness 0.15)
				)
				(justify left bottom mirror)
			)
		)
		(property "Description" "SMD Chip Resistor, 100 ohm, ± 1%, 62.5 mW, 0402 [1005 Metric], Thick Film, General Purpose"
			(at 0 0 90)
			(layer "F.Fab")
			(hide yes)
			(effects
				(font
					(size 1.27 1.27)
					(thickness 0.15)
				)
			)
		)
		(property "Author" "Antmicro"
			(at 276.7 -107.1 0)
			(layer "B.Fab")
			(hide yes)
			(effects
				(font
					(size 1 1)
					(thickness 0.15)
				)
				(justify mirror)
			)
		)
		(property "License" "Apache-2.0"
			(at 276.7 -107.1 0)
			(layer "B.Fab")
			(hide yes)
			(effects
				(font
					(size 1 1)
					(thickness 0.15)
				)
				(justify mirror)
			)
		)
		(property "MPN" "CR0402-FX-1000GLF"
			(at 276.7 -107.1 0)
			(layer "B.Fab")
			(hide yes)
			(effects
				(font
					(size 1 1)
					(thickness 0.15)
				)
				(justify mirror)
			)
		)
		(property "Manufacturer" "Bourns"
			(at 276.7 -107.1 0)
			(layer "B.Fab")
			(hide yes)
			(effects
				(font
					(size 1 1)
					(thickness 0.15)
				)
				(justify mirror)
			)
		)
		(property "Tolerance" "1%"
			(at 276.7 -107.1 0)
			(layer "B.Fab")
			(hide yes)
			(effects
				(font
					(size 1 1)
					(thickness 0.15)
				)
				(justify mirror)
			)
		)
		(property "Val" "100R"
			(at 276.7 -107.1 0)
			(layer "B.Fab")
			(hide yes)
			(effects
				(font
					(size 1 1)
					(thickness 0.15)
				)
				(justify mirror)
			)
		)
		(sheetname "User GPIO + LED + button + DIP switch")
		(sheetfile "user-gpio.kicad_sch")
		(attr smd)
		(fp_rect
			(start -0.925 0.47)
			(end 0.925 -0.47)
			(stroke
				(width 0.05)
				(type default)
			)
			(fill no)
			(layer "B.CrtYd")
		)
		(fp_rect
			(start -0.5 0.25)
			(end 0.5 -0.25)
			(stroke
				(width 0.15)
				(type solid)
			)
			(fill no)
			(layer "B.Fab")
		)
		(pad "1" smd roundrect
			(at -0.48 0 90)
			(size 0.59 0.64)
			(layers "B.Cu" "B.Mask" "B.Paste")
			(roundrect_rratio 0.25)
			(net 830 "/User GPIO + LED + button + DIP switch/CW_20PIN_TPDIC")
			(pintype "passive")
		)
		(pad "2" smd roundrect
			(at 0.48 0 90)
			(size 0.59 0.64)
			(layers "B.Cu" "B.Mask" "B.Paste")
			(roundrect_rratio 0.25)
			(net 480 "/FPGA Bank 12 & 13/CW_HEADER.TPDIC")
			(pintype "passive")
		)
	)
	(footprint "antmicro-footprints:C_0201"
		(layer "B.Cu")
		(at 184.350001 131.500001)
		(descr "Capacitor SMD 0201")
		(tags "capacitor SMD 0201")
		(property "Reference" "C160"
			(at -3.375001 0.374999 0)
			(layer "B.SilkS")
			(effects
				(font
					(size 0.7 0.7)
					(thickness 0.15)
				)
				(justify right bottom mirror)
			)
		)
		(property "Value" "C_4u7_0201"
			(at 0 -1.4 0)
			(layer "B.Fab")
			(effects
				(font
					(size 0.7 0.7)
					(thickness 0.15)
				)
				(justify right bottom mirror)
			)
		)
		(property "Description" "SMD Multilayer Ceramic Capacitor, 4.7 µF, 6.3 V, 0201 [0603 Metric], ± 20%, X5R, GRM Series"
			(at 0 0 0)
			(layer "F.Fab")
			(hide yes)
			(effects
				(font
					(size 1.27 1.27)
					(thickness 0.15)
				)
			)
		)
		(property "Author" "Antmicro"
			(at 0 0 0)
			(layer "B.Fab")
			(hide yes)
			(effects
				(font
					(size 1 1)
					(thickness 0.15)
				)
				(justify mirror)
			)
		)
		(property "Dielectric" ""
			(at 0 0 0)
			(layer "B.Fab")
			(hide yes)
			(effects
				(font
					(size 1 1)
					(thickness 0.15)
				)
				(justify mirror)
			)
		)
		(property "License" "Apache-2.0"
			(at 0 0 0)
			(layer "B.Fab")
			(hide yes)
			(effects
				(font
					(size 1 1)
					(thickness 0.15)
				)
				(justify mirror)
			)
		)
		(property "MPN" "GRM035R60J475ME15D"
			(at 0 0 0)
			(layer "B.Fab")
			(hide yes)
			(effects
				(font
					(size 1 1)
					(thickness 0.15)
				)
				(justify mirror)
			)
		)
		(property "Manufacturer" "Murata"
			(at 0 0 0)
			(layer "B.Fab")
			(hide yes)
			(effects
				(font
					(size 1 1)
					(thickness 0.15)
				)
				(justify mirror)
			)
		)
		(property "Val" "4u7"
			(at 0 0 0)
			(layer "B.Fab")
			(hide yes)
			(effects
				(font
					(size 1 1)
					(thickness 0.15)
				)
				(justify mirror)
			)
		)
		(property "Voltage" ""
			(at 0 0 0)
			(layer "B.Fab")
			(hide yes)
			(effects
				(font
					(size 1 1)
					(thickness 0.15)
				)
				(justify mirror)
			)
		)
		(sheetname "FPGA supply")
		(sheetfile "fpga-supply.kicad_sch")
		(attr smd)
		(fp_rect
			(start -0.7 0.35)
			(end 0.7 -0.35)
			(stroke
				(width 0.05)
				(type default)
			)
			(fill no)
			(layer "B.CrtYd")
		)
		(fp_rect
			(start 0.3 -0.15)
			(end -0.301 0.149)
			(stroke
				(width 0.15)
				(type solid)
			)
			(fill no)
			(layer "B.Fab")
		)
		(pad "" smd roundrect
			(at -0.349 0.002)
			(size 0.318 0.36)
			(layers "B.Paste")
			(roundrect_rratio 0.25)
		)
		(pad "" smd roundrect
			(at 0.341 0.002)
			(size 0.318 0.36)
			(layers "B.Paste")
			(roundrect_rratio 0.25)
		)
		(pad "1" smd roundrect
			(at -0.321 0.002)
			(size 0.46 0.4)
			(layers "B.Cu" "B.Mask")
			(roundrect_rratio 0.25)
			(net 1 "GND")
			(pintype "passive")
		)
		(pad "2" smd roundrect
			(at 0.32 0.002)
			(size 0.46 0.4)
			(layers "B.Cu" "B.Mask")
			(roundrect_rratio 0.25)
			(net 8 "+1V2_MGTAVTT")
			(pintype "passive")
		)
	)
	(footprint "antmicro-footprints:C_0402_1005Metric"
		(layer "B.Cu")
		(at 198 143.5)
		(descr "Capacitor SMD 0402")
		(tags "capacitor SMD 0402")
		(property "Reference" "C94"
			(at 1.1 1.225 180)
			(layer "B.SilkS")
			(effects
				(font
					(size 0.7 0.7)
					(thickness 0.15)
				)
				(justify left bottom mirror)
			)
		)
		(property "Value" "C_100n_0402"
			(at 0 -1.169 180)
			(layer "B.Fab")
			(effects
				(font
					(size 0.7 0.7)
					(thickness 0.15)
				)
				(justify left bottom mirror)
			)
		)
		(property "Description" "SMD Multilayer Ceramic Capacitor, 0.1 µF, 50 V, 0402 [1005 Metric], ± 10%, X5R, GRM Series"
			(at 0 0 0)
			(layer "F.Fab")
			(hide yes)
			(effects
				(font
					(size 1.27 1.27)
					(thickness 0.15)
				)
			)
		)
		(property "Author" "Antmicro"
			(at 0 0 0)
			(layer "B.Fab")
			(hide yes)
			(effects
				(font
					(size 1 1)
					(thickness 0.15)
				)
				(justify mirror)
			)
		)
		(property "Dielectric" "X5R"
			(at 0 0 0)
			(layer "B.Fab")
			(hide yes)
			(effects
				(font
					(size 1 1)
					(thickness 0.15)
				)
				(justify mirror)
			)
		)
		(property "License" "Apache-2.0"
			(at 0 0 0)
			(layer "B.Fab")
			(hide yes)
			(effects
				(font
					(size 1 1)
					(thickness 0.15)
				)
				(justify mirror)
			)
		)
		(property "MPN" "GRM155R61H104KE14D"
			(at 0 0 0)
			(layer "B.Fab")
			(hide yes)
			(effects
				(font
					(size 1 1)
					(thickness 0.15)
				)
				(justify mirror)
			)
		)
		(property "Manufacturer" "Murata"
			(at 0 0 0)
			(layer "B.Fab")
			(hide yes)
			(effects
				(font
					(size 1 1)
					(thickness 0.15)
				)
				(justify mirror)
			)
		)
		(property "Val" "100n"
			(at 0 0 0)
			(layer "B.Fab")
			(hide yes)
			(effects
				(font
					(size 1 1)
					(thickness 0.15)
				)
				(justify mirror)
			)
		)
		(property "Voltage" "50V"
			(at 0 0 0)
			(layer "B.Fab")
			(hide yes)
			(effects
				(font
					(size 1 1)
					(thickness 0.15)
				)
				(justify mirror)
			)
		)
		(sheetname "FPGA Bank 18 & 32")
		(sheetfile "fpga-bank-18-32.kicad_sch")
		(attr smd)
		(fp_rect
			(start -0.925 0.47)
			(end 0.925 -0.47)
			(stroke
				(width 0.05)
				(type default)
			)
			(fill no)
			(layer "B.CrtYd")
		)
		(fp_line
			(start -0.494 -0.248)
			(end -0.494 0.25)
			(stroke
				(width 0.15)
				(type solid)
			)
			(layer "B.Fab")
		)
		(fp_line
			(start -0.494 0.25)
			(end 0.504 0.25)
			(stroke
				(width 0.15)
				(type solid)
			)
			(layer "B.Fab")
		)
		(fp_line
			(start 0.504 -0.248)
			(end -0.494 -0.248)
			(stroke
				(width 0.15)
				(type solid)
			)
			(layer "B.Fab")
		)
		(fp_line
			(start 0.504 0.25)
			(end 0.504 -0.248)
			(stroke
				(width 0.15)
				(type solid)
			)
			(layer "B.Fab")
		)
		(pad "1" smd roundrect
			(at -0.48 0)
			(size 0.59 0.64)
			(layers "B.Cu" "B.Mask" "B.Paste")
			(roundrect_rratio 0.25)
			(net 1 "GND")
			(pintype "passive")
		)
		(pad "2" smd roundrect
			(at 0.48 0)
			(size 0.59 0.64)
			(layers "B.Cu" "B.Mask" "B.Paste")
			(roundrect_rratio 0.25)
			(net 26 "+1V8")
			(pintype "passive")
		)
	)
	(footprint "antmicro-footprints:R_0402_1005Metric"
		(layer "B.Cu")
		(at 237.599999 84.699999 -90)
		(descr "Resistor SMD 0402")
		(tags "resistor SMD 0402")
		(property "Reference" "R116"
			(at 0.750001 -0.425001 90)
			(layer "B.SilkS")
			(effects
				(font
					(size 0.7 0.7)
					(thickness 0.15)
				)
				(justify left bottom mirror)
			)
		)
		(property "Value" "R_100R_0402"
			(at 0 -1.4 90)
			(layer "B.Fab")
			(effects
				(font
					(size 0.7 0.7)
					(thickness 0.15)
				)
				(justify left bottom mirror)
			)
		)
		(property "Description" "SMD Chip Resistor, 100 ohm, ± 1%, 62.5 mW, 0402 [1005 Metric], Thick Film, General Purpose"
			(at 0 0 270)
			(layer "F.Fab")
			(hide yes)
			(effects
				(font
					(size 1.27 1.27)
					(thickness 0.15)
				)
			)
		)
		(property "Author" "Antmicro"
			(at 152.9 322.299998 0)
			(layer "B.Fab")
			(hide yes)
			(effects
				(font
					(size 1 1)
					(thickness 0.15)
				)
				(justify mirror)
			)
		)
		(property "License" "Apache-2.0"
			(at 152.9 322.299998 0)
			(layer "B.Fab")
			(hide yes)
			(effects
				(font
					(size 1 1)
					(thickness 0.15)
				)
				(justify mirror)
			)
		)
		(property "MPN" "CR0402-FX-1000GLF"
			(at 152.9 322.299998 0)
			(layer "B.Fab")
			(hide yes)
			(effects
				(font
					(size 1 1)
					(thickness 0.15)
				)
				(justify mirror)
			)
		)
		(property "Manufacturer" "Bourns"
			(at 152.9 322.299998 0)
			(layer "B.Fab")
			(hide yes)
			(effects
				(font
					(size 1 1)
					(thickness 0.15)
				)
				(justify mirror)
			)
		)
		(property "Tolerance" "1%"
			(at 152.9 322.299998 0)
			(layer "B.Fab")
			(hide yes)
			(effects
				(font
					(size 1 1)
					(thickness 0.15)
				)
				(justify mirror)
			)
		)
		(property "Val" "100R"
			(at 152.9 322.299998 0)
			(layer "B.Fab")
			(hide yes)
			(effects
				(font
					(size 1 1)
					(thickness 0.15)
				)
				(justify mirror)
			)
		)
		(sheetname "User GPIO + LED + button + DIP switch")
		(sheetfile "user-gpio.kicad_sch")
		(attr smd)
		(fp_rect
			(start -0.925 0.47)
			(end 0.925 -0.47)
			(stroke
				(width 0.05)
				(type default)
			)
			(fill no)
			(layer "B.CrtYd")
		)
		(fp_rect
			(start -0.5 0.25)
			(end 0.5 -0.25)
			(stroke
				(width 0.15)
				(type solid)
			)
			(fill no)
			(layer "B.Fab")
		)
		(pad "1" smd roundrect
			(at -0.48 0 270)
			(size 0.59 0.64)
			(layers "B.Cu" "B.Mask" "B.Paste")
			(roundrect_rratio 0.25)
			(net 816 "/User GPIO + LED + button + DIP switch/PMOD_B_7")
			(pintype "passive")
		)
		(pad "2" smd roundrect
			(at 0.48 0 270)
			(size 0.59 0.64)
			(layers "B.Cu" "B.Mask" "B.Paste")
			(roundrect_rratio 0.25)
			(net 442 "/FPGA Bank 12 & 13/PMOD_B.IO7")
			(pintype "passive")
		)
	)
	(footprint "antmicro-footprints:C_0402_1005Metric"
		(layer "B.Cu")
		(at 260.301 123 90)
		(descr "Capacitor SMD 0402")
		(tags "capacitor SMD 0402")
		(property "Reference" "C402"
			(at 1.45 1.274 270)
			(layer "B.SilkS")
			(effects
				(font
					(size 0.7 0.7)
					(thickness 0.15)
				)
				(justify left bottom mirror)
			)
		)
		(property "Value" "C_100n_0402"
			(at 0 -1.169 270)
			(layer "B.Fab")
			(effects
				(font
					(size 0.7 0.7)
					(thickness 0.15)
				)
				(justify left bottom mirror)
			)
		)
		(property "Description" "SMD Multilayer Ceramic Capacitor, 0.1 µF, 50 V, 0402 [1005 Metric], ± 10%, X5R, GRM Series"
			(at 0 0 90)
			(layer "F.Fab")
			(hide yes)
			(effects
				(font
					(size 1.27 1.27)
					(thickness 0.15)
				)
			)
		)
		(property "Author" "Antmicro"
			(at 383.301 -137.301 0)
			(layer "B.Fab")
			(hide yes)
			(effects
				(font
					(size 1 1)
					(thickness 0.15)
				)
				(justify mirror)
			)
		)
		(property "Dielectric" "X5R"
			(at 383.301 -137.301 0)
			(layer "B.Fab")
			(hide yes)
			(effects
				(font
					(size 1 1)
					(thickness 0.15)
				)
				(justify mirror)
			)
		)
		(property "License" "Apache-2.0"
			(at 383.301 -137.301 0)
			(layer "B.Fab")
			(hide yes)
			(effects
				(font
					(size 1 1)
					(thickness 0.15)
				)
				(justify mirror)
			)
		)
		(property "MPN" "GRM155R61H104KE14D"
			(at 383.301 -137.301 0)
			(layer "B.Fab")
			(hide yes)
			(effects
				(font
					(size 1 1)
					(thickness 0.15)
				)
				(justify mirror)
			)
		)
		(property "Manufacturer" "Murata"
			(at 383.301 -137.301 0)
			(layer "B.Fab")
			(hide yes)
			(effects
				(font
					(size 1 1)
					(thickness 0.15)
				)
				(justify mirror)
			)
		)
		(property "Val" "100n"
			(at 383.301 -137.301 0)
			(layer "B.Fab")
			(hide yes)
			(effects
				(font
					(size 1 1)
					(thickness 0.15)
				)
				(justify mirror)
			)
		)
		(property "Voltage" "50V"
			(at 383.301 -137.301 0)
			(layer "B.Fab")
			(hide yes)
			(effects
				(font
					(size 1 1)
					(thickness 0.15)
				)
				(justify mirror)
			)
		)
		(sheetname "USB PHY")
		(sheetfile "usb-phy.kicad_sch")
		(attr smd)
		(fp_rect
			(start -0.925 0.47)
			(end 0.925 -0.47)
			(stroke
				(width 0.05)
				(type default)
			)
			(fill no)
			(layer "B.CrtYd")
		)
		(fp_line
			(start 0.504 -0.248)
			(end -0.494 -0.248)
			(stroke
				(width 0.15)
				(type solid)
			)
			(layer "B.Fab")
		)
		(fp_line
			(start -0.494 -0.248)
			(end -0.494 0.25)
			(stroke
				(width 0.15)
				(type solid)
			)
			(layer "B.Fab")
		)
		(fp_line
			(start 0.504 0.25)
			(end 0.504 -0.248)
			(stroke
				(width 0.15)
				(type solid)
			)
			(layer "B.Fab")
		)
		(fp_line
			(start -0.494 0.25)
			(end 0.504 0.25)
			(stroke
				(width 0.15)
				(type solid)
			)
			(layer "B.Fab")
		)
		(pad "1" smd roundrect
			(at -0.48 0 90)
			(size 0.59 0.64)
			(layers "B.Cu" "B.Mask" "B.Paste")
			(roundrect_rratio 0.25)
			(net 1 "GND")
			(pintype "passive")
		)
		(pad "2" smd roundrect
			(at 0.48 0 90)
			(size 0.59 0.64)
			(layers "B.Cu" "B.Mask" "B.Paste")
			(roundrect_rratio 0.25)
			(net 24 "+3V3")
			(pintype "passive")
		)
	)
	(footprint "antmicro-footprints:C_0402_1005Metric"
		(layer "B.Cu")
		(at 167.145001 83.635001 180)
		(descr "Capacitor SMD 0402")
		(tags "capacitor SMD 0402")
		(property "Reference" "C299"
			(at 0.820001 -0.389999 0)
			(layer "B.SilkS")
			(effects
				(font
					(size 0.7 0.7)
					(thickness 0.15)
				)
				(justify left bottom mirror)
			)
		)
		(property "Value" "C_100n_0402"
			(at 0 -1.4 0)
			(layer "B.Fab")
			(effects
				(font
					(size 0.7 0.7)
					(thickness 0.15)
				)
				(justify left bottom mirror)
			)
		)
		(property "Description" "SMD Multilayer Ceramic Capacitor, 0.1 µF, 50 V, 0402 [1005 Metric], ± 10%, X5R, GRM Series"
			(at 0 0 180)
			(layer "F.Fab")
			(hide yes)
			(effects
				(font
					(size 1.27 1.27)
					(thickness 0.15)
				)
			)
		)
		(property "Author" "Antmicro"
			(at 334.290002 167.270002 0)
			(layer "B.Fab")
			(hide yes)
			(effects
				(font
					(size 1 1)
					(thickness 0.15)
				)
				(justify mirror)
			)
		)
		(property "Dielectric" "X5R"
			(at 334.290002 167.270002 0)
			(layer "B.Fab")
			(hide yes)
			(effects
				(font
					(size 1 1)
					(thickness 0.15)
				)
				(justify mirror)
			)
		)
		(property "License" "Apache-2.0"
			(at 334.290002 167.270002 0)
			(layer "B.Fab")
			(hide yes)
			(effects
				(font
					(size 1 1)
					(thickness 0.15)
				)
				(justify mirror)
			)
		)
		(property "MPN" "GRM155R61H104KE14D"
			(at 334.290002 167.270002 0)
			(layer "B.Fab")
			(hide yes)
			(effects
				(font
					(size 1 1)
					(thickness 0.15)
				)
				(justify mirror)
			)
		)
		(property "Manufacturer" "Murata"
			(at 334.290002 167.270002 0)
			(layer "B.Fab")
			(hide yes)
			(effects
				(font
					(size 1 1)
					(thickness 0.15)
				)
				(justify mirror)
			)
		)
		(property "Val" "100n"
			(at 334.290002 167.270002 0)
			(layer "B.Fab")
			(hide yes)
			(effects
				(font
					(size 1 1)
					(thickness 0.15)
				)
				(justify mirror)
			)
		)
		(property "Voltage" "50V"
			(at 334.290002 167.270002 0)
			(layer "B.Fab")
			(hide yes)
			(effects
				(font
					(size 1 1)
					(thickness 0.15)
				)
				(justify mirror)
			)
		)
		(sheetname "FMC+ HSPC")
		(sheetfile "fmc-hspc.kicad_sch")
		(attr smd)
		(fp_rect
			(start -0.925 0.47)
			(end 0.925 -0.47)
			(stroke
				(width 0.05)
				(type default)
			)
			(fill no)
			(layer "B.CrtYd")
		)
		(fp_line
			(start 0.504 0.25)
			(end 0.504 -0.248)
			(stroke
				(width 0.15)
				(type solid)
			)
			(layer "B.Fab")
		)
		(fp_line
			(start 0.504 -0.248)
			(end -0.494 -0.248)
			(stroke
				(width 0.15)
				(type solid)
			)
			(layer "B.Fab")
		)
		(fp_line
			(start -0.494 0.25)
			(end 0.504 0.25)
			(stroke
				(width 0.15)
				(type solid)
			)
			(layer "B.Fab")
		)
		(fp_line
			(start -0.494 -0.248)
			(end -0.494 0.25)
			(stroke
				(width 0.15)
				(type solid)
			)
			(layer "B.Fab")
		)
		(pad "1" smd roundrect
			(at -0.48 0 180)
			(size 0.59 0.64)
			(layers "B.Cu" "B.Mask" "B.Paste")
			(roundrect_rratio 0.25)
			(net 63 "/FMC+ HSPC/GTX116.TX3_N")
			(pintype "passive")
		)
		(pad "2" smd roundrect
			(at 0.48 0 180)
			(size 0.59 0.64)
			(layers "B.Cu" "B.Mask" "B.Paste")
			(roundrect_rratio 0.25)
			(net 62 "/FMC+ HSPC/GTX_TX0_C_N")
			(pintype "passive")
		)
	)
	(footprint "antmicro-footprints:C_0402_1005Metric"
		(layer "B.Cu")
		(at 194.9 126.325 90)
		(descr "Capacitor SMD 0402")
		(tags "capacitor SMD 0402")
		(property "Reference" "C113"
			(at 31.2 23.4 270)
			(layer "B.SilkS")
			(effects
				(font
					(size 0.7 0.7)
					(thickness 0.15)
				)
				(justify left bottom mirror)
			)
		)
		(property "Value" "C_100n_0402"
			(at 0 -1.169 270)
			(layer "B.Fab")
			(effects
				(font
					(size 0.7 0.7)
					(thickness 0.15)
				)
				(justify left bottom mirror)
			)
		)
		(property "Description" "SMD Multilayer Ceramic Capacitor, 0.1 µF, 50 V, 0402 [1005 Metric], ± 10%, X5R, GRM Series"
			(at 0 0 90)
			(layer "F.Fab")
			(hide yes)
			(effects
				(font
					(size 1.27 1.27)
					(thickness 0.15)
				)
			)
		)
		(property "Author" "Antmicro"
			(at 321.225 -68.575 0)
			(layer "B.Fab")
			(hide yes)
			(effects
				(font
					(size 1 1)
					(thickness 0.15)
				)
				(justify mirror)
			)
		)
		(property "Dielectric" "X5R"
			(at 321.225 -68.575 0)
			(layer "B.Fab")
			(hide yes)
			(effects
				(font
					(size 1 1)
					(thickness 0.15)
				)
				(justify mirror)
			)
		)
		(property "License" "Apache-2.0"
			(at 321.225 -68.575 0)
			(layer "B.Fab")
			(hide yes)
			(effects
				(font
					(size 1 1)
					(thickness 0.15)
				)
				(justify mirror)
			)
		)
		(property "MPN" "GRM155R61H104KE14D"
			(at 321.225 -68.575 0)
			(layer "B.Fab")
			(hide yes)
			(effects
				(font
					(size 1 1)
					(thickness 0.15)
				)
				(justify mirror)
			)
		)
		(property "Manufacturer" "Murata"
			(at 321.225 -68.575 0)
			(layer "B.Fab")
			(hide yes)
			(effects
				(font
					(size 1 1)
					(thickness 0.15)
				)
				(justify mirror)
			)
		)
		(property "Val" "100n"
			(at 321.225 -68.575 0)
			(layer "B.Fab")
			(hide yes)
			(effects
				(font
					(size 1 1)
					(thickness 0.15)
				)
				(justify mirror)
			)
		)
		(property "Voltage" "50V"
			(at 321.225 -68.575 0)
			(layer "B.Fab")
			(hide yes)
			(effects
				(font
					(size 1 1)
					(thickness 0.15)
				)
				(justify mirror)
			)
		)
		(sheetname "FPGA supply")
		(sheetfile "fpga-supply.kicad_sch")
		(attr smd)
		(fp_rect
			(start -0.925 0.47)
			(end 0.925 -0.47)
			(stroke
				(width 0.05)
				(type default)
			)
			(fill no)
			(layer "B.CrtYd")
		)
		(fp_line
			(start 0.504 -0.248)
			(end -0.494 -0.248)
			(stroke
				(width 0.15)
				(type solid)
			)
			(layer "B.Fab")
		)
		(fp_line
			(start -0.494 -0.248)
			(end -0.494 0.25)
			(stroke
				(width 0.15)
				(type solid)
			)
			(layer "B.Fab")
		)
		(fp_line
			(start 0.504 0.25)
			(end 0.504 -0.248)
			(stroke
				(width 0.15)
				(type solid)
			)
			(layer "B.Fab")
		)
		(fp_line
			(start -0.494 0.25)
			(end 0.504 0.25)
			(stroke
				(width 0.15)
				(type solid)
			)
			(layer "B.Fab")
		)
		(pad "1" smd roundrect
			(at -0.48 0 90)
			(size 0.59 0.64)
			(layers "B.Cu" "B.Mask" "B.Paste")
			(roundrect_rratio 0.25)
			(net 1 "GND")
			(pintype "passive")
		)
		(pad "2" smd roundrect
			(at 0.48 0 90)
			(size 0.59 0.64)
			(layers "B.Cu" "B.Mask" "B.Paste")
			(roundrect_rratio 0.25)
			(net 650 "+1V0")
			(pintype "passive")
		)
	)
	(footprint "antmicro-footprints:R_0402_1005Metric"
		(layer "B.Cu")
		(at 229 155.2)
		(descr "Resistor SMD 0402")
		(tags "resistor SMD 0402")
		(property "Reference" "R229"
			(at 3.65 0.375 180)
			(layer "B.SilkS")
			(effects
				(font
					(size 0.7 0.7)
					(thickness 0.15)
				)
				(justify left bottom mirror)
			)
		)
		(property "Value" "R_2k2_0402"
			(at 0 -1.4 180)
			(layer "B.Fab")
			(effects
				(font
					(size 0.7 0.7)
					(thickness 0.15)
				)
				(justify left bottom mirror)
			)
		)
		(property "Description" "SMD Chip Resistor, 2.2 kohm, ± 1%, 62.5 mW, 0402 [1005 Metric], Thick Film, General Purpose"
			(at 0 0 0)
			(layer "F.Fab")
			(hide yes)
			(effects
				(font
					(size 1.27 1.27)
					(thickness 0.15)
				)
			)
		)
		(property "Author" "Antmicro"
			(at 0 0 0)
			(layer "B.Fab")
			(hide yes)
			(effects
				(font
					(size 1 1)
					(thickness 0.15)
				)
				(justify mirror)
			)
		)
		(property "License" "Apache-2.0"
			(at 0 0 0)
			(layer "B.Fab")
			(hide yes)
			(effects
				(font
					(size 1 1)
					(thickness 0.15)
				)
				(justify mirror)
			)
		)
		(property "MPN" "CR0402-FX-2201GLF"
			(at 0 0 0)
			(layer "B.Fab")
			(hide yes)
			(effects
				(font
					(size 1 1)
					(thickness 0.15)
				)
				(justify mirror)
			)
		)
		(property "Manufacturer" "Bourns"
			(at 0 0 0)
			(layer "B.Fab")
			(hide yes)
			(effects
				(font
					(size 1 1)
					(thickness 0.15)
				)
				(justify mirror)
			)
		)
		(property "Tolerance" "1%"
			(at 0 0 0)
			(layer "B.Fab")
			(hide yes)
			(effects
				(font
					(size 1 1)
					(thickness 0.15)
				)
				(justify mirror)
			)
		)
		(property "Val" "2k2"
			(at 0 0 0)
			(layer "B.Fab")
			(hide yes)
			(effects
				(font
					(size 1 1)
					(thickness 0.15)
				)
				(justify mirror)
			)
		)
		(sheetname "HDMI + Ethernet")
		(sheetfile "hdmi-ethernet.kicad_sch")
		(attr smd)
		(fp_rect
			(start -0.925 0.47)
			(end 0.925 -0.47)
			(stroke
				(width 0.05)
				(type default)
			)
			(fill no)
			(layer "B.CrtYd")
		)
		(fp_rect
			(start -0.5 0.25)
			(end 0.5 -0.25)
			(stroke
				(width 0.15)
				(type solid)
			)
			(fill no)
			(layer "B.Fab")
		)
		(pad "1" smd roundrect
			(at -0.48 0)
			(size 0.59 0.64)
			(layers "B.Cu" "B.Mask" "B.Paste")
			(roundrect_rratio 0.25)
			(net 847 "/HDMI + Ethernet/ETH_LED_LINK-")
			(pintype "passive")
		)
		(pad "2" smd roundrect
			(at 0.48 0)
			(size 0.59 0.64)
			(layers "B.Cu" "B.Mask" "B.Paste")
			(roundrect_rratio 0.25)
			(net 1 "GND")
			(pintype "passive")
		)
	)
	(footprint "antmicro-footprints:C_0402_1005Metric"
		(layer "B.Cu")
		(at 190.5 141 90)
		(descr "Capacitor SMD 0402")
		(tags "capacitor SMD 0402")
		(property "Reference" "C79"
			(at 0.975 -0.475 270)
			(layer "B.SilkS")
			(effects
				(font
					(size 0.7 0.7)
					(thickness 0.15)
				)
				(justify left bottom mirror)
			)
		)
		(property "Value" "C_100n_0402"
			(at 0 -1.169 270)
			(layer "B.Fab")
			(effects
				(font
					(size 0.7 0.7)
					(thickness 0.15)
				)
				(justify left bottom mirror)
			)
		)
		(property "Description" "SMD Multilayer Ceramic Capacitor, 0.1 µF, 50 V, 0402 [1005 Metric], ± 10%, X5R, GRM Series"
			(at 0 0 90)
			(layer "F.Fab")
			(hide yes)
			(effects
				(font
					(size 1.27 1.27)
					(thickness 0.15)
				)
			)
		)
		(property "Author" "Antmicro"
			(at 331.5 -49.5 0)
			(layer "B.Fab")
			(hide yes)
			(effects
				(font
					(size 1 1)
					(thickness 0.15)
				)
				(justify mirror)
			)
		)
		(property "Dielectric" "X5R"
			(at 331.5 -49.5 0)
			(layer "B.Fab")
			(hide yes)
			(effects
				(font
					(size 1 1)
					(thickness 0.15)
				)
				(justify mirror)
			)
		)
		(property "License" "Apache-2.0"
			(at 331.5 -49.5 0)
			(layer "B.Fab")
			(hide yes)
			(effects
				(font
					(size 1 1)
					(thickness 0.15)
				)
				(justify mirror)
			)
		)
		(property "MPN" "GRM155R61H104KE14D"
			(at 331.5 -49.5 0)
			(layer "B.Fab")
			(hide yes)
			(effects
				(font
					(size 1 1)
					(thickness 0.15)
				)
				(justify mirror)
			)
		)
		(property "Manufacturer" "Murata"
			(at 331.5 -49.5 0)
			(layer "B.Fab")
			(hide yes)
			(effects
				(font
					(size 1 1)
					(thickness 0.15)
				)
				(justify mirror)
			)
		)
		(property "Val" "100n"
			(at 331.5 -49.5 0)
			(layer "B.Fab")
			(hide yes)
			(effects
				(font
					(size 1 1)
					(thickness 0.15)
				)
				(justify mirror)
			)
		)
		(property "Voltage" "50V"
			(at 331.5 -49.5 0)
			(layer "B.Fab")
			(hide yes)
			(effects
				(font
					(size 1 1)
					(thickness 0.15)
				)
				(justify mirror)
			)
		)
		(sheetname "FPGA Bank 33 & 34")
		(sheetfile "fpga-bank-33-34.kicad_sch")
		(attr smd)
		(fp_rect
			(start -0.925 0.47)
			(end 0.925 -0.47)
			(stroke
				(width 0.05)
				(type default)
			)
			(fill no)
			(layer "B.CrtYd")
		)
		(fp_line
			(start 0.504 -0.248)
			(end -0.494 -0.248)
			(stroke
				(width 0.15)
				(type solid)
			)
			(layer "B.Fab")
		)
		(fp_line
			(start -0.494 -0.248)
			(end -0.494 0.25)
			(stroke
				(width 0.15)
				(type solid)
			)
			(layer "B.Fab")
		)
		(fp_line
			(start 0.504 0.25)
			(end 0.504 -0.248)
			(stroke
				(width 0.15)
				(type solid)
			)
			(layer "B.Fab")
		)
		(fp_line
			(start -0.494 0.25)
			(end 0.504 0.25)
			(stroke
				(width 0.15)
				(type solid)
			)
			(layer "B.Fab")
		)
		(pad "1" smd roundrect
			(at -0.48 0 90)
			(size 0.59 0.64)
			(layers "B.Cu" "B.Mask" "B.Paste")
			(roundrect_rratio 0.25)
			(net 1 "GND")
			(pintype "passive")
		)
		(pad "2" smd roundrect
			(at 0.48 0 90)
			(size 0.59 0.64)
			(layers "B.Cu" "B.Mask" "B.Paste")
			(roundrect_rratio 0.25)
			(net 25 "+1V35")
			(pintype "passive")
		)
	)
	(footprint "antmicro-footprints:R_0402_1005Metric"
		(layer "B.Cu")
		(at 236.299999 84.7 90)
		(descr "Resistor SMD 0402")
		(tags "resistor SMD 0402")
		(property "Reference" "R124"
			(at -0.775 0.400001 270)
			(layer "B.SilkS")
			(effects
				(font
					(size 0.7 0.7)
					(thickness 0.15)
				)
				(justify left bottom mirror)
			)
		)
		(property "Value" "R_100R_0402"
			(at 0 -1.4 270)
			(layer "B.Fab")
			(effects
				(font
					(size 0.7 0.7)
					(thickness 0.15)
				)
				(justify left bottom mirror)
			)
		)
		(property "Description" "SMD Chip Resistor, 100 ohm, ± 1%, 62.5 mW, 0402 [1005 Metric], Thick Film, General Purpose"
			(at 0 0 90)
			(layer "F.Fab")
			(hide yes)
			(effects
				(font
					(size 1.27 1.27)
					(thickness 0.15)
				)
			)
		)
		(property "Author" "Antmicro"
			(at 320.999999 -151.599999 0)
			(layer "B.Fab")
			(hide yes)
			(effects
				(font
					(size 1 1)
					(thickness 0.15)
				)
				(justify mirror)
			)
		)
		(property "License" "Apache-2.0"
			(at 320.999999 -151.599999 0)
			(layer "B.Fab")
			(hide yes)
			(effects
				(font
					(size 1 1)
					(thickness 0.15)
				)
				(justify mirror)
			)
		)
		(property "MPN" "CR0402-FX-1000GLF"
			(at 320.999999 -151.599999 0)
			(layer "B.Fab")
			(hide yes)
			(effects
				(font
					(size 1 1)
					(thickness 0.15)
				)
				(justify mirror)
			)
		)
		(property "Manufacturer" "Bourns"
			(at 320.999999 -151.599999 0)
			(layer "B.Fab")
			(hide yes)
			(effects
				(font
					(size 1 1)
					(thickness 0.15)
				)
				(justify mirror)
			)
		)
		(property "Tolerance" "1%"
			(at 320.999999 -151.599999 0)
			(layer "B.Fab")
			(hide yes)
			(effects
				(font
					(size 1 1)
					(thickness 0.15)
				)
				(justify mirror)
			)
		)
		(property "Val" "100R"
			(at 320.999999 -151.599999 0)
			(layer "B.Fab")
			(hide yes)
			(effects
				(font
					(size 1 1)
					(thickness 0.15)
				)
				(justify mirror)
			)
		)
		(sheetname "User GPIO + LED + button + DIP switch")
		(sheetfile "user-gpio.kicad_sch")
		(attr smd)
		(fp_rect
			(start -0.925 0.47)
			(end 0.925 -0.47)
			(stroke
				(width 0.05)
				(type default)
			)
			(fill no)
			(layer "B.CrtYd")
		)
		(fp_rect
			(start -0.5 0.25)
			(end 0.5 -0.25)
			(stroke
				(width 0.15)
				(type solid)
			)
			(fill no)
			(layer "B.Fab")
		)
		(pad "1" smd roundrect
			(at -0.48 0 90)
			(size 0.59 0.64)
			(layers "B.Cu" "B.Mask" "B.Paste")
			(roundrect_rratio 0.25)
			(net 462 "/FPGA Bank 12 & 13/PMOD_B.IO1")
			(pintype "passive")
		)
		(pad "2" smd roundrect
			(at 0.48 0 90)
			(size 0.59 0.64)
			(layers "B.Cu" "B.Mask" "B.Paste")
			(roundrect_rratio 0.25)
			(net 817 "/User GPIO + LED + button + DIP switch/PMOD_B_1")
			(pintype "passive")
		)
	)
	(footprint "antmicro-footprints:R_0402_1005Metric"
		(layer "B.Cu")
		(at 225.9 125.8 -90)
		(descr "Resistor SMD 0402")
		(tags "resistor SMD 0402")
		(property "Reference" "R111"
			(at -1.325 -1.35 90)
			(layer "B.SilkS")
			(effects
				(font
					(size 0.7 0.7)
					(thickness 0.15)
				)
				(justify left bottom mirror)
			)
		)
		(property "Value" "R_1k_0402"
			(at 0 -1.4 90)
			(layer "B.Fab")
			(effects
				(font
					(size 0.7 0.7)
					(thickness 0.15)
				)
				(justify left bottom mirror)
			)
		)
		(property "Description" "SMD Chip Resistor, 1 kohm, ± 1%, 63 mW, 0402 [1005 Metric], Thick Film, General Purpose"
			(at 0 0 270)
			(layer "F.Fab")
			(hide yes)
			(effects
				(font
					(size 1.27 1.27)
					(thickness 0.15)
				)
			)
		)
		(property "Author" "Antmicro"
			(at 100.1 351.7 0)
			(layer "B.Fab")
			(hide yes)
			(effects
				(font
					(size 1 1)
					(thickness 0.15)
				)
				(justify mirror)
			)
		)
		(property "License" "Apache-2.0"
			(at 100.1 351.7 0)
			(layer "B.Fab")
			(hide yes)
			(effects
				(font
					(size 1 1)
					(thickness 0.15)
				)
				(justify mirror)
			)
		)
		(property "MPN" "CR0402-FX-1001GLF"
			(at 100.1 351.7 0)
			(layer "B.Fab")
			(hide yes)
			(effects
				(font
					(size 1 1)
					(thickness 0.15)
				)
				(justify mirror)
			)
		)
		(property "Manufacturer" "Bourns"
			(at 100.1 351.7 0)
			(layer "B.Fab")
			(hide yes)
			(effects
				(font
					(size 1 1)
					(thickness 0.15)
				)
				(justify mirror)
			)
		)
		(property "Tolerance" "1%"
			(at 100.1 351.7 0)
			(layer "B.Fab")
			(hide yes)
			(effects
				(font
					(size 1 1)
					(thickness 0.15)
				)
				(justify mirror)
			)
		)
		(property "Val" "1k"
			(at 100.1 351.7 0)
			(layer "B.Fab")
			(hide yes)
			(effects
				(font
					(size 1 1)
					(thickness 0.15)
				)
				(justify mirror)
			)
		)
		(sheetname "User GPIO + LED + button + DIP switch")
		(sheetfile "user-gpio.kicad_sch")
		(attr smd)
		(fp_rect
			(start -0.925 0.47)
			(end 0.925 -0.47)
			(stroke
				(width 0.05)
				(type default)
			)
			(fill no)
			(layer "B.CrtYd")
		)
		(fp_rect
			(start -0.5 0.25)
			(end 0.5 -0.25)
			(stroke
				(width 0.15)
				(type solid)
			)
			(fill no)
			(layer "B.Fab")
		)
		(pad "1" smd roundrect
			(at -0.48 0 270)
			(size 0.59 0.64)
			(layers "B.Cu" "B.Mask" "B.Paste")
			(roundrect_rratio 0.25)
			(net 801 "/User GPIO + LED + button + DIP switch/FAN_PWM_PIN")
			(pintype "passive")
		)
		(pad "2" smd roundrect
			(at 0.48 0 270)
			(size 0.59 0.64)
			(layers "B.Cu" "B.Mask" "B.Paste")
			(roundrect_rratio 0.25)
			(net 703 "+5V")
			(pintype "passive")
		)
	)
	(footprint "antmicro-footprints:C_0201"
		(layer "B.Cu")
		(at 201.5 134.45 180)
		(descr "Capacitor SMD 0201")
		(tags "capacitor SMD 0201")
		(property "Reference" "C34"
			(at -26.9 28.1 0)
			(layer "B.SilkS")
			(effects
				(font
					(size 0.7 0.7)
					(thickness 0.15)
				)
				(justify left bottom mirror)
			)
		)
		(property "Value" "C_4u7_0201"
			(at 0 -1.4 0)
			(layer "B.Fab")
			(effects
				(font
					(size 0.7 0.7)
					(thickness 0.15)
				)
				(justify left bottom mirror)
			)
		)
		(property "Description" "SMD Multilayer Ceramic Capacitor, 4.7 µF, 6.3 V, 0201 [0603 Metric], ± 20%, X5R, GRM Series"
			(at 0 0 180)
			(layer "F.Fab")
			(hide yes)
			(effects
				(font
					(size 1.27 1.27)
					(thickness 0.15)
				)
			)
		)
		(property "Author" "Antmicro"
			(at 403 268.9 0)
			(layer "B.Fab")
			(hide yes)
			(effects
				(font
					(size 1 1)
					(thickness 0.15)
				)
				(justify mirror)
			)
		)
		(property "Dielectric" ""
			(at 403 268.9 0)
			(layer "B.Fab")
			(hide yes)
			(effects
				(font
					(size 1 1)
					(thickness 0.15)
				)
				(justify mirror)
			)
		)
		(property "License" "Apache-2.0"
			(at 403 268.9 0)
			(layer "B.Fab")
			(hide yes)
			(effects
				(font
					(size 1 1)
					(thickness 0.15)
				)
				(justify mirror)
			)
		)
		(property "MPN" "GRM035R60J475ME15D"
			(at 403 268.9 0)
			(layer "B.Fab")
			(hide yes)
			(effects
				(font
					(size 1 1)
					(thickness 0.15)
				)
				(justify mirror)
			)
		)
		(property "Manufacturer" "Murata"
			(at 403 268.9 0)
			(layer "B.Fab")
			(hide yes)
			(effects
				(font
					(size 1 1)
					(thickness 0.15)
				)
				(justify mirror)
			)
		)
		(property "Val" "4u7"
			(at 403 268.9 0)
			(layer "B.Fab")
			(hide yes)
			(effects
				(font
					(size 1 1)
					(thickness 0.15)
				)
				(justify mirror)
			)
		)
		(property "Voltage" ""
			(at 403 268.9 0)
			(layer "B.Fab")
			(hide yes)
			(effects
				(font
					(size 1 1)
					(thickness 0.15)
				)
				(justify mirror)
			)
		)
		(sheetname "FPGA supply")
		(sheetfile "fpga-supply.kicad_sch")
		(attr smd)
		(fp_rect
			(start -0.7 0.35)
			(end 0.7 -0.35)
			(stroke
				(width 0.05)
				(type default)
			)
			(fill no)
			(layer "B.CrtYd")
		)
		(fp_rect
			(start 0.3 -0.15)
			(end -0.301 0.149)
			(stroke
				(width 0.15)
				(type solid)
			)
			(fill no)
			(layer "B.Fab")
		)
		(pad "" smd roundrect
			(at -0.349 0.002 180)
			(size 0.318 0.36)
			(layers "B.Paste")
			(roundrect_rratio 0.25)
		)
		(pad "" smd roundrect
			(at 0.341 0.002 180)
			(size 0.318 0.36)
			(layers "B.Paste")
			(roundrect_rratio 0.25)
		)
		(pad "1" smd roundrect
			(at -0.321 0.002 180)
			(size 0.46 0.4)
			(layers "B.Cu" "B.Mask")
			(roundrect_rratio 0.25)
			(net 1 "GND")
			(pintype "passive")
		)
		(pad "2" smd roundrect
			(at 0.32 0.002 180)
			(size 0.46 0.4)
			(layers "B.Cu" "B.Mask")
			(roundrect_rratio 0.25)
			(net 650 "+1V0")
			(pintype "passive")
		)
	)
	(footprint "antmicro-footprints:R_0402_1005Metric"
		(layer "B.Cu")
		(at 172.75 176.7625 180)
		(descr "Resistor SMD 0402")
		(tags "resistor SMD 0402")
		(property "Reference" "R320"
			(at 0.725 -0.4125 0)
			(layer "B.SilkS")
			(effects
				(font
					(size 0.7 0.7)
					(thickness 0.15)
				)
				(justify left bottom mirror)
			)
		)
		(property "Value" "R_0R_0402"
			(at 0 -1.4 0)
			(layer "B.Fab")
			(effects
				(font
					(size 0.7 0.7)
					(thickness 0.15)
				)
				(justify left bottom mirror)
			)
		)
		(property "Description" "SMD Chip Resistor, Jumper, 0 ohm, 100 mW, 0402 [1005 Metric], Thick Film, General Purpose"
			(at 0 0 180)
			(layer "F.Fab")
			(hide yes)
			(effects
				(font
					(size 1.27 1.27)
					(thickness 0.15)
				)
			)
		)
		(property "Author" "Antmicro"
			(at 345.5 353.525 0)
			(layer "B.Fab")
			(hide yes)
			(effects
				(font
					(size 1 1)
					(thickness 0.15)
				)
				(justify mirror)
			)
		)
		(property "Current" "1A"
			(at 345.5 353.525 0)
			(layer "B.Fab")
			(hide yes)
			(effects
				(font
					(size 1 1)
					(thickness 0.15)
				)
				(justify mirror)
			)
		)
		(property "DNP" "DNP"
			(at 345.5 353.525 0)
			(layer "B.Fab")
			(hide yes)
			(effects
				(font
					(size 1 1)
					(thickness 0.15)
				)
				(justify mirror)
			)
		)
		(property "License" "Apache-2.0"
			(at 345.5 353.525 0)
			(layer "B.Fab")
			(hide yes)
			(effects
				(font
					(size 1 1)
					(thickness 0.15)
				)
				(justify mirror)
			)
		)
		(property "MPN" "ERJ2GE0R00X"
			(at 345.5 353.525 0)
			(layer "B.Fab")
			(hide yes)
			(effects
				(font
					(size 1 1)
					(thickness 0.15)
				)
				(justify mirror)
			)
		)
		(property "Manufacturer" "Panasonic"
			(at 345.5 353.525 0)
			(layer "B.Fab")
			(hide yes)
			(effects
				(font
					(size 1 1)
					(thickness 0.15)
				)
				(justify mirror)
			)
		)
		(property "Tolerance" ""
			(at 345.5 353.525 0)
			(layer "B.Fab")
			(hide yes)
			(effects
				(font
					(size 1 1)
					(thickness 0.15)
				)
				(justify mirror)
			)
		)
		(property "Val" "0R"
			(at 345.5 353.525 0)
			(layer "B.Fab")
			(hide yes)
			(effects
				(font
					(size 1 1)
					(thickness 0.15)
				)
				(justify mirror)
			)
		)
		(property "dnp" ""
			(at 345.5 353.525 0)
			(layer "B.Fab")
			(hide yes)
			(effects
				(font
					(size 1 1)
					(thickness 0.15)
				)
				(justify mirror)
			)
		)
		(property "exclude_from_bom" ""
			(at 345.5 353.525 0)
			(layer "B.Fab")
			(hide yes)
			(effects
				(font
					(size 1 1)
					(thickness 0.15)
				)
				(justify mirror)
			)
		)
		(sheetname "DC-DC Converters")
		(sheetfile "dc-dc.kicad_sch")
		(attr smd exclude_from_bom)
		(fp_rect
			(start -0.925 0.47)
			(end 0.925 -0.47)
			(stroke
				(width 0.05)
				(type default)
			)
			(fill no)
			(layer "B.CrtYd")
		)
		(fp_rect
			(start -0.5 0.25)
			(end 0.5 -0.25)
			(stroke
				(width 0.15)
				(type solid)
			)
			(fill no)
			(layer "B.Fab")
		)
		(pad "1" smd roundrect
			(at -0.48 0 180)
			(size 0.59 0.64)
			(layers "B.Cu" "B.Mask" "B.Paste")
			(roundrect_rratio 0.25)
			(net 965 "/DC-DC Converters/FB8")
			(pintype "passive")
		)
		(pad "2" smd roundrect
			(at 0.48 0 180)
			(size 0.59 0.64)
			(layers "B.Cu" "B.Mask" "B.Paste")
			(roundrect_rratio 0.25)
			(net 1216 "/DC-DC Converters/SENSE_1V35_P")
			(pintype "passive")
		)
	)
	(footprint "antmicro-footprints:R_Array_4x0201_Panasonic_EXB18V"
		(layer "B.Cu")
		(at 247.901 149.15)
		(property "Reference" "R29"
			(at 1.074 1.475 0)
			(layer "B.SilkS")
			(effects
				(font
					(size 0.7 0.7)
					(thickness 0.15)
				)
				(justify left bottom mirror)
			)
		)
		(property "Value" "R_4x33R_0201_array"
			(at -1.1 -1.8 0)
			(layer "B.Fab")
			(effects
				(font
					(size 0.7 0.7)
					(thickness 0.15)
				)
				(justify right bottom mirror)
			)
		)
		(property "Description" "Fixed Network Resistor, 33 ohm, Isolated, 4 Resistors, 0502 [1406 Metric], Flat, ± 5%"
			(at 0 0 0)
			(layer "F.Fab")
			(hide yes)
			(effects
				(font
					(size 1.27 1.27)
					(thickness 0.15)
				)
			)
		)
		(property "Author" "Antmicro"
			(at 0 0 0)
			(layer "B.Fab")
			(hide yes)
			(effects
				(font
					(size 1 1)
					(thickness 0.15)
				)
				(justify mirror)
			)
		)
		(property "License" "Apache-2.0"
			(at 0 0 0)
			(layer "B.Fab")
			(hide yes)
			(effects
				(font
					(size 1 1)
					(thickness 0.15)
				)
				(justify mirror)
			)
		)
		(property "MPN" "EXB-18V330JX"
			(at 0 0 0)
			(layer "B.Fab")
			(hide yes)
			(effects
				(font
					(size 1 1)
					(thickness 0.15)
				)
				(justify mirror)
			)
		)
		(property "Manufacturer" "Panasonic"
			(at 0 0 0)
			(layer "B.Fab")
			(hide yes)
			(effects
				(font
					(size 1 1)
					(thickness 0.15)
				)
				(justify mirror)
			)
		)
		(property "Val" "R_4x33R_0201"
			(at 0 0 0)
			(layer "B.Fab")
			(hide yes)
			(effects
				(font
					(size 1 1)
					(thickness 0.15)
				)
				(justify mirror)
			)
		)
		(sheetname "Supervisior MCU")
		(sheetfile "supervisor-mcu.kicad_sch")
		(attr smd)
		(fp_line
			(start -0.8 0.45)
			(end -0.8 -0.45)
			(stroke
				(width 0.12)
				(type solid)
			)
			(layer "B.SilkS")
		)
		(fp_line
			(start 0.8 0.45)
			(end 0.8 -0.45)
			(stroke
				(width 0.12)
				(type solid)
			)
			(layer "B.SilkS")
		)
		(fp_rect
			(start -0.898 0.66)
			(end 0.898 -0.65)
			(stroke
				(width 0.05)
				(type solid)
			)
			(fill no)
			(layer "B.CrtYd")
		)
		(pad "1" smd roundrect
			(at -0.6 -0.298)
			(size 0.2 0.4)
			(layers "B.Cu" "B.Mask" "B.Paste")
			(roundrect_rratio 0.25)
			(net 1374 "/SUP_MCU.D6")
			(pinfunction "R1.1")
			(pintype "passive")
		)
		(pad "2" smd roundrect
			(at -0.202 -0.298)
			(size 0.2 0.4)
			(layers "B.Cu" "B.Mask" "B.Paste")
			(roundrect_rratio 0.25)
			(net 1375 "/SUP_MCU.D7")
			(pinfunction "R2.1")
			(pintype "passive")
		)
		(pad "3" smd roundrect
			(at 0.2 -0.298)
			(size 0.2 0.4)
			(layers "B.Cu" "B.Mask" "B.Paste")
			(roundrect_rratio 0.25)
			(net 1376 "/SUP_MCU.CE")
			(pinfunction "R3.1")
			(pintype "passive")
		)
		(pad "4" smd roundrect
			(at 0.598 -0.298)
			(size 0.2 0.4)
			(layers "B.Cu" "B.Mask" "B.Paste")
			(roundrect_rratio 0.25)
			(net 1316 "/SUP_MCU.INITB")
			(pinfunction "R4.1")
			(pintype "passive")
		)
		(pad "5" smd roundrect
			(at 0.598 0.3)
			(size 0.2 0.4)
			(layers "B.Cu" "B.Mask" "B.Paste")
			(roundrect_rratio 0.25)
			(net 1060 "/Supervisior MCU/CFG_INITB")
			(pinfunction "R4.2")
			(pintype "passive")
		)
		(pad "6" smd roundrect
			(at 0.2 0.3)
			(size 0.2 0.4)
			(layers "B.Cu" "B.Mask" "B.Paste")
			(roundrect_rratio 0.25)
			(net 1095 "/Supervisior MCU/USB_CE")
			(pinfunction "R3.2")
			(pintype "passive")
		)
		(pad "7" smd roundrect
			(at -0.202 0.3)
			(size 0.2 0.4)
			(layers "B.Cu" "B.Mask" "B.Paste")
			(roundrect_rratio 0.25)
			(net 1113 "/Supervisior MCU/USB_D7")
			(pinfunction "R2.2")
			(pintype "passive")
		)
		(pad "8" smd roundrect
			(at -0.6 0.3)
			(size 0.2 0.4)
			(layers "B.Cu" "B.Mask" "B.Paste")
			(roundrect_rratio 0.25)
			(net 1112 "/Supervisior MCU/USB_D6")
			(pinfunction "R1.2")
			(pintype "passive")
		)
	)
	(footprint "antmicro-footprints:SOD-523"
		(layer "B.Cu")
		(at 237.426 137.7)
		(property "Reference" "D38"
			(at -0.951 0.375 180)
			(layer "B.SilkS")
			(effects
				(font
					(size 0.7 0.7)
					(thickness 0.15)
				)
				(justify left bottom mirror)
			)
		)
		(property "Value" "BAT54-02V-G3-08"
			(at 0 -1.499 180)
			(layer "B.Fab")
			(effects
				(font
					(size 0.7 0.7)
					(thickness 0.15)
				)
				(justify left bottom mirror)
			)
		)
		(property "Description" "Small Signal Schottky Diode, Single, 30 V, 200 mA, 800 mV, 600 mA, 125 °C"
			(at 0 0 0)
			(layer "F.Fab")
			(hide yes)
			(effects
				(font
					(size 1.27 1.27)
					(thickness 0.15)
				)
			)
		)
		(property "Author" "Antmicro"
			(at 0 0 0)
			(layer "B.Fab")
			(hide yes)
			(effects
				(font
					(size 1 1)
					(thickness 0.15)
				)
				(justify mirror)
			)
		)
		(property "License" "Apache-2.0"
			(at 0 0 0)
			(layer "B.Fab")
			(hide yes)
			(effects
				(font
					(size 1 1)
					(thickness 0.15)
				)
				(justify mirror)
			)
		)
		(property "MPN" "BAT54-02V-G3-08"
			(at 0 0 0)
			(layer "B.Fab")
			(hide yes)
			(effects
				(font
					(size 1 1)
					(thickness 0.15)
				)
				(justify mirror)
			)
		)
		(property "Manufacturer" "Vishay"
			(at 0 0 0)
			(layer "B.Fab")
			(hide yes)
			(effects
				(font
					(size 1 1)
					(thickness 0.15)
				)
				(justify mirror)
			)
		)
		(property "Public" "False"
			(at 0 0 0)
			(layer "B.Fab")
			(hide yes)
			(effects
				(font
					(size 1 1)
					(thickness 0.15)
				)
				(justify mirror)
			)
		)
		(sheetname "USB PHY")
		(sheetfile "usb-phy.kicad_sch")
		(attr smd)
		(fp_line
			(start -0.35 0.5)
			(end -0.35 -0.5)
			(stroke
				(width 0.15)
				(type solid)
			)
			(layer "B.SilkS")
		)
		(fp_rect
			(start -1 0.6)
			(end 1 -0.6)
			(stroke
				(width 0.05)
				(type solid)
			)
			(fill no)
			(layer "B.CrtYd")
		)
		(fp_line
			(start -0.652 -0.423)
			(end -0.652 0.425)
			(stroke
				(width 0.15)
				(type solid)
			)
			(layer "B.Fab")
		)
		(fp_line
			(start -0.652 -0.423)
			(end 0.65 -0.423)
			(stroke
				(width 0.15)
				(type solid)
			)
			(layer "B.Fab")
		)
		(fp_line
			(start -0.652 0.425)
			(end 0.65 0.425)
			(stroke
				(width 0.15)
				(type solid)
			)
			(layer "B.Fab")
		)
		(fp_line
			(start -0.35 0.4)
			(end -0.35 -0.4)
			(stroke
				(width 0.15)
				(type solid)
			)
			(layer "B.Fab")
		)
		(fp_line
			(start 0.65 0.425)
			(end 0.65 -0.423)
			(stroke
				(width 0.15)
				(type solid)
			)
			(layer "B.Fab")
		)
		(pad "1" smd roundrect
			(at -0.701 0)
			(size 0.5 0.6)
			(layers "B.Cu" "B.Mask" "B.Paste")
			(roundrect_rratio 0.25)
			(net 1205 "Net-(D38-Pad1)")
			(pinfunction "C")
			(pintype "passive")
		)
		(pad "2" smd roundrect
			(at 0.699 0)
			(size 0.5 0.6)
			(layers "B.Cu" "B.Mask" "B.Paste")
			(roundrect_rratio 0.25)
			(net 24 "+3V3")
			(pinfunction "A")
			(pintype "passive")
		)
	)
	(footprint "antmicro-footprints:R_0402_1005Metric"
		(layer "B.Cu")
		(at 198.491252 94.55)
		(descr "Resistor SMD 0402")
		(tags "resistor SMD 0402")
		(property "Reference" "R212"
			(at 1.483748 -4.6 180)
			(layer "B.SilkS")
			(effects
				(font
					(size 0.7 0.7)
					(thickness 0.15)
				)
				(justify left bottom mirror)
			)
		)
		(property "Value" "R_2k2_0402"
			(at 0 -1.4 180)
			(layer "B.Fab")
			(effects
				(font
					(size 0.7 0.7)
					(thickness 0.15)
				)
				(justify left bottom mirror)
			)
		)
		(property "Description" "SMD Chip Resistor, 2.2 kohm, ± 1%, 62.5 mW, 0402 [1005 Metric], Thick Film, General Purpose"
			(at 0 0 0)
			(layer "F.Fab")
			(hide yes)
			(effects
				(font
					(size 1.27 1.27)
					(thickness 0.15)
				)
			)
		)
		(property "Author" "Antmicro"
			(at 0 0 0)
			(layer "B.Fab")
			(hide yes)
			(effects
				(font
					(size 1 1)
					(thickness 0.15)
				)
				(justify mirror)
			)
		)
		(property "License" "Apache-2.0"
			(at 0 0 0)
			(layer "B.Fab")
			(hide yes)
			(effects
				(font
					(size 1 1)
					(thickness 0.15)
				)
				(justify mirror)
			)
		)
		(property "MPN" "CR0402-FX-2201GLF"
			(at 0 0 0)
			(layer "B.Fab")
			(hide yes)
			(effects
				(font
					(size 1 1)
					(thickness 0.15)
				)
				(justify mirror)
			)
		)
		(property "Manufacturer" "Bourns"
			(at 0 0 0)
			(layer "B.Fab")
			(hide yes)
			(effects
				(font
					(size 1 1)
					(thickness 0.15)
				)
				(justify mirror)
			)
		)
		(property "Tolerance" "1%"
			(at 0 0 0)
			(layer "B.Fab")
			(hide yes)
			(effects
				(font
					(size 1 1)
					(thickness 0.15)
				)
				(justify mirror)
			)
		)
		(property "Val" "2k2"
			(at 0 0 0)
			(layer "B.Fab")
			(hide yes)
			(effects
				(font
					(size 1 1)
					(thickness 0.15)
				)
				(justify mirror)
			)
		)
		(sheetname "HDMI + Ethernet")
		(sheetfile "hdmi-ethernet.kicad_sch")
		(attr smd)
		(fp_rect
			(start -0.925 0.47)
			(end 0.925 -0.47)
			(stroke
				(width 0.05)
				(type default)
			)
			(fill no)
			(layer "B.CrtYd")
		)
		(fp_rect
			(start -0.5 0.25)
			(end 0.5 -0.25)
			(stroke
				(width 0.15)
				(type solid)
			)
			(fill no)
			(layer "B.Fab")
		)
		(pad "1" smd roundrect
			(at -0.48 0)
			(size 0.59 0.64)
			(layers "B.Cu" "B.Mask" "B.Paste")
			(roundrect_rratio 0.25)
			(net 506 "/FPGA Bank 16 & 17/GBE_RGMII.RXD0")
			(pintype "passive")
		)
		(pad "2" smd roundrect
			(at 0.48 0)
			(size 0.59 0.64)
			(layers "B.Cu" "B.Mask" "B.Paste")
			(roundrect_rratio 0.25)
			(net 1 "GND")
			(pintype "passive")
		)
	)
	(footprint "antmicro-footprints:C_0402_1005Metric"
		(layer "B.Cu")
		(at 202 116.5 180)
		(descr "Capacitor SMD 0402")
		(tags "capacitor SMD 0402")
		(property "Reference" "C61"
			(at -1.15 0.45 0)
			(layer "B.SilkS")
			(effects
				(font
					(size 0.7 0.7)
					(thickness 0.15)
				)
				(justify left bottom mirror)
			)
		)
		(property "Value" "C_100n_0402"
			(at 0 -1.169 0)
			(layer "B.Fab")
			(effects
				(font
					(size 0.7 0.7)
					(thickness 0.15)
				)
				(justify left bottom mirror)
			)
		)
		(property "Description" "SMD Multilayer Ceramic Capacitor, 0.1 µF, 50 V, 0402 [1005 Metric], ± 10%, X5R, GRM Series"
			(at 0 0 180)
			(layer "F.Fab")
			(hide yes)
			(effects
				(font
					(size 1.27 1.27)
					(thickness 0.15)
				)
			)
		)
		(property "Author" "Antmicro"
			(at 404 233 0)
			(layer "B.Fab")
			(hide yes)
			(effects
				(font
					(size 1 1)
					(thickness 0.15)
				)
				(justify mirror)
			)
		)
		(property "Dielectric" "X5R"
			(at 404 233 0)
			(layer "B.Fab")
			(hide yes)
			(effects
				(font
					(size 1 1)
					(thickness 0.15)
				)
				(justify mirror)
			)
		)
		(property "License" "Apache-2.0"
			(at 404 233 0)
			(layer "B.Fab")
			(hide yes)
			(effects
				(font
					(size 1 1)
					(thickness 0.15)
				)
				(justify mirror)
			)
		)
		(property "MPN" "GRM155R61H104KE14D"
			(at 404 233 0)
			(layer "B.Fab")
			(hide yes)
			(effects
				(font
					(size 1 1)
					(thickness 0.15)
				)
				(justify mirror)
			)
		)
		(property "Manufacturer" "Murata"
			(at 404 233 0)
			(layer "B.Fab")
			(hide yes)
			(effects
				(font
					(size 1 1)
					(thickness 0.15)
				)
				(justify mirror)
			)
		)
		(property "Val" "100n"
			(at 404 233 0)
			(layer "B.Fab")
			(hide yes)
			(effects
				(font
					(size 1 1)
					(thickness 0.15)
				)
				(justify mirror)
			)
		)
		(property "Voltage" "50V"
			(at 404 233 0)
			(layer "B.Fab")
			(hide yes)
			(effects
				(font
					(size 1 1)
					(thickness 0.15)
				)
				(justify mirror)
			)
		)
		(sheetname "FPGA Bank 16 & 17")
		(sheetfile "fpga-bank-16-17.kicad_sch")
		(attr smd)
		(fp_rect
			(start -0.925 0.47)
			(end 0.925 -0.47)
			(stroke
				(width 0.05)
				(type default)
			)
			(fill no)
			(layer "B.CrtYd")
		)
		(fp_line
			(start 0.504 0.25)
			(end 0.504 -0.248)
			(stroke
				(width 0.15)
				(type solid)
			)
			(layer "B.Fab")
		)
		(fp_line
			(start 0.504 -0.248)
			(end -0.494 -0.248)
			(stroke
				(width 0.15)
				(type solid)
			)
			(layer "B.Fab")
		)
		(fp_line
			(start -0.494 0.25)
			(end 0.504 0.25)
			(stroke
				(width 0.15)
				(type solid)
			)
			(layer "B.Fab")
		)
		(fp_line
			(start -0.494 -0.248)
			(end -0.494 0.25)
			(stroke
				(width 0.15)
				(type solid)
			)
			(layer "B.Fab")
		)
		(pad "1" smd roundrect
			(at -0.48 0 180)
			(size 0.59 0.64)
			(layers "B.Cu" "B.Mask" "B.Paste")
			(roundrect_rratio 0.25)
			(net 1 "GND")
			(pintype "passive")
		)
		(pad "2" smd roundrect
			(at 0.48 0 180)
			(size 0.59 0.64)
			(layers "B.Cu" "B.Mask" "B.Paste")
			(roundrect_rratio 0.25)
			(net 24 "+3V3")
			(pintype "passive")
		)
	)
	(footprint "antmicro-footprints:R_0402_1005Metric"
		(layer "B.Cu")
		(at 261.5 83.8)
		(descr "Resistor SMD 0402")
		(tags "resistor SMD 0402")
		(property "Reference" "R107"
			(at 1.425 1.275 180)
			(layer "B.SilkS")
			(effects
				(font
					(size 0.7 0.7)
					(thickness 0.15)
				)
				(justify left bottom mirror)
			)
		)
		(property "Value" "R_1k_0402"
			(at 0 -1.4 180)
			(layer "B.Fab")
			(effects
				(font
					(size 0.7 0.7)
					(thickness 0.15)
				)
				(justify left bottom mirror)
			)
		)
		(property "Description" "SMD Chip Resistor, 1 kohm, ± 1%, 63 mW, 0402 [1005 Metric], Thick Film, General Purpose"
			(at 0 0 0)
			(layer "F.Fab")
			(hide yes)
			(effects
				(font
					(size 1.27 1.27)
					(thickness 0.15)
				)
			)
		)
		(property "Author" "Antmicro"
			(at 0 0 0)
			(layer "B.Fab")
			(hide yes)
			(effects
				(font
					(size 1 1)
					(thickness 0.15)
				)
				(justify mirror)
			)
		)
		(property "License" "Apache-2.0"
			(at 0 0 0)
			(layer "B.Fab")
			(hide yes)
			(effects
				(font
					(size 1 1)
					(thickness 0.15)
				)
				(justify mirror)
			)
		)
		(property "MPN" "CR0402-FX-1001GLF"
			(at 0 0 0)
			(layer "B.Fab")
			(hide yes)
			(effects
				(font
					(size 1 1)
					(thickness 0.15)
				)
				(justify mirror)
			)
		)
		(property "Manufacturer" "Bourns"
			(at 0 0 0)
			(layer "B.Fab")
			(hide yes)
			(effects
				(font
					(size 1 1)
					(thickness 0.15)
				)
				(justify mirror)
			)
		)
		(property "Tolerance" "1%"
			(at 0 0 0)
			(layer "B.Fab")
			(hide yes)
			(effects
				(font
					(size 1 1)
					(thickness 0.15)
				)
				(justify mirror)
			)
		)
		(property "Val" "1k"
			(at 0 0 0)
			(layer "B.Fab")
			(hide yes)
			(effects
				(font
					(size 1 1)
					(thickness 0.15)
				)
				(justify mirror)
			)
		)
		(sheetname "User GPIO + LED + button + DIP switch")
		(sheetfile "user-gpio.kicad_sch")
		(attr smd)
		(fp_rect
			(start -0.925 0.47)
			(end 0.925 -0.47)
			(stroke
				(width 0.05)
				(type default)
			)
			(fill no)
			(layer "B.CrtYd")
		)
		(fp_rect
			(start -0.5 0.25)
			(end 0.5 -0.25)
			(stroke
				(width 0.15)
				(type solid)
			)
			(fill no)
			(layer "B.Fab")
		)
		(pad "1" smd roundrect
			(at -0.48 0)
			(size 0.59 0.64)
			(layers "B.Cu" "B.Mask" "B.Paste")
			(roundrect_rratio 0.25)
			(net 24 "+3V3")
			(pintype "passive")
		)
		(pad "2" smd roundrect
			(at 0.48 0)
			(size 0.59 0.64)
			(layers "B.Cu" "B.Mask" "B.Paste")
			(roundrect_rratio 0.25)
			(net 775 "Net-(D18-A)")
			(pintype "passive")
		)
	)
	(footprint "antmicro-footprints:R_0402_1005Metric"
		(layer "B.Cu")
		(at 200.891252 99.25 -90)
		(descr "Resistor SMD 0402")
		(tags "resistor SMD 0402")
		(property "Reference" "R208"
			(at 3.8 -0.333748 90)
			(layer "B.SilkS")
			(effects
				(font
					(size 0.7 0.7)
					(thickness 0.15)
				)
				(justify left bottom mirror)
			)
		)
		(property "Value" "R_10k_0402"
			(at 0 -1.4 90)
			(layer "B.Fab")
			(effects
				(font
					(size 0.7 0.7)
					(thickness 0.15)
				)
				(justify left bottom mirror)
			)
		)
		(property "Description" "SMD Chip Resistor, 10 kohm, ± 1%, 62.5 mW, 0402 [1005 Metric], Thick Film, General Purpose"
			(at 0 0 270)
			(layer "F.Fab")
			(hide yes)
			(effects
				(font
					(size 1.27 1.27)
					(thickness 0.15)
				)
			)
		)
		(property "Author" "Antmicro"
			(at 101.641252 300.141252 0)
			(layer "B.Fab")
			(hide yes)
			(effects
				(font
					(size 1 1)
					(thickness 0.15)
				)
				(justify mirror)
			)
		)
		(property "License" "Apache-2.0"
			(at 101.641252 300.141252 0)
			(layer "B.Fab")
			(hide yes)
			(effects
				(font
					(size 1 1)
					(thickness 0.15)
				)
				(justify mirror)
			)
		)
		(property "MPN" "CR0402-FX-1002GLF"
			(at 101.641252 300.141252 0)
			(layer "B.Fab")
			(hide yes)
			(effects
				(font
					(size 1 1)
					(thickness 0.15)
				)
				(justify mirror)
			)
		)
		(property "Manufacturer" "Bourns"
			(at 101.641252 300.141252 0)
			(layer "B.Fab")
			(hide yes)
			(effects
				(font
					(size 1 1)
					(thickness 0.15)
				)
				(justify mirror)
			)
		)
		(property "Tolerance" "1%"
			(at 101.641252 300.141252 0)
			(layer "B.Fab")
			(hide yes)
			(effects
				(font
					(size 1 1)
					(thickness 0.15)
				)
				(justify mirror)
			)
		)
		(property "Val" "10k"
			(at 101.641252 300.141252 0)
			(layer "B.Fab")
			(hide yes)
			(effects
				(font
					(size 1 1)
					(thickness 0.15)
				)
				(justify mirror)
			)
		)
		(sheetname "HDMI + Ethernet")
		(sheetfile "hdmi-ethernet.kicad_sch")
		(attr smd)
		(fp_rect
			(start -0.925 0.47)
			(end 0.925 -0.47)
			(stroke
				(width 0.05)
				(type default)
			)
			(fill no)
			(layer "B.CrtYd")
		)
		(fp_rect
			(start -0.5 0.25)
			(end 0.5 -0.25)
			(stroke
				(width 0.15)
				(type solid)
			)
			(fill no)
			(layer "B.Fab")
		)
		(pad "1" smd roundrect
			(at -0.48 0 270)
			(size 0.59 0.64)
			(layers "B.Cu" "B.Mask" "B.Paste")
			(roundrect_rratio 0.25)
			(net 510 "/FPGA Bank 16 & 17/GBE_RGMII.REFCLK")
			(pintype "passive")
		)
		(pad "2" smd roundrect
			(at 0.48 0 270)
			(size 0.59 0.64)
			(layers "B.Cu" "B.Mask" "B.Paste")
			(roundrect_rratio 0.25)
			(net 24 "+3V3")
			(pintype "passive")
		)
	)
	(footprint "antmicro-footprints:R_Array_4x0201_Panasonic_EXB18V"
		(layer "B.Cu")
		(at 251.901 127.9)
		(property "Reference" "R22"
			(at 1.099 -0.725 0)
			(layer "B.SilkS")
			(effects
				(font
					(size 0.7 0.7)
					(thickness 0.15)
				)
				(justify left bottom mirror)
			)
		)
		(property "Value" "R_4x33R_0201_array"
			(at -1.1 -1.8 0)
			(layer "B.Fab")
			(effects
				(font
					(size 0.7 0.7)
					(thickness 0.15)
				)
				(justify right bottom mirror)
			)
		)
		(property "Description" "Fixed Network Resistor, 33 ohm, Isolated, 4 Resistors, 0502 [1406 Metric], Flat, ± 5%"
			(at 0 0 0)
			(layer "F.Fab")
			(hide yes)
			(effects
				(font
					(size 1.27 1.27)
					(thickness 0.15)
				)
			)
		)
		(property "Author" "Antmicro"
			(at 0 0 0)
			(layer "B.Fab")
			(hide yes)
			(effects
				(font
					(size 1 1)
					(thickness 0.15)
				)
				(justify mirror)
			)
		)
		(property "License" "Apache-2.0"
			(at 0 0 0)
			(layer "B.Fab")
			(hide yes)
			(effects
				(font
					(size 1 1)
					(thickness 0.15)
				)
				(justify mirror)
			)
		)
		(property "MPN" "EXB-18V330JX"
			(at 0 0 0)
			(layer "B.Fab")
			(hide yes)
			(effects
				(font
					(size 1 1)
					(thickness 0.15)
				)
				(justify mirror)
			)
		)
		(property "Manufacturer" "Panasonic"
			(at 0 0 0)
			(layer "B.Fab")
			(hide yes)
			(effects
				(font
					(size 1 1)
					(thickness 0.15)
				)
				(justify mirror)
			)
		)
		(property "Val" "R_4x33R_0201"
			(at 0 0 0)
			(layer "B.Fab")
			(hide yes)
			(effects
				(font
					(size 1 1)
					(thickness 0.15)
				)
				(justify mirror)
			)
		)
		(sheetname "Supervisior MCU")
		(sheetfile "supervisor-mcu.kicad_sch")
		(attr smd)
		(fp_line
			(start -0.8 0.45)
			(end -0.8 -0.45)
			(stroke
				(width 0.12)
				(type solid)
			)
			(layer "B.SilkS")
		)
		(fp_line
			(start 0.8 0.45)
			(end 0.8 -0.45)
			(stroke
				(width 0.12)
				(type solid)
			)
			(layer "B.SilkS")
		)
		(fp_rect
			(start -0.898 0.66)
			(end 0.898 -0.65)
			(stroke
				(width 0.05)
				(type solid)
			)
			(fill no)
			(layer "B.CrtYd")
		)
		(pad "1" smd roundrect
			(at -0.6 -0.298)
			(size 0.2 0.4)
			(layers "B.Cu" "B.Mask" "B.Paste")
			(roundrect_rratio 0.25)
			(net 1340 "/SUP_MCU.SW_STATE")
			(pinfunction "R1.1")
			(pintype "passive")
		)
		(pad "2" smd roundrect
			(at -0.202 -0.298)
			(size 0.2 0.4)
			(layers "B.Cu" "B.Mask" "B.Paste")
			(roundrect_rratio 0.25)
			(net 1332 "/SUP_MCU.CCLK")
			(pinfunction "R2.1")
			(pintype "passive")
		)
		(pad "3" smd roundrect
			(at 0.2 -0.298)
			(size 0.2 0.4)
			(layers "B.Cu" "B.Mask" "B.Paste")
			(roundrect_rratio 0.25)
			(net 348 "unconnected-(R22-R3.1-Pad3)")
			(pinfunction "R3.1")
			(pintype "passive+no_connect")
		)
		(pad "4" smd roundrect
			(at 0.598 -0.298)
			(size 0.2 0.4)
			(layers "B.Cu" "B.Mask" "B.Paste")
			(roundrect_rratio 0.25)
			(net 1358 "/SUP_MCU.A2")
			(pinfunction "R4.1")
			(pintype "passive")
		)
		(pad "5" smd roundrect
			(at 0.598 0.3)
			(size 0.2 0.4)
			(layers "B.Cu" "B.Mask" "B.Paste")
			(roundrect_rratio 0.25)
			(net 1063 "/Supervisior MCU/USB_A2")
			(pinfunction "R4.2")
			(pintype "passive")
		)
		(pad "6" smd roundrect
			(at 0.2 0.3)
			(size 0.2 0.4)
			(layers "B.Cu" "B.Mask" "B.Paste")
			(roundrect_rratio 0.25)
			(net 1108 "/Supervisior MCU/PWR_RST")
			(pinfunction "R3.2")
			(pintype "passive")
		)
		(pad "7" smd roundrect
			(at -0.202 0.3)
			(size 0.2 0.4)
			(layers "B.Cu" "B.Mask" "B.Paste")
			(roundrect_rratio 0.25)
			(net 112 "/Supervisior MCU/SAM_FPGA_CCLK")
			(pinfunction "R2.2")
			(pintype "passive")
		)
		(pad "8" smd roundrect
			(at -0.6 0.3)
			(size 0.2 0.4)
			(layers "B.Cu" "B.Mask" "B.Paste")
			(roundrect_rratio 0.25)
			(net 276 "/Supervisior MCU/SW_STATE")
			(pinfunction "R1.2")
			(pintype "passive")
		)
	)
	(footprint "antmicro-footprints:USON-10_2.5x1mm_P0.5mm"
		(layer "B.Cu")
		(at 190.000001 74.000001 90)
		(descr "USON-10 2.5x1mm_ Pitch 0.5mm")
		(tags "USON-10 2.5x1mm Pitch 0.5mm")
		(property "Reference" "U2"
			(at -1.649999 0.799999 0)
			(layer "B.SilkS")
			(effects
				(font
					(size 0.7 0.7)
					(thickness 0.15)
				)
				(justify left bottom mirror)
			)
		)
		(property "Value" "TPD4E05U06QDQARQ1"
			(at 0.018 -2.499 270)
			(layer "B.Fab")
			(effects
				(font
					(size 0.7 0.7)
					(thickness 0.15)
				)
				(justify left bottom mirror)
			)
		)
		(property "Description" "ESD protection"
			(at 0 0 90)
			(layer "F.Fab")
			(hide yes)
			(effects
				(font
					(size 1.27 1.27)
					(thickness 0.15)
				)
			)
		)
		(property "Author" "Antmicro"
			(at 264.000002 -116 0)
			(layer "B.Fab")
			(hide yes)
			(effects
				(font
					(size 1 1)
					(thickness 0.15)
				)
				(justify mirror)
			)
		)
		(property "License" "Apache-2.0"
			(at 264.000002 -116 0)
			(layer "B.Fab")
			(hide yes)
			(effects
				(font
					(size 1 1)
					(thickness 0.15)
				)
				(justify mirror)
			)
		)
		(property "MPN" "TPD4E05U06QDQARQ1"
			(at 264.000002 -116 0)
			(layer "B.Fab")
			(hide yes)
			(effects
				(font
					(size 1 1)
					(thickness 0.15)
				)
				(justify mirror)
			)
		)
		(property "Manufacturer" "Texas Instruments"
			(at 264.000002 -116 0)
			(layer "B.Fab")
			(hide yes)
			(effects
				(font
					(size 1 1)
					(thickness 0.15)
				)
				(justify mirror)
			)
		)
		(sheetname "FPGA Config")
		(sheetfile "fpga-config.kicad_sch")
		(attr smd)
		(fp_line
			(start 0.498 -1.398)
			(end -0.5 -1.398)
			(stroke
				(width 0.15)
				(type solid)
			)
			(layer "B.SilkS")
		)
		(fp_line
			(start 0.498 1.401)
			(end -0.5 1.401)
			(stroke
				(width 0.15)
				(type solid)
			)
			(layer "B.SilkS")
		)
		(fp_circle
			(center -0.68 1.27)
			(end -0.63 1.27)
			(stroke
				(width 0.15)
				(type solid)
			)
			(fill yes)
			(layer "B.SilkS")
		)
		(fp_rect
			(start -0.8 1.5)
			(end 0.8 -1.499)
			(stroke
				(width 0.05)
				(type solid)
			)
			(fill no)
			(layer "B.CrtYd")
		)
		(fp_line
			(start -0.5 -1.249)
			(end 0.498 -1.249)
			(stroke
				(width 0.15)
				(type solid)
			)
			(layer "B.Fab")
		)
		(fp_line
			(start -0.5 1)
			(end -0.5 -1.249)
			(stroke
				(width 0.15)
				(type solid)
			)
			(layer "B.Fab")
		)
		(fp_line
			(start 0.498 1.25)
			(end 0.498 -1.249)
			(stroke
				(width 0.15)
				(type solid)
			)
			(layer "B.Fab")
		)
		(fp_line
			(start 0.498 1.25)
			(end -0.25 1.25)
			(stroke
				(width 0.15)
				(type solid)
			)
			(layer "B.Fab")
		)
		(fp_line
			(start -0.25 1.25)
			(end -0.5 1)
			(stroke
				(width 0.15)
				(type solid)
			)
			(layer "B.Fab")
		)
		(pad "1" smd roundrect
			(at -0.387 1 180)
			(size 0.25 0.55)
			(layers "B.Cu" "B.Mask" "B.Paste")
			(roundrect_rratio 0.25)
			(net 161 "/FPGA Config/JTAG.TMS")
			(pintype "passive")
		)
		(pad "2" smd roundrect
			(at -0.387 0.5 180)
			(size 0.25 0.55)
			(layers "B.Cu" "B.Mask" "B.Paste")
			(roundrect_rratio 0.25)
			(net 165 "/FPGA Config/JTAG.TCK")
			(pintype "passive")
		)
		(pad "3" smd roundrect
			(at -0.387 0 180)
			(size 0.4 0.55)
			(layers "B.Cu" "B.Mask" "B.Paste")
			(roundrect_rratio 0.25)
			(net 1 "GND")
			(pintype "power_in")
		)
		(pad "4" smd roundrect
			(at -0.387 -0.498 180)
			(size 0.25 0.55)
			(layers "B.Cu" "B.Mask" "B.Paste")
			(roundrect_rratio 0.25)
			(net 190 "/FPGA Config/JTAG.TDO")
			(pintype "passive")
		)
		(pad "5" smd roundrect
			(at -0.387 -0.998 180)
			(size 0.25 0.55)
			(layers "B.Cu" "B.Mask" "B.Paste")
			(roundrect_rratio 0.25)
			(net 220 "/FPGA Config/JTAG.TDI")
			(pintype "passive")
		)
		(pad "6" smd roundrect
			(at 0.385 -0.998 180)
			(size 0.25 0.55)
			(layers "B.Cu" "B.Mask" "B.Paste")
			(roundrect_rratio 0.25)
			(net 220 "/FPGA Config/JTAG.TDI")
			(pintype "passive")
		)
		(pad "7" smd roundrect
			(at 0.385 -0.498 180)
			(size 0.25 0.55)
			(layers "B.Cu" "B.Mask" "B.Paste")
			(roundrect_rratio 0.25)
			(net 190 "/FPGA Config/JTAG.TDO")
			(pintype "passive")
		)
		(pad "8" smd roundrect
			(at 0.385 0 180)
			(size 0.4 0.55)
			(layers "B.Cu" "B.Mask" "B.Paste")
			(roundrect_rratio 0.25)
			(net 1 "GND")
			(pintype "passive")
		)
		(pad "9" smd roundrect
			(at 0.385 0.5 180)
			(size 0.25 0.55)
			(layers "B.Cu" "B.Mask" "B.Paste")
			(roundrect_rratio 0.25)
			(net 165 "/FPGA Config/JTAG.TCK")
			(pintype "passive")
		)
		(pad "10" smd roundrect
			(at 0.385 1 180)
			(size 0.25 0.55)
			(layers "B.Cu" "B.Mask" "B.Paste")
			(roundrect_rratio 0.25)
			(net 161 "/FPGA Config/JTAG.TMS")
			(pintype "passive")
		)
	)
	(footprint "antmicro-footprints:NetTie-2_SMD_Pad0.127mm"
		(layer "B.Cu")
		(at 196.76 86.9 -135)
		(descr "Net tie, 2 pin, 0.127mm  SMD pads")
		(tags "net tie")
		(property "Reference" "NT37"
			(at -0.128 1.345 45)
			(layer "B.SilkS")
			(hide yes)
			(effects
				(font
					(size 0.7 0.7)
					(thickness 0.15)
				)
				(justify left bottom mirror)
			)
		)
		(property "Value" "Net-Tie_2"
			(at 0 -1.199 45)
			(layer "B.Fab")
			(effects
				(font
					(size 0.7 0.7)
					(thickness 0.15)
				)
				(justify left bottom mirror)
			)
		)
		(property "Description" "Net tie, 2 pins"
			(at 0 0 225)
			(layer "F.Fab")
			(hide yes)
			(effects
				(font
					(size 1.27 1.27)
					(thickness 0.15)
				)
			)
		)
		(property "Author" "Antmicro"
			(at 274.442751 287.47791 0)
			(layer "B.Fab")
			(hide yes)
			(effects
				(font
					(size 1 1)
					(thickness 0.15)
				)
				(justify mirror)
			)
		)
		(property "License" "Apache-2.0"
			(at 274.442751 287.47791 0)
			(layer "B.Fab")
			(hide yes)
			(effects
				(font
					(size 1 1)
					(thickness 0.15)
				)
				(justify mirror)
			)
		)
		(property "MPN" ""
			(at 274.442751 287.47791 0)
			(layer "B.Fab")
			(hide yes)
			(effects
				(font
					(size 1 1)
					(thickness 0.15)
				)
				(justify mirror)
			)
		)
		(property "Manufacturer" ""
			(at 274.442751 287.47791 0)
			(layer "B.Fab")
			(hide yes)
			(effects
				(font
					(size 1 1)
					(thickness 0.15)
				)
				(justify mirror)
			)
		)
		(sheetname "DC-DC Converters")
		(sheetfile "dc-dc.kicad_sch")
		(attr exclude_from_pos_files)
		(net_tie_pad_groups "1, 2")
		(fp_poly
			(pts
				(xy -0.0635 0.0635) (xy 0.0625 0.0635) (xy 0.0625 -0.0635) (xy -0.0635 -0.0635)
			)
			(stroke
				(width 0)
				(type solid)
			)
			(fill yes)
			(layer "B.Cu")
		)
		(pad "1" smd roundrect
			(at -0.127001 0 45)
			(size 0.127 0.127)
			(layers "B.Cu")
			(roundrect_rratio 0.5)
			(chamfer_ratio 0)
			(chamfer top_left bottom_left)
			(net 1 "GND")
			(pinfunction "1")
			(pintype "passive")
		)
		(pad "2" smd roundrect
			(at 0.125999 0 225)
			(size 0.127 0.127)
			(layers "B.Cu")
			(roundrect_rratio 0.5)
			(chamfer_ratio 0)
			(chamfer top_left bottom_left)
			(net 1225 "/DC-DC Converters/SENSE_1V2_N")
			(pinfunction "2")
			(pintype "passive")
		)
	)
	(footprint "antmicro-footprints:C_0201"
		(layer "B.Cu")
		(at 192.3 116.2 -45)
		(descr "Capacitor SMD 0201")
		(tags "capacitor SMD 0201")
		(property "Reference" "C124"
			(at 1.467247 -0.371231 315)
			(unlocked yes)
			(layer "B.SilkS")
			(effects
				(font
					(size 0.7 0.7)
					(thickness 0.15)
				)
				(justify left bottom mirror)
			)
		)
		(property "Value" "C_100n_0201"
			(at 0 -1.399999 135)
			(layer "B.Fab")
			(effects
				(font
					(size 0.7 0.7)
					(thickness 0.15)
				)
				(justify left bottom mirror)
			)
		)
		(property "Description" "SMD Multilayer Ceramic Capacitor, 0.1 µF, 6.3 V, 0201 [0603 Metric], ± 10%, X6S, CC Series"
			(at 0 0 315)
			(layer "F.Fab")
			(hide yes)
			(effects
				(font
					(size 1.27 1.27)
					(thickness 0.15)
				)
			)
		)
		(property "Author" "Antmicro"
			(at -25.842442 170.010826 0)
			(layer "B.Fab")
			(hide yes)
			(effects
				(font
					(size 1 1)
					(thickness 0.15)
				)
				(justify mirror)
			)
		)
		(property "Dielectric" ""
			(at -25.842442 170.010826 0)
			(layer "B.Fab")
			(hide yes)
			(effects
				(font
					(size 1 1)
					(thickness 0.15)
				)
				(justify mirror)
			)
		)
		(property "License" "Apache-2.0"
			(at -25.842442 170.010826 0)
			(layer "B.Fab")
			(hide yes)
			(effects
				(font
					(size 1 1)
					(thickness 0.15)
				)
				(justify mirror)
			)
		)
		(property "MPN" "CC0201KRX6S5BB104"
			(at -25.842442 170.010826 0)
			(layer "B.Fab")
			(hide yes)
			(effects
				(font
					(size 1 1)
					(thickness 0.15)
				)
				(justify mirror)
			)
		)
		(property "Manufacturer" "YAGEO"
			(at -25.842442 170.010826 0)
			(layer "B.Fab")
			(hide yes)
			(effects
				(font
					(size 1 1)
					(thickness 0.15)
				)
				(justify mirror)
			)
		)
		(property "Val" "100n"
			(at -25.842442 170.010826 0)
			(layer "B.Fab")
			(hide yes)
			(effects
				(font
					(size 1 1)
					(thickness 0.15)
				)
				(justify mirror)
			)
		)
		(property "Voltage" ""
			(at -25.842442 170.010826 0)
			(layer "B.Fab")
			(hide yes)
			(effects
				(font
					(size 1 1)
					(thickness 0.15)
				)
				(justify mirror)
			)
		)
		(sheetname "FPGA supply")
		(sheetfile "fpga-supply.kicad_sch")
		(attr smd)
		(fp_poly
			(pts
				(xy -0.7 0.35) (xy 0.7 0.35) (xy 0.7 -0.35) (xy -0.7 -0.35)
			)
			(stroke
				(width 0.05)
				(type default)
			)
			(fill no)
			(layer "B.CrtYd")
		)
		(fp_poly
			(pts
				(xy 0.3 -0.15) (xy -0.301 -0.15) (xy -0.301 0.149) (xy 0.3 0.149)
			)
			(stroke
				(width 0.15)
				(type solid)
			)
			(fill no)
			(layer "B.Fab")
		)
		(pad "" smd roundrect
			(at -0.349 0.002 315)
			(size 0.318 0.36)
			(layers "B.Paste")
			(roundrect_rratio 0.25)
		)
		(pad "" smd roundrect
			(at 0.341 0.002 315)
			(size 0.318 0.36)
			(layers "B.Paste")
			(roundrect_rratio 0.25)
		)
		(pad "1" smd roundrect
			(at -0.321 0.002 315)
			(size 0.46 0.4)
			(layers "B.Cu" "B.Mask")
			(roundrect_rratio 0.25)
			(net 6 "+1V0_MGTAVCC")
			(pintype "passive")
		)
		(pad "2" smd roundrect
			(at 0.32 0.002 315)
			(size 0.46 0.4)
			(layers "B.Cu" "B.Mask")
			(roundrect_rratio 0.25)
			(net 1 "GND")
			(pintype "passive")
		)
	)
	(footprint "antmicro-footprints:C_0402_1005Metric"
		(layer "B.Cu")
		(at 215.875 118.025 180)
		(descr "Capacitor SMD 0402")
		(tags "capacitor SMD 0402")
		(property "Reference" "C15"
			(at -1.1 -1.225 0)
			(layer "B.SilkS")
			(effects
				(font
					(size 0.7 0.7)
					(thickness 0.15)
				)
				(justify left bottom mirror)
			)
		)
		(property "Value" "C_100n_0402"
			(at 0 -1.169 0)
			(layer "B.Fab")
			(effects
				(font
					(size 0.7 0.7)
					(thickness 0.15)
				)
				(justify left bottom mirror)
			)
		)
		(property "Description" "SMD Multilayer Ceramic Capacitor, 0.1 µF, 50 V, 0402 [1005 Metric], ± 10%, X5R, GRM Series"
			(at 0 0 180)
			(layer "F.Fab")
			(hide yes)
			(effects
				(font
					(size 1.27 1.27)
					(thickness 0.15)
				)
			)
		)
		(property "Author" "Antmicro"
			(at 431.75 236.05 0)
			(layer "B.Fab")
			(hide yes)
			(effects
				(font
					(size 1 1)
					(thickness 0.15)
				)
				(justify mirror)
			)
		)
		(property "Dielectric" "X5R"
			(at 431.75 236.05 0)
			(layer "B.Fab")
			(hide yes)
			(effects
				(font
					(size 1 1)
					(thickness 0.15)
				)
				(justify mirror)
			)
		)
		(property "License" "Apache-2.0"
			(at 431.75 236.05 0)
			(layer "B.Fab")
			(hide yes)
			(effects
				(font
					(size 1 1)
					(thickness 0.15)
				)
				(justify mirror)
			)
		)
		(property "MPN" "GRM155R61H104KE14D"
			(at 431.75 236.05 0)
			(layer "B.Fab")
			(hide yes)
			(effects
				(font
					(size 1 1)
					(thickness 0.15)
				)
				(justify mirror)
			)
		)
		(property "Manufacturer" "Murata"
			(at 431.75 236.05 0)
			(layer "B.Fab")
			(hide yes)
			(effects
				(font
					(size 1 1)
					(thickness 0.15)
				)
				(justify mirror)
			)
		)
		(property "Val" "100n"
			(at 431.75 236.05 0)
			(layer "B.Fab")
			(hide yes)
			(effects
				(font
					(size 1 1)
					(thickness 0.15)
				)
				(justify mirror)
			)
		)
		(property "Voltage" "50V"
			(at 431.75 236.05 0)
			(layer "B.Fab")
			(hide yes)
			(effects
				(font
					(size 1 1)
					(thickness 0.15)
				)
				(justify mirror)
			)
		)
		(sheetname "FPGA Bank 16 & 17")
		(sheetfile "fpga-bank-16-17.kicad_sch")
		(attr smd)
		(fp_rect
			(start -0.925 0.47)
			(end 0.925 -0.47)
			(stroke
				(width 0.05)
				(type default)
			)
			(fill no)
			(layer "B.CrtYd")
		)
		(fp_line
			(start 0.504 0.25)
			(end 0.504 -0.248)
			(stroke
				(width 0.15)
				(type solid)
			)
			(layer "B.Fab")
		)
		(fp_line
			(start 0.504 -0.248)
			(end -0.494 -0.248)
			(stroke
				(width 0.15)
				(type solid)
			)
			(layer "B.Fab")
		)
		(fp_line
			(start -0.494 0.25)
			(end 0.504 0.25)
			(stroke
				(width 0.15)
				(type solid)
			)
			(layer "B.Fab")
		)
		(fp_line
			(start -0.494 -0.248)
			(end -0.494 0.25)
			(stroke
				(width 0.15)
				(type solid)
			)
			(layer "B.Fab")
		)
		(pad "1" smd roundrect
			(at -0.48 0 180)
			(size 0.59 0.64)
			(layers "B.Cu" "B.Mask" "B.Paste")
			(roundrect_rratio 0.25)
			(net 1 "GND")
			(pintype "passive")
		)
		(pad "2" smd roundrect
			(at 0.48 0 180)
			(size 0.59 0.64)
			(layers "B.Cu" "B.Mask" "B.Paste")
			(roundrect_rratio 0.25)
			(net 3 "VCC_USR_B")
			(pintype "passive")
		)
	)
	(footprint "antmicro-footprints:C_0402_1005Metric"
		(layer "B.Cu")
		(at 251.701 112.3 180)
		(descr "Capacitor SMD 0402")
		(tags "capacitor SMD 0402")
		(property "Reference" "C398"
			(at -3.799 -0.325 0)
			(layer "B.SilkS")
			(effects
				(font
					(size 0.7 0.7)
					(thickness 0.15)
				)
				(justify left bottom mirror)
			)
		)
		(property "Value" "C_100n_0402"
			(at 0 -1.169 0)
			(layer "B.Fab")
			(effects
				(font
					(size 0.7 0.7)
					(thickness 0.15)
				)
				(justify left bottom mirror)
			)
		)
		(property "Description" "SMD Multilayer Ceramic Capacitor, 0.1 µF, 50 V, 0402 [1005 Metric], ± 10%, X5R, GRM Series"
			(at 0 0 180)
			(layer "F.Fab")
			(hide yes)
			(effects
				(font
					(size 1.27 1.27)
					(thickness 0.15)
				)
			)
		)
		(property "Author" "Antmicro"
			(at 503.402 224.6 0)
			(layer "B.Fab")
			(hide yes)
			(effects
				(font
					(size 1 1)
					(thickness 0.15)
				)
				(justify mirror)
			)
		)
		(property "Dielectric" "X5R"
			(at 503.402 224.6 0)
			(layer "B.Fab")
			(hide yes)
			(effects
				(font
					(size 1 1)
					(thickness 0.15)
				)
				(justify mirror)
			)
		)
		(property "License" "Apache-2.0"
			(at 503.402 224.6 0)
			(layer "B.Fab")
			(hide yes)
			(effects
				(font
					(size 1 1)
					(thickness 0.15)
				)
				(justify mirror)
			)
		)
		(property "MPN" "GRM155R61H104KE14D"
			(at 503.402 224.6 0)
			(layer "B.Fab")
			(hide yes)
			(effects
				(font
					(size 1 1)
					(thickness 0.15)
				)
				(justify mirror)
			)
		)
		(property "Manufacturer" "Murata"
			(at 503.402 224.6 0)
			(layer "B.Fab")
			(hide yes)
			(effects
				(font
					(size 1 1)
					(thickness 0.15)
				)
				(justify mirror)
			)
		)
		(property "Val" "100n"
			(at 503.402 224.6 0)
			(layer "B.Fab")
			(hide yes)
			(effects
				(font
					(size 1 1)
					(thickness 0.15)
				)
				(justify mirror)
			)
		)
		(property "Voltage" "50V"
			(at 503.402 224.6 0)
			(layer "B.Fab")
			(hide yes)
			(effects
				(font
					(size 1 1)
					(thickness 0.15)
				)
				(justify mirror)
			)
		)
		(sheetname "HDMI + Ethernet")
		(sheetfile "hdmi-ethernet.kicad_sch")
		(attr smd)
		(fp_rect
			(start -0.925 0.47)
			(end 0.925 -0.47)
			(stroke
				(width 0.05)
				(type default)
			)
			(fill no)
			(layer "B.CrtYd")
		)
		(fp_line
			(start 0.504 0.25)
			(end 0.504 -0.248)
			(stroke
				(width 0.15)
				(type solid)
			)
			(layer "B.Fab")
		)
		(fp_line
			(start 0.504 -0.248)
			(end -0.494 -0.248)
			(stroke
				(width 0.15)
				(type solid)
			)
			(layer "B.Fab")
		)
		(fp_line
			(start -0.494 0.25)
			(end 0.504 0.25)
			(stroke
				(width 0.15)
				(type solid)
			)
			(layer "B.Fab")
		)
		(fp_line
			(start -0.494 -0.248)
			(end -0.494 0.25)
			(stroke
				(width 0.15)
				(type solid)
			)
			(layer "B.Fab")
		)
		(pad "1" smd roundrect
			(at -0.48 0 180)
			(size 0.59 0.64)
			(layers "B.Cu" "B.Mask" "B.Paste")
			(roundrect_rratio 0.25)
			(net 1 "GND")
			(pintype "passive")
		)
		(pad "2" smd roundrect
			(at 0.48 0 180)
			(size 0.59 0.64)
			(layers "B.Cu" "B.Mask" "B.Paste")
			(roundrect_rratio 0.25)
			(net 795 "/HDMI + Ethernet/HDMI_5V")
			(pintype "passive")
		)
	)
	(footprint "antmicro-footprints:C_0402_1005Metric"
		(layer "B.Cu")
		(at 173.15 141.7 180)
		(descr "Capacitor SMD 0402")
		(tags "capacitor SMD 0402")
		(property "Reference" "C294"
			(at -1.9 0.45 0)
			(layer "B.SilkS")
			(effects
				(font
					(size 0.7 0.7)
					(thickness 0.15)
				)
				(justify left bottom mirror)
			)
		)
		(property "Value" "C_100n_0402"
			(at 0 -1.169 0)
			(layer "B.Fab")
			(effects
				(font
					(size 0.7 0.7)
					(thickness 0.15)
				)
				(justify left bottom mirror)
			)
		)
		(property "Description" "SMD Multilayer Ceramic Capacitor, 0.1 µF, 50 V, 0402 [1005 Metric], ± 10%, X5R, GRM Series"
			(at 0 0 180)
			(layer "F.Fab")
			(hide yes)
			(effects
				(font
					(size 1.27 1.27)
					(thickness 0.15)
				)
			)
		)
		(property "Author" "Antmicro"
			(at 346.3 283.4 0)
			(layer "B.Fab")
			(hide yes)
			(effects
				(font
					(size 1 1)
					(thickness 0.15)
				)
				(justify mirror)
			)
		)
		(property "Dielectric" "X5R"
			(at 346.3 283.4 0)
			(layer "B.Fab")
			(hide yes)
			(effects
				(font
					(size 1 1)
					(thickness 0.15)
				)
				(justify mirror)
			)
		)
		(property "License" "Apache-2.0"
			(at 346.3 283.4 0)
			(layer "B.Fab")
			(hide yes)
			(effects
				(font
					(size 1 1)
					(thickness 0.15)
				)
				(justify mirror)
			)
		)
		(property "MPN" "GRM155R61H104KE14D"
			(at 346.3 283.4 0)
			(layer "B.Fab")
			(hide yes)
			(effects
				(font
					(size 1 1)
					(thickness 0.15)
				)
				(justify mirror)
			)
		)
		(property "Manufacturer" "Murata"
			(at 346.3 283.4 0)
			(layer "B.Fab")
			(hide yes)
			(effects
				(font
					(size 1 1)
					(thickness 0.15)
				)
				(justify mirror)
			)
		)
		(property "Val" "100n"
			(at 346.3 283.4 0)
			(layer "B.Fab")
			(hide yes)
			(effects
				(font
					(size 1 1)
					(thickness 0.15)
				)
				(justify mirror)
			)
		)
		(property "Voltage" "50V"
			(at 346.3 283.4 0)
			(layer "B.Fab")
			(hide yes)
			(effects
				(font
					(size 1 1)
					(thickness 0.15)
				)
				(justify mirror)
			)
		)
		(sheetname "DRAM + SRAM")
		(sheetfile "ram.kicad_sch")
		(attr smd)
		(fp_rect
			(start -0.925 0.47)
			(end 0.925 -0.47)
			(stroke
				(width 0.05)
				(type default)
			)
			(fill no)
			(layer "B.CrtYd")
		)
		(fp_line
			(start 0.504 0.25)
			(end 0.504 -0.248)
			(stroke
				(width 0.15)
				(type solid)
			)
			(layer "B.Fab")
		)
		(fp_line
			(start 0.504 -0.248)
			(end -0.494 -0.248)
			(stroke
				(width 0.15)
				(type solid)
			)
			(layer "B.Fab")
		)
		(fp_line
			(start -0.494 0.25)
			(end 0.504 0.25)
			(stroke
				(width 0.15)
				(type solid)
			)
			(layer "B.Fab")
		)
		(fp_line
			(start -0.494 -0.248)
			(end -0.494 0.25)
			(stroke
				(width 0.15)
				(type solid)
			)
			(layer "B.Fab")
		)
		(pad "1" smd roundrect
			(at -0.48 0 180)
			(size 0.59 0.64)
			(layers "B.Cu" "B.Mask" "B.Paste")
			(roundrect_rratio 0.25)
			(net 1 "GND")
			(pintype "passive")
		)
		(pad "2" smd roundrect
			(at 0.48 0 180)
			(size 0.59 0.64)
			(layers "B.Cu" "B.Mask" "B.Paste")
			(roundrect_rratio 0.25)
			(net 25 "+1V35")
			(pintype "passive")
		)
	)
	(footprint "antmicro-footprints:C_0402_1005Metric"
		(layer "B.Cu")
		(at 193.5 138 -90)
		(descr "Capacitor SMD 0402")
		(tags "capacitor SMD 0402")
		(property "Reference" "C95"
			(at -0.85 -1.25 90)
			(layer "B.SilkS")
			(effects
				(font
					(size 0.7 0.7)
					(thickness 0.15)
				)
				(justify left bottom mirror)
			)
		)
		(property "Value" "C_100n_0402"
			(at 0 -1.169 90)
			(layer "B.Fab")
			(effects
				(font
					(size 0.7 0.7)
					(thickness 0.15)
				)
				(justify left bottom mirror)
			)
		)
		(property "Description" "SMD Multilayer Ceramic Capacitor, 0.1 µF, 50 V, 0402 [1005 Metric], ± 10%, X5R, GRM Series"
			(at 0 0 270)
			(layer "F.Fab")
			(hide yes)
			(effects
				(font
					(size 1.27 1.27)
					(thickness 0.15)
				)
			)
		)
		(property "Author" "Antmicro"
			(at 55.5 331.5 0)
			(layer "B.Fab")
			(hide yes)
			(effects
				(font
					(size 1 1)
					(thickness 0.15)
				)
				(justify mirror)
			)
		)
		(property "Dielectric" "X5R"
			(at 55.5 331.5 0)
			(layer "B.Fab")
			(hide yes)
			(effects
				(font
					(size 1 1)
					(thickness 0.15)
				)
				(justify mirror)
			)
		)
		(property "License" "Apache-2.0"
			(at 55.5 331.5 0)
			(layer "B.Fab")
			(hide yes)
			(effects
				(font
					(size 1 1)
					(thickness 0.15)
				)
				(justify mirror)
			)
		)
		(property "MPN" "GRM155R61H104KE14D"
			(at 55.5 331.5 0)
			(layer "B.Fab")
			(hide yes)
			(effects
				(font
					(size 1 1)
					(thickness 0.15)
				)
				(justify mirror)
			)
		)
		(property "Manufacturer" "Murata"
			(at 55.5 331.5 0)
			(layer "B.Fab")
			(hide yes)
			(effects
				(font
					(size 1 1)
					(thickness 0.15)
				)
				(justify mirror)
			)
		)
		(property "Val" "100n"
			(at 55.5 331.5 0)
			(layer "B.Fab")
			(hide yes)
			(effects
				(font
					(size 1 1)
					(thickness 0.15)
				)
				(justify mirror)
			)
		)
		(property "Voltage" "50V"
			(at 55.5 331.5 0)
			(layer "B.Fab")
			(hide yes)
			(effects
				(font
					(size 1 1)
					(thickness 0.15)
				)
				(justify mirror)
			)
		)
		(sheetname "FPGA Bank 33 & 34")
		(sheetfile "fpga-bank-33-34.kicad_sch")
		(attr smd)
		(fp_rect
			(start -0.925 0.47)
			(end 0.925 -0.47)
			(stroke
				(width 0.05)
				(type default)
			)
			(fill no)
			(layer "B.CrtYd")
		)
		(fp_line
			(start -0.494 0.25)
			(end 0.504 0.25)
			(stroke
				(width 0.15)
				(type solid)
			)
			(layer "B.Fab")
		)
		(fp_line
			(start 0.504 0.25)
			(end 0.504 -0.248)
			(stroke
				(width 0.15)
				(type solid)
			)
			(layer "B.Fab")
		)
		(fp_line
			(start -0.494 -0.248)
			(end -0.494 0.25)
			(stroke
				(width 0.15)
				(type solid)
			)
			(layer "B.Fab")
		)
		(fp_line
			(start 0.504 -0.248)
			(end -0.494 -0.248)
			(stroke
				(width 0.15)
				(type solid)
			)
			(layer "B.Fab")
		)
		(pad "1" smd roundrect
			(at -0.48 0 270)
			(size 0.59 0.64)
			(layers "B.Cu" "B.Mask" "B.Paste")
			(roundrect_rratio 0.25)
			(net 1 "GND")
			(pintype "passive")
		)
		(pad "2" smd roundrect
			(at 0.48 0 270)
			(size 0.59 0.64)
			(layers "B.Cu" "B.Mask" "B.Paste")
			(roundrect_rratio 0.25)
			(net 26 "+1V8")
			(pintype "passive")
		)
	)
	(footprint "antmicro-footprints:C_0402_1005Metric"
		(layer "B.Cu")
		(at 191.75 132.3)
		(descr "Capacitor SMD 0402")
		(tags "capacitor SMD 0402")
		(property "Reference" "C123"
			(at 22.925 -28.1 180)
			(layer "B.SilkS")
			(effects
				(font
					(size 0.7 0.7)
					(thickness 0.15)
				)
				(justify left bottom mirror)
			)
		)
		(property "Value" "C_100n_0402"
			(at 0 -1.169 180)
			(layer "B.Fab")
			(effects
				(font
					(size 0.7 0.7)
					(thickness 0.15)
				)
				(justify left bottom mirror)
			)
		)
		(property "Description" "SMD Multilayer Ceramic Capacitor, 0.1 µF, 50 V, 0402 [1005 Metric], ± 10%, X5R, GRM Series"
			(at 0 0 0)
			(layer "F.Fab")
			(hide yes)
			(effects
				(font
					(size 1.27 1.27)
					(thickness 0.15)
				)
			)
		)
		(property "Author" "Antmicro"
			(at 0 0 0)
			(layer "B.Fab")
			(hide yes)
			(effects
				(font
					(size 1 1)
					(thickness 0.15)
				)
				(justify mirror)
			)
		)
		(property "Dielectric" "X5R"
			(at 0 0 0)
			(layer "B.Fab")
			(hide yes)
			(effects
				(font
					(size 1 1)
					(thickness 0.15)
				)
				(justify mirror)
			)
		)
		(property "License" "Apache-2.0"
			(at 0 0 0)
			(layer "B.Fab")
			(hide yes)
			(effects
				(font
					(size 1 1)
					(thickness 0.15)
				)
				(justify mirror)
			)
		)
		(property "MPN" "GRM155R61H104KE14D"
			(at 0 0 0)
			(layer "B.Fab")
			(hide yes)
			(effects
				(font
					(size 1 1)
					(thickness 0.15)
				)
				(justify mirror)
			)
		)
		(property "Manufacturer" "Murata"
			(at 0 0 0)
			(layer "B.Fab")
			(hide yes)
			(effects
				(font
					(size 1 1)
					(thickness 0.15)
				)
				(justify mirror)
			)
		)
		(property "Val" "100n"
			(at 0 0 0)
			(layer "B.Fab")
			(hide yes)
			(effects
				(font
					(size 1 1)
					(thickness 0.15)
				)
				(justify mirror)
			)
		)
		(property "Voltage" "50V"
			(at 0 0 0)
			(layer "B.Fab")
			(hide yes)
			(effects
				(font
					(size 1 1)
					(thickness 0.15)
				)
				(justify mirror)
			)
		)
		(sheetname "FPGA supply")
		(sheetfile "fpga-supply.kicad_sch")
		(attr smd)
		(fp_rect
			(start -0.925 0.47)
			(end 0.925 -0.47)
			(stroke
				(width 0.05)
				(type default)
			)
			(fill no)
			(layer "B.CrtYd")
		)
		(fp_line
			(start -0.494 -0.248)
			(end -0.494 0.25)
			(stroke
				(width 0.15)
				(type solid)
			)
			(layer "B.Fab")
		)
		(fp_line
			(start -0.494 0.25)
			(end 0.504 0.25)
			(stroke
				(width 0.15)
				(type solid)
			)
			(layer "B.Fab")
		)
		(fp_line
			(start 0.504 -0.248)
			(end -0.494 -0.248)
			(stroke
				(width 0.15)
				(type solid)
			)
			(layer "B.Fab")
		)
		(fp_line
			(start 0.504 0.25)
			(end 0.504 -0.248)
			(stroke
				(width 0.15)
				(type solid)
			)
			(layer "B.Fab")
		)
		(pad "1" smd roundrect
			(at -0.48 0)
			(size 0.59 0.64)
			(layers "B.Cu" "B.Mask" "B.Paste")
			(roundrect_rratio 0.25)
			(net 26 "+1V8")
			(pintype "passive")
		)
		(pad "2" smd roundrect
			(at 0.48 0)
			(size 0.59 0.64)
			(layers "B.Cu" "B.Mask" "B.Paste")
			(roundrect_rratio 0.25)
			(net 1 "GND")
			(pintype "passive")
		)
	)
	(footprint "antmicro-footprints:NetTie-2_SMD_Pad0.127mm"
		(layer "B.Cu")
		(at 248.501 148.4 90)
		(descr "Net tie, 2 pin, 0.127mm  SMD pads")
		(tags "net tie")
		(property "Reference" "NT7"
			(at -0.128 1.345 270)
			(layer "B.SilkS")
			(hide yes)
			(effects
				(font
					(size 0.7 0.7)
					(thickness 0.15)
				)
				(justify left bottom mirror)
			)
		)
		(property "Value" "Net-Tie_2"
			(at 0 -1.199 270)
			(layer "B.Fab")
			(effects
				(font
					(size 0.7 0.7)
					(thickness 0.15)
				)
				(justify left bottom mirror)
			)
		)
		(property "Description" "Net tie, 2 pins"
			(at 0 0 90)
			(layer "F.Fab")
			(hide yes)
			(effects
				(font
					(size 1.27 1.27)
					(thickness 0.15)
				)
			)
		)
		(property "Author" "Antmicro"
			(at 396.901 -100.101 0)
			(layer "B.Fab")
			(hide yes)
			(effects
				(font
					(size 1 1)
					(thickness 0.15)
				)
				(justify mirror)
			)
		)
		(property "License" "Apache-2.0"
			(at 396.901 -100.101 0)
			(layer "B.Fab")
			(hide yes)
			(effects
				(font
					(size 1 1)
					(thickness 0.15)
				)
				(justify mirror)
			)
		)
		(property "MPN" ""
			(at 396.901 -100.101 0)
			(layer "B.Fab")
			(hide yes)
			(effects
				(font
					(size 1 1)
					(thickness 0.15)
				)
				(justify mirror)
			)
		)
		(property "Manufacturer" ""
			(at 396.901 -100.101 0)
			(layer "B.Fab")
			(hide yes)
			(effects
				(font
					(size 1 1)
					(thickness 0.15)
				)
				(justify mirror)
			)
		)
		(sheetname "FPGA Config")
		(sheetfile "fpga-config.kicad_sch")
		(attr exclude_from_pos_files)
		(net_tie_pad_groups "1, 2")
		(fp_poly
			(pts
				(xy -0.0635 0.0635) (xy 0.0625 0.0635) (xy 0.0625 -0.0635) (xy -0.0635 -0.0635)
			)
			(stroke
				(width 0)
				(type solid)
			)
			(fill yes)
			(layer "B.Cu")
		)
		(pad "1" smd roundrect
			(at -0.127 0 270)
			(size 0.127 0.127)
			(layers "B.Cu")
			(roundrect_rratio 0.5)
			(chamfer_ratio 0)
			(chamfer top_left bottom_left)
			(net 1316 "/SUP_MCU.INITB")
			(pinfunction "1")
			(pintype "passive")
		)
		(pad "2" smd roundrect
			(at 0.126 0 90)
			(size 0.127 0.127)
			(layers "B.Cu")
			(roundrect_rratio 0.5)
			(chamfer_ratio 0)
			(chamfer top_left bottom_left)
			(net 257 "/FPGA Config/INIT_B")
			(pinfunction "2")
			(pintype "passive")
		)
	)
	(footprint "antmicro-footprints:C_0402_1005Metric"
		(layer "B.Cu")
		(at 265.401 171.8)
		(descr "Capacitor SMD 0402")
		(tags "capacitor SMD 0402")
		(property "Reference" "C272"
			(at 3.699 0.375 180)
			(layer "B.SilkS")
			(effects
				(font
					(size 0.7 0.7)
					(thickness 0.15)
				)
				(justify left bottom mirror)
			)
		)
		(property "Value" "C_100n_0402"
			(at 0 -1.169 180)
			(layer "B.Fab")
			(effects
				(font
					(size 0.7 0.7)
					(thickness 0.15)
				)
				(justify left bottom mirror)
			)
		)
		(property "Description" "SMD Multilayer Ceramic Capacitor, 0.1 µF, 50 V, 0402 [1005 Metric], ± 10%, X5R, GRM Series"
			(at 0 0 0)
			(layer "F.Fab")
			(hide yes)
			(effects
				(font
					(size 1.27 1.27)
					(thickness 0.15)
				)
			)
		)
		(property "Author" "Antmicro"
			(at 0 0 0)
			(layer "B.Fab")
			(hide yes)
			(effects
				(font
					(size 1 1)
					(thickness 0.15)
				)
				(justify mirror)
			)
		)
		(property "Dielectric" "X5R"
			(at 0 0 0)
			(layer "B.Fab")
			(hide yes)
			(effects
				(font
					(size 1 1)
					(thickness 0.15)
				)
				(justify mirror)
			)
		)
		(property "License" "Apache-2.0"
			(at 0 0 0)
			(layer "B.Fab")
			(hide yes)
			(effects
				(font
					(size 1 1)
					(thickness 0.15)
				)
				(justify mirror)
			)
		)
		(property "MPN" "GRM155R61H104KE14D"
			(at 0 0 0)
			(layer "B.Fab")
			(hide yes)
			(effects
				(font
					(size 1 1)
					(thickness 0.15)
				)
				(justify mirror)
			)
		)
		(property "Manufacturer" "Murata"
			(at 0 0 0)
			(layer "B.Fab")
			(hide yes)
			(effects
				(font
					(size 1 1)
					(thickness 0.15)
				)
				(justify mirror)
			)
		)
		(property "Val" "100n"
			(at 0 0 0)
			(layer "B.Fab")
			(hide yes)
			(effects
				(font
					(size 1 1)
					(thickness 0.15)
				)
				(justify mirror)
			)
		)
		(property "Voltage" "50V"
			(at 0 0 0)
			(layer "B.Fab")
			(hide yes)
			(effects
				(font
					(size 1 1)
					(thickness 0.15)
				)
				(justify mirror)
			)
		)
		(sheetname "HDMI + Ethernet")
		(sheetfile "hdmi-ethernet.kicad_sch")
		(attr smd)
		(fp_rect
			(start -0.925 0.47)
			(end 0.925 -0.47)
			(stroke
				(width 0.05)
				(type default)
			)
			(fill no)
			(layer "B.CrtYd")
		)
		(fp_line
			(start -0.494 -0.248)
			(end -0.494 0.25)
			(stroke
				(width 0.15)
				(type solid)
			)
			(layer "B.Fab")
		)
		(fp_line
			(start -0.494 0.25)
			(end 0.504 0.25)
			(stroke
				(width 0.15)
				(type solid)
			)
			(layer "B.Fab")
		)
		(fp_line
			(start 0.504 -0.248)
			(end -0.494 -0.248)
			(stroke
				(width 0.15)
				(type solid)
			)
			(layer "B.Fab")
		)
		(fp_line
			(start 0.504 0.25)
			(end 0.504 -0.248)
			(stroke
				(width 0.15)
				(type solid)
			)
			(layer "B.Fab")
		)
		(pad "1" smd roundrect
			(at -0.48 0)
			(size 0.59 0.64)
			(layers "B.Cu" "B.Mask" "B.Paste")
			(roundrect_rratio 0.25)
			(net 1 "GND")
			(pintype "passive")
		)
		(pad "2" smd roundrect
			(at 0.48 0)
			(size 0.59 0.64)
			(layers "B.Cu" "B.Mask" "B.Paste")
			(roundrect_rratio 0.25)
			(net 723 "/HDMI + Ethernet/ETH_CONN_SH")
			(pintype "passive")
		)
	)
	(footprint "antmicro-footprints:C_0201"
		(layer "B.Cu")
		(at 188.000001 128.500001 180)
		(descr "Capacitor SMD 0201")
		(tags "capacitor SMD 0201")
		(property "Reference" "C147"
			(at 0.625001 -0.324999 0)
			(layer "B.SilkS")
			(effects
				(font
					(size 0.7 0.7)
					(thickness 0.15)
				)
				(justify left bottom mirror)
			)
		)
		(property "Value" "C_100n_0201"
			(at 0 -1.4 0)
			(layer "B.Fab")
			(effects
				(font
					(size 0.7 0.7)
					(thickness 0.15)
				)
				(justify left bottom mirror)
			)
		)
		(property "Description" "SMD Multilayer Ceramic Capacitor, 0.1 µF, 6.3 V, 0201 [0603 Metric], ± 10%, X6S, CC Series"
			(at 0 0 180)
			(layer "F.Fab")
			(hide yes)
			(effects
				(font
					(size 1.27 1.27)
					(thickness 0.15)
				)
			)
		)
		(property "Author" "Antmicro"
			(at 376.000002 257.000002 0)
			(layer "B.Fab")
			(hide yes)
			(effects
				(font
					(size 1 1)
					(thickness 0.15)
				)
				(justify mirror)
			)
		)
		(property "Dielectric" ""
			(at 376.000002 257.000002 0)
			(layer "B.Fab")
			(hide yes)
			(effects
				(font
					(size 1 1)
					(thickness 0.15)
				)
				(justify mirror)
			)
		)
		(property "License" "Apache-2.0"
			(at 376.000002 257.000002 0)
			(layer "B.Fab")
			(hide yes)
			(effects
				(font
					(size 1 1)
					(thickness 0.15)
				)
				(justify mirror)
			)
		)
		(property "MPN" "CC0201KRX6S5BB104"
			(at 376.000002 257.000002 0)
			(layer "B.Fab")
			(hide yes)
			(effects
				(font
					(size 1 1)
					(thickness 0.15)
				)
				(justify mirror)
			)
		)
		(property "Manufacturer" "YAGEO"
			(at 376.000002 257.000002 0)
			(layer "B.Fab")
			(hide yes)
			(effects
				(font
					(size 1 1)
					(thickness 0.15)
				)
				(justify mirror)
			)
		)
		(property "Val" "100n"
			(at 376.000002 257.000002 0)
			(layer "B.Fab")
			(hide yes)
			(effects
				(font
					(size 1 1)
					(thickness 0.15)
				)
				(justify mirror)
			)
		)
		(property "Voltage" ""
			(at 376.000002 257.000002 0)
			(layer "B.Fab")
			(hide yes)
			(effects
				(font
					(size 1 1)
					(thickness 0.15)
				)
				(justify mirror)
			)
		)
		(sheetname "FPGA supply")
		(sheetfile "fpga-supply.kicad_sch")
		(attr smd)
		(fp_rect
			(start -0.7 0.35)
			(end 0.7 -0.35)
			(stroke
				(width 0.05)
				(type default)
			)
			(fill no)
			(layer "B.CrtYd")
		)
		(fp_rect
			(start 0.3 -0.15)
			(end -0.301 0.149)
			(stroke
				(width 0.15)
				(type solid)
			)
			(fill no)
			(layer "B.Fab")
		)
		(pad "" smd roundrect
			(at -0.349 0.002 180)
			(size 0.318 0.36)
			(layers "B.Paste")
			(roundrect_rratio 0.25)
		)
		(pad "" smd roundrect
			(at 0.341 0.002 180)
			(size 0.318 0.36)
			(layers "B.Paste")
			(roundrect_rratio 0.25)
		)
		(pad "1" smd roundrect
			(at -0.321 0.002 180)
			(size 0.46 0.4)
			(layers "B.Cu" "B.Mask")
			(roundrect_rratio 0.25)
			(net 1 "GND")
			(pintype "passive")
		)
		(pad "2" smd roundrect
			(at 0.32 0.002 180)
			(size 0.46 0.4)
			(layers "B.Cu" "B.Mask")
			(roundrect_rratio 0.25)
			(net 8 "+1V2_MGTAVTT")
			(pintype "passive")
		)
	)
	(footprint "antmicro-footprints:C_0603_1608Metric"
		(layer "B.Cu")
		(at 230.45 165.2 90)
		(descr "Capacitor SMD 0603")
		(tags "capacitor 0603")
		(property "Reference" "C191"
			(at 3.975 0.4 270)
			(layer "B.SilkS")
			(effects
				(font
					(size 0.7 0.7)
					(thickness 0.15)
				)
				(justify left bottom mirror)
			)
		)
		(property "Value" "C_1u_25V_0603"
			(at 0 -1.6 270)
			(layer "B.Fab")
			(effects
				(font
					(size 0.7 0.7)
					(thickness 0.15)
				)
				(justify left bottom mirror)
			)
		)
		(property "Description" "SMD Multilayer Ceramic Capacitor, 1 µF, 25 V, 0603 [1608 Metric], ± 10%, X5R, CL"
			(at 0 0 90)
			(layer "F.Fab")
			(hide yes)
			(effects
				(font
					(size 1.27 1.27)
					(thickness 0.15)
				)
			)
		)
		(property "Author" "Antmicro"
			(at 395.65 -65.25 0)
			(layer "B.Fab")
			(hide yes)
			(effects
				(font
					(size 1 1)
					(thickness 0.15)
				)
				(justify mirror)
			)
		)
		(property "Dielectric" ""
			(at 395.65 -65.25 0)
			(layer "B.Fab")
			(hide yes)
			(effects
				(font
					(size 1 1)
					(thickness 0.15)
				)
				(justify mirror)
			)
		)
		(property "License" "Apache-2.0"
			(at 395.65 -65.25 0)
			(layer "B.Fab")
			(hide yes)
			(effects
				(font
					(size 1 1)
					(thickness 0.15)
				)
				(justify mirror)
			)
		)
		(property "MPN" "CL10A105KA8NNNC"
			(at 395.65 -65.25 0)
			(layer "B.Fab")
			(hide yes)
			(effects
				(font
					(size 1 1)
					(thickness 0.15)
				)
				(justify mirror)
			)
		)
		(property "Manufacturer" "Samsung Electro-Mechanics"
			(at 395.65 -65.25 0)
			(layer "B.Fab")
			(hide yes)
			(effects
				(font
					(size 1 1)
					(thickness 0.15)
				)
				(justify mirror)
			)
		)
		(property "Val" "1u"
			(at 395.65 -65.25 0)
			(layer "B.Fab")
			(hide yes)
			(effects
				(font
					(size 1 1)
					(thickness 0.15)
				)
				(justify mirror)
			)
		)
		(property "Voltage" "25V"
			(at 395.65 -65.25 0)
			(layer "B.Fab")
			(hide yes)
			(effects
				(font
					(size 1 1)
					(thickness 0.15)
				)
				(justify mirror)
			)
		)
		(sheetname "Power supply")
		(sheetfile "power-supply.kicad_sch")
		(attr smd)
		(fp_line
			(start -0.15 -0.4)
			(end 0.15 -0.4)
			(stroke
				(width 0.15)
				(type solid)
			)
			(layer "B.SilkS")
		)
		(fp_line
			(start -0.15 0.4)
			(end 0.15 0.4)
			(stroke
				(width 0.15)
				(type solid)
			)
			(layer "B.SilkS")
		)
		(fp_rect
			(start -1.25 0.65)
			(end 1.25 -0.65)
			(stroke
				(width 0.05)
				(type solid)
			)
			(fill no)
			(layer "B.CrtYd")
		)
		(fp_rect
			(start -0.8 0.4)
			(end 0.8 -0.4)
			(stroke
				(width 0.15)
				(type solid)
			)
			(fill no)
			(layer "B.Fab")
		)
		(pad "1" smd roundrect
			(at -0.7 0 90)
			(size 0.8 1)
			(layers "B.Cu" "B.Mask" "B.Paste")
			(roundrect_rratio 0.2)
			(net 5 "/Power supply/PD_VBUS")
			(pintype "passive")
		)
		(pad "2" smd roundrect
			(at 0.7 0 90)
			(size 0.8 1)
			(layers "B.Cu" "B.Mask" "B.Paste")
			(roundrect_rratio 0.2)
			(net 1 "GND")
			(pintype "passive")
		)
	)
	(footprint "antmicro-footprints:R_0402_1005Metric"
		(layer "B.Cu")
		(at 170 144.625 180)
		(descr "Resistor SMD 0402")
		(tags "resistor SMD 0402")
		(property "Reference" "R43"
			(at -3.025 -1.425 0)
			(layer "B.SilkS")
			(effects
				(font
					(size 0.7 0.7)
					(thickness 0.15)
				)
				(justify left bottom mirror)
			)
		)
		(property "Value" "R_40R2_0402"
			(at 0 -1.4 0)
			(layer "B.Fab")
			(effects
				(font
					(size 0.7 0.7)
					(thickness 0.15)
				)
				(justify left bottom mirror)
			)
		)
		(property "Description" "SMD Chip Resistor, Ceramic, 40.2 ohm, ± 1%, 62.5 mW, 0402 [1005 Metric], Thick Film"
			(at 0 0 180)
			(layer "F.Fab")
			(hide yes)
			(effects
				(font
					(size 1.27 1.27)
					(thickness 0.15)
				)
			)
		)
		(property "Author" "Antmicro"
			(at 340 289.25 0)
			(layer "B.Fab")
			(hide yes)
			(effects
				(font
					(size 1 1)
					(thickness 0.15)
				)
				(justify mirror)
			)
		)
		(property "License" "Apache-2.0"
			(at 340 289.25 0)
			(layer "B.Fab")
			(hide yes)
			(effects
				(font
					(size 1 1)
					(thickness 0.15)
				)
				(justify mirror)
			)
		)
		(property "MPN" "CR0402-FX-40R2GLF"
			(at 340 289.25 0)
			(layer "B.Fab")
			(hide yes)
			(effects
				(font
					(size 1 1)
					(thickness 0.15)
				)
				(justify mirror)
			)
		)
		(property "Manufacturer" "Bourns"
			(at 340 289.25 0)
			(layer "B.Fab")
			(hide yes)
			(effects
				(font
					(size 1 1)
					(thickness 0.15)
				)
				(justify mirror)
			)
		)
		(property "Tolerance" "1%"
			(at 340 289.25 0)
			(layer "B.Fab")
			(hide yes)
			(effects
				(font
					(size 1 1)
					(thickness 0.15)
				)
				(justify mirror)
			)
		)
		(property "Val" "40R2"
			(at 340 289.25 0)
			(layer "B.Fab")
			(hide yes)
			(effects
				(font
					(size 1 1)
					(thickness 0.15)
				)
				(justify mirror)
			)
		)
		(sheetname "DRAM + SRAM")
		(sheetfile "ram.kicad_sch")
		(attr smd)
		(fp_rect
			(start -0.925 0.47)
			(end 0.925 -0.47)
			(stroke
				(width 0.05)
				(type default)
			)
			(fill no)
			(layer "B.CrtYd")
		)
		(fp_rect
			(start -0.5 0.25)
			(end 0.5 -0.25)
			(stroke
				(width 0.15)
				(type solid)
			)
			(fill no)
			(layer "B.Fab")
		)
		(pad "1" smd roundrect
			(at -0.48 0 180)
			(size 0.59 0.64)
			(layers "B.Cu" "B.Mask" "B.Paste")
			(roundrect_rratio 0.25)
			(net 560 "/DRAM + SRAM/DDR.~{RAS}")
			(pintype "passive")
		)
		(pad "2" smd roundrect
			(at 0.48 0 180)
			(size 0.59 0.64)
			(layers "B.Cu" "B.Mask" "B.Paste")
			(roundrect_rratio 0.25)
			(net 7 "+0V675_VTT")
			(pintype "passive")
		)
	)
	(footprint "antmicro-footprints:C_0402_1005Metric"
		(layer "B.Cu")
		(at 196.4 134.175 180)
		(descr "Capacitor SMD 0402")
		(tags "capacitor SMD 0402")
		(property "Reference" "C59"
			(at -25.1 28.075 0)
			(layer "B.SilkS")
			(effects
				(font
					(size 0.7 0.7)
					(thickness 0.15)
				)
				(justify left bottom mirror)
			)
		)
		(property "Value" "C_100n_0402"
			(at 0 -1.169 0)
			(layer "B.Fab")
			(effects
				(font
					(size 0.7 0.7)
					(thickness 0.15)
				)
				(justify left bottom mirror)
			)
		)
		(property "Description" "SMD Multilayer Ceramic Capacitor, 0.1 µF, 50 V, 0402 [1005 Metric], ± 10%, X5R, GRM Series"
			(at 0 0 180)
			(layer "F.Fab")
			(hide yes)
			(effects
				(font
					(size 1.27 1.27)
					(thickness 0.15)
				)
			)
		)
		(property "Author" "Antmicro"
			(at 392.8 268.35 0)
			(layer "B.Fab")
			(hide yes)
			(effects
				(font
					(size 1 1)
					(thickness 0.15)
				)
				(justify mirror)
			)
		)
		(property "Dielectric" "X5R"
			(at 392.8 268.35 0)
			(layer "B.Fab")
			(hide yes)
			(effects
				(font
					(size 1 1)
					(thickness 0.15)
				)
				(justify mirror)
			)
		)
		(property "License" "Apache-2.0"
			(at 392.8 268.35 0)
			(layer "B.Fab")
			(hide yes)
			(effects
				(font
					(size 1 1)
					(thickness 0.15)
				)
				(justify mirror)
			)
		)
		(property "MPN" "GRM155R61H104KE14D"
			(at 392.8 268.35 0)
			(layer "B.Fab")
			(hide yes)
			(effects
				(font
					(size 1 1)
					(thickness 0.15)
				)
				(justify mirror)
			)
		)
		(property "Manufacturer" "Murata"
			(at 392.8 268.35 0)
			(layer "B.Fab")
			(hide yes)
			(effects
				(font
					(size 1 1)
					(thickness 0.15)
				)
				(justify mirror)
			)
		)
		(property "Val" "100n"
			(at 392.8 268.35 0)
			(layer "B.Fab")
			(hide yes)
			(effects
				(font
					(size 1 1)
					(thickness 0.15)
				)
				(justify mirror)
			)
		)
		(property "Voltage" "50V"
			(at 392.8 268.35 0)
			(layer "B.Fab")
			(hide yes)
			(effects
				(font
					(size 1 1)
					(thickness 0.15)
				)
				(justify mirror)
			)
		)
		(sheetname "FPGA supply")
		(sheetfile "fpga-supply.kicad_sch")
		(attr smd)
		(fp_rect
			(start -0.925 0.47)
			(end 0.925 -0.47)
			(stroke
				(width 0.05)
				(type default)
			)
			(fill no)
			(layer "B.CrtYd")
		)
		(fp_line
			(start 0.504 0.25)
			(end 0.504 -0.248)
			(stroke
				(width 0.15)
				(type solid)
			)
			(layer "B.Fab")
		)
		(fp_line
			(start 0.504 -0.248)
			(end -0.494 -0.248)
			(stroke
				(width 0.15)
				(type solid)
			)
			(layer "B.Fab")
		)
		(fp_line
			(start -0.494 0.25)
			(end 0.504 0.25)
			(stroke
				(width 0.15)
				(type solid)
			)
			(layer "B.Fab")
		)
		(fp_line
			(start -0.494 -0.248)
			(end -0.494 0.25)
			(stroke
				(width 0.15)
				(type solid)
			)
			(layer "B.Fab")
		)
		(pad "1" smd roundrect
			(at -0.48 0 180)
			(size 0.59 0.64)
			(layers "B.Cu" "B.Mask" "B.Paste")
			(roundrect_rratio 0.25)
			(net 1 "GND")
			(pintype "passive")
		)
		(pad "2" smd roundrect
			(at 0.48 0 180)
			(size 0.59 0.64)
			(layers "B.Cu" "B.Mask" "B.Paste")
			(roundrect_rratio 0.25)
			(net 26 "+1V8")
			(pintype "passive")
		)
	)
	(footprint "antmicro-footprints:R_0402_1005Metric"
		(layer "B.Cu")
		(at 258.4 81.4 -90)
		(descr "Resistor SMD 0402")
		(tags "resistor SMD 0402")
		(property "Reference" "R360"
			(at -1.25 0.525 90)
			(layer "B.SilkS")
			(effects
				(font
					(size 0.7 0.7)
					(thickness 0.15)
				)
				(justify left bottom mirror)
			)
		)
		(property "Value" "R_100k_0402"
			(at 0 -1.4 90)
			(layer "B.Fab")
			(effects
				(font
					(size 0.7 0.7)
					(thickness 0.15)
				)
				(justify left bottom mirror)
			)
		)
		(property "Description" "SMD Chip Resistor, 100 kohm, ± 1%, 62.5 mW, 0402 [1005 Metric], Thick Film, General Purpose"
			(at 0 0 270)
			(layer "F.Fab")
			(hide yes)
			(effects
				(font
					(size 1.27 1.27)
					(thickness 0.15)
				)
			)
		)
		(property "Author" "Antmicro"
			(at 177 339.8 0)
			(layer "B.Fab")
			(hide yes)
			(effects
				(font
					(size 1 1)
					(thickness 0.15)
				)
				(justify mirror)
			)
		)
		(property "License" "Apache-2.0"
			(at 177 339.8 0)
			(layer "B.Fab")
			(hide yes)
			(effects
				(font
					(size 1 1)
					(thickness 0.15)
				)
				(justify mirror)
			)
		)
		(property "MPN" "CR0402-FX-1003GLF"
			(at 177 339.8 0)
			(layer "B.Fab")
			(hide yes)
			(effects
				(font
					(size 1 1)
					(thickness 0.15)
				)
				(justify mirror)
			)
		)
		(property "Manufacturer" "Bourns"
			(at 177 339.8 0)
			(layer "B.Fab")
			(hide yes)
			(effects
				(font
					(size 1 1)
					(thickness 0.15)
				)
				(justify mirror)
			)
		)
		(property "Tolerance" "1%"
			(at 177 339.8 0)
			(layer "B.Fab")
			(hide yes)
			(effects
				(font
					(size 1 1)
					(thickness 0.15)
				)
				(justify mirror)
			)
		)
		(property "Val" "100k"
			(at 177 339.8 0)
			(layer "B.Fab")
			(hide yes)
			(effects
				(font
					(size 1 1)
					(thickness 0.15)
				)
				(justify mirror)
			)
		)
		(sheetname "User GPIO + LED + button + DIP switch")
		(sheetfile "user-gpio.kicad_sch")
		(attr smd)
		(fp_rect
			(start -0.925 0.47)
			(end 0.925 -0.47)
			(stroke
				(width 0.05)
				(type default)
			)
			(fill no)
			(layer "B.CrtYd")
		)
		(fp_rect
			(start -0.5 0.25)
			(end 0.5 -0.25)
			(stroke
				(width 0.15)
				(type solid)
			)
			(fill no)
			(layer "B.Fab")
		)
		(pad "1" smd roundrect
			(at -0.48 0 270)
			(size 0.59 0.64)
			(layers "B.Cu" "B.Mask" "B.Paste")
			(roundrect_rratio 0.25)
			(net 1307 "/USER_IO.LED_BLUE")
			(pintype "passive")
		)
		(pad "2" smd roundrect
			(at 0.48 0 270)
			(size 0.59 0.64)
			(layers "B.Cu" "B.Mask" "B.Paste")
			(roundrect_rratio 0.25)
			(net 1 "GND")
			(pintype "passive")
		)
	)
	(footprint "antmicro-footprints:SOT-23-5"
		(layer "B.Cu")
		(at 186.55 184.8 -90)
		(property "Reference" "U44"
			(at -1.075 -2.7 90)
			(layer "B.SilkS")
			(effects
				(font
					(size 0.7 0.7)
					(thickness 0.15)
				)
				(justify left bottom mirror)
			)
		)
		(property "Value" "NCP718BSN330T1G"
			(at 0.002 -2.799 90)
			(layer "B.Fab")
			(effects
				(font
					(size 0.7 0.7)
					(thickness 0.15)
				)
				(justify left bottom mirror)
			)
		)
		(property "Description" "Linear Voltage Regulator IC Positive Fixed 1 Output 300mA TSOT-23-5"
			(at 0 0 270)
			(layer "F.Fab")
			(hide yes)
			(effects
				(font
					(size 1.27 1.27)
					(thickness 0.15)
				)
			)
		)
		(property "Author" "Antmicro"
			(at 1.75 371.35 0)
			(layer "B.Fab")
			(hide yes)
			(effects
				(font
					(size 1 1)
					(thickness 0.15)
				)
				(justify mirror)
			)
		)
		(property "License" "Apache-2.0"
			(at 1.75 371.35 0)
			(layer "B.Fab")
			(hide yes)
			(effects
				(font
					(size 1 1)
					(thickness 0.15)
				)
				(justify mirror)
			)
		)
		(property "MPN" "NCP718BSN330T1G"
			(at 1.75 371.35 0)
			(layer "B.Fab")
			(hide yes)
			(effects
				(font
					(size 1 1)
					(thickness 0.15)
				)
				(justify mirror)
			)
		)
		(property "Manufacturer" "ON Semiconductor"
			(at 1.75 371.35 0)
			(layer "B.Fab")
			(hide yes)
			(effects
				(font
					(size 1 1)
					(thickness 0.15)
				)
				(justify mirror)
			)
		)
		(sheetname "DC-DC Converters")
		(sheetfile "dc-dc.kicad_sch")
		(attr smd)
		(fp_line
			(start -0.8 1.6)
			(end -0.5 1.6)
			(stroke
				(width 0.15)
				(type solid)
			)
			(layer "B.SilkS")
		)
		(fp_line
			(start -0.8 1.6)
			(end -0.8 1.3)
			(stroke
				(width 0.15)
				(type solid)
			)
			(layer "B.SilkS")
		)
		(fp_line
			(start 0.8 1.6)
			(end 0.5 1.6)
			(stroke
				(width 0.15)
				(type solid)
			)
			(layer "B.SilkS")
		)
		(fp_line
			(start 0.8 1.3)
			(end 0.8 1.6)
			(stroke
				(width 0.15)
				(type solid)
			)
			(layer "B.SilkS")
		)
		(fp_line
			(start 0.8 -0.55)
			(end 0.8 0.55)
			(stroke
				(width 0.15)
				(type solid)
			)
			(layer "B.SilkS")
		)
		(fp_line
			(start 0.8 -1.3)
			(end 0.8 -1.599)
			(stroke
				(width 0.15)
				(type solid)
			)
			(layer "B.SilkS")
		)
		(fp_line
			(start 0.8 -1.599)
			(end 0.549 -1.599)
			(stroke
				(width 0.15)
				(type solid)
			)
			(layer "B.SilkS")
		)
		(fp_line
			(start -0.85 -1.6)
			(end -0.85 -1.301)
			(stroke
				(width 0.15)
				(type solid)
			)
			(layer "B.SilkS")
		)
		(fp_line
			(start -0.55 -1.6)
			(end -0.85 -1.6)
			(stroke
				(width 0.15)
				(type solid)
			)
			(layer "B.SilkS")
		)
		(fp_circle
			(center -1.25 1.5)
			(end -1.2 1.5)
			(stroke
				(width 0.15)
				(type solid)
			)
			(fill yes)
			(layer "B.SilkS")
		)
		(fp_rect
			(start 1.9 1.76)
			(end -1.9 -1.75)
			(stroke
				(width 0.05)
				(type solid)
			)
			(fill no)
			(layer "B.CrtYd")
		)
		(fp_line
			(start -0.398 1.526)
			(end -0.874 1.05)
			(stroke
				(width 0.15)
				(type solid)
			)
			(layer "B.Fab")
		)
		(fp_rect
			(start 0.874 -1.523)
			(end -0.873 1.525)
			(stroke
				(width 0.15)
				(type solid)
			)
			(fill no)
			(layer "B.Fab")
		)
		(pad "1" smd rect
			(at -1.351 0.951)
			(size 0.55 1)
			(layers "B.Cu" "B.Mask" "B.Paste")
			(net 702 "VDC")
			(pinfunction "VIN")
			(pintype "passive")
		)
		(pad "2" smd rect
			(at -1.351 0)
			(size 0.55 1)
			(layers "B.Cu" "B.Mask" "B.Paste")
			(net 1 "GND")
			(pinfunction "GND")
			(pintype "passive")
		)
		(pad "3" smd rect
			(at -1.351 -0.949)
			(size 0.55 1)
			(layers "B.Cu" "B.Mask" "B.Paste")
			(net 702 "VDC")
			(pinfunction "EN")
			(pintype "passive")
		)
		(pad "4" smd rect
			(at 1.35 -0.949)
			(size 0.55 1)
			(layers "B.Cu" "B.Mask" "B.Paste")
			(net 1411 "unconnected-(U44-NC-Pad4)")
			(pinfunction "NC")
			(pintype "no_connect")
		)
		(pad "5" smd rect
			(at 1.35 0.951)
			(size 0.55 1)
			(layers "B.Cu" "B.Mask" "B.Paste")
			(net 37 "+3V3_AON")
			(pinfunction "VOUT")
			(pintype "passive")
		)
	)
	(footprint "antmicro-footprints:C_0603_1608Metric"
		(layer "B.Cu")
		(at 161.8 147 -90)
		(descr "Capacitor SMD 0603")
		(tags "capacitor 0603")
		(property "Reference" "C166"
			(at 0.175 -1.575 90)
			(layer "B.SilkS")
			(effects
				(font
					(size 0.7 0.7)
					(thickness 0.15)
				)
				(justify left bottom mirror)
			)
		)
		(property "Value" "C_47u_0603"
			(at 0 -1.6 90)
			(layer "B.Fab")
			(effects
				(font
					(size 0.7 0.7)
					(thickness 0.15)
				)
				(justify left bottom mirror)
			)
		)
		(property "Description" "SMD Multilayer Ceramic Capacitor, 47 µF, 6.3 V, 0603 [1608 Metric], ± 20%, X5R, GRM Series"
			(at 0 0 270)
			(layer "F.Fab")
			(hide yes)
			(effects
				(font
					(size 1.27 1.27)
					(thickness 0.15)
				)
			)
		)
		(property "Author" "Antmicro"
			(at 14.8 308.8 0)
			(layer "B.Fab")
			(hide yes)
			(effects
				(font
					(size 1 1)
					(thickness 0.15)
				)
				(justify mirror)
			)
		)
		(property "Dielectric" ""
			(at 14.8 308.8 0)
			(layer "B.Fab")
			(hide yes)
			(effects
				(font
					(size 1 1)
					(thickness 0.15)
				)
				(justify mirror)
			)
		)
		(property "License" "Apache-2.0"
			(at 14.8 308.8 0)
			(layer "B.Fab")
			(hide yes)
			(effects
				(font
					(size 1 1)
					(thickness 0.15)
				)
				(justify mirror)
			)
		)
		(property "MPN" "GRM188R60J476ME15D"
			(at 14.8 308.8 0)
			(layer "B.Fab")
			(hide yes)
			(effects
				(font
					(size 1 1)
					(thickness 0.15)
				)
				(justify mirror)
			)
		)
		(property "Manufacturer" "Murata"
			(at 14.8 308.8 0)
			(layer "B.Fab")
			(hide yes)
			(effects
				(font
					(size 1 1)
					(thickness 0.15)
				)
				(justify mirror)
			)
		)
		(property "Val" "47u"
			(at 14.8 308.8 0)
			(layer "B.Fab")
			(hide yes)
			(effects
				(font
					(size 1 1)
					(thickness 0.15)
				)
				(justify mirror)
			)
		)
		(property "Voltage" ""
			(at 14.8 308.8 0)
			(layer "B.Fab")
			(hide yes)
			(effects
				(font
					(size 1 1)
					(thickness 0.15)
				)
				(justify mirror)
			)
		)
		(sheetname "DRAM + SRAM")
		(sheetfile "ram.kicad_sch")
		(attr smd)
		(fp_line
			(start -0.15 0.4)
			(end 0.15 0.4)
			(stroke
				(width 0.15)
				(type solid)
			)
			(layer "B.SilkS")
		)
		(fp_line
			(start -0.15 -0.4)
			(end 0.15 -0.4)
			(stroke
				(width 0.15)
				(type solid)
			)
			(layer "B.SilkS")
		)
		(fp_rect
			(start -1.25 0.65)
			(end 1.25 -0.65)
			(stroke
				(width 0.05)
				(type solid)
			)
			(fill no)
			(layer "B.CrtYd")
		)
		(fp_rect
			(start -0.8 0.4)
			(end 0.8 -0.4)
			(stroke
				(width 0.15)
				(type solid)
			)
			(fill no)
			(layer "B.Fab")
		)
		(pad "1" smd roundrect
			(at -0.7 0 270)
			(size 0.8 1)
			(layers "B.Cu" "B.Mask" "B.Paste")
			(roundrect_rratio 0.2)
			(net 7 "+0V675_VTT")
			(pintype "passive")
		)
		(pad "2" smd roundrect
			(at 0.7 0 270)
			(size 0.8 1)
			(layers "B.Cu" "B.Mask" "B.Paste")
			(roundrect_rratio 0.2)
			(net 25 "+1V35")
			(pintype "passive")
		)
	)
	(footprint "antmicro-footprints:SOT-23-3"
		(layer "B.Cu")
		(at 162.4 186)
		(property "Reference" "D33"
			(at 0.925 -1.775 180)
			(layer "B.SilkS")
			(effects
				(font
					(size 0.7 0.7)
					(thickness 0.15)
				)
				(justify left bottom mirror)
			)
		)
		(property "Value" "BZX84C5V1-TP"
			(at -1.9 -2.7 180)
			(layer "B.Fab")
			(effects
				(font
					(size 0.7 0.7)
					(thickness 0.15)
				)
				(justify left bottom mirror)
			)
		)
		(property "Description" "Zener Single Diode, 5.1 V, 350 mW, SOT-23, 3 Pins, 150 °C, Surface Mount"
			(at 0 0 0)
			(layer "F.Fab")
			(hide yes)
			(effects
				(font
					(size 1.27 1.27)
					(thickness 0.15)
				)
			)
		)
		(property "Author" "Antmicro"
			(at 0 0 0)
			(layer "B.Fab")
			(hide yes)
			(effects
				(font
					(size 1 1)
					(thickness 0.15)
				)
				(justify mirror)
			)
		)
		(property "License" "Apache-2.0"
			(at 0 0 0)
			(layer "B.Fab")
			(hide yes)
			(effects
				(font
					(size 1 1)
					(thickness 0.15)
				)
				(justify mirror)
			)
		)
		(property "MPN" "BZX84C5V1-TP"
			(at 0 0 0)
			(layer "B.Fab")
			(hide yes)
			(effects
				(font
					(size 1 1)
					(thickness 0.15)
				)
				(justify mirror)
			)
		)
		(property "Manufacturer" "Micro Commercial Components"
			(at 0 0 0)
			(layer "B.Fab")
			(hide yes)
			(effects
				(font
					(size 1 1)
					(thickness 0.15)
				)
				(justify mirror)
			)
		)
		(sheetname "DC-DC Converters")
		(sheetfile "dc-dc.kicad_sch")
		(attr smd)
		(fp_line
			(start -1.45 1.35)
			(end -0.85 1.35)
			(stroke
				(width 0.15)
				(type solid)
			)
			(layer "B.SilkS")
		)
		(fp_line
			(start -0.85 1.35)
			(end -0.7 1.5)
			(stroke
				(width 0.15)
				(type solid)
			)
			(layer "B.SilkS")
		)
		(fp_line
			(start -0.7 -1.5)
			(end -0.7 -1.35)
			(stroke
				(width 0.15)
				(type solid)
			)
			(layer "B.SilkS")
		)
		(fp_line
			(start 0.7 -1.5)
			(end -0.7 -1.5)
			(stroke
				(width 0.15)
				(type solid)
			)
			(layer "B.SilkS")
		)
		(fp_line
			(start 0.7 -0.4)
			(end 0.7 -1.5)
			(stroke
				(width 0.15)
				(type solid)
			)
			(layer "B.SilkS")
		)
		(fp_line
			(start 0.7 0.4)
			(end 0.7 1.5)
			(stroke
				(width 0.15)
				(type solid)
			)
			(layer "B.SilkS")
		)
		(fp_line
			(start 0.7 1.5)
			(end -0.7 1.5)
			(stroke
				(width 0.15)
				(type solid)
			)
			(layer "B.SilkS")
		)
		(fp_line
			(start -1.75 -1.4)
			(end -1.75 -0.5)
			(stroke
				(width 0.05)
				(type solid)
			)
			(layer "B.CrtYd")
		)
		(fp_line
			(start -1.75 -0.5)
			(end -0.85 -0.5)
			(stroke
				(width 0.05)
				(type solid)
			)
			(layer "B.CrtYd")
		)
		(fp_line
			(start -1.75 0.5)
			(end -1.75 1.4)
			(stroke
				(width 0.05)
				(type solid)
			)
			(layer "B.CrtYd")
		)
		(fp_line
			(start -0.9 1.4)
			(end -1.75 1.4)
			(stroke
				(width 0.05)
				(type solid)
			)
			(layer "B.CrtYd")
		)
		(fp_line
			(start -0.9 1.6)
			(end -0.9 1.4)
			(stroke
				(width 0.05)
				(type solid)
			)
			(layer "B.CrtYd")
		)
		(fp_line
			(start -0.9 1.6)
			(end 0.825 1.6)
			(stroke
				(width 0.05)
				(type solid)
			)
			(layer "B.CrtYd")
		)
		(fp_line
			(start -0.85 -1.65)
			(end -0.85 -1.4)
			(stroke
				(width 0.05)
				(type solid)
			)
			(layer "B.CrtYd")
		)
		(fp_line
			(start -0.85 -1.4)
			(end -1.75 -1.4)
			(stroke
				(width 0.05)
				(type solid)
			)
			(layer "B.CrtYd")
		)
		(fp_line
			(start -0.85 -0.5)
			(end -0.85 0.5)
			(stroke
				(width 0.05)
				(type solid)
			)
			(layer "B.CrtYd")
		)
		(fp_line
			(start -0.85 0.5)
			(end -1.75 0.5)
			(stroke
				(width 0.05)
				(type solid)
			)
			(layer "B.CrtYd")
		)
		(fp_line
			(start 0.825 0.45)
			(end 1.75 0.45)
			(stroke
				(width 0.05)
				(type solid)
			)
			(layer "B.CrtYd")
		)
		(fp_line
			(start 0.825 1.6)
			(end 0.825 0.45)
			(stroke
				(width 0.05)
				(type solid)
			)
			(layer "B.CrtYd")
		)
		(fp_line
			(start 0.85 -1.65)
			(end -0.85 -1.65)
			(stroke
				(width 0.05)
				(type solid)
			)
			(layer "B.CrtYd")
		)
		(fp_line
			(start 0.85 -0.45)
			(end 0.85 -1.65)
			(stroke
				(width 0.05)
				(type solid)
			)
			(layer "B.CrtYd")
		)
		(fp_line
			(start 1.75 -0.45)
			(end 0.85 -0.45)
			(stroke
				(width 0.05)
				(type solid)
			)
			(layer "B.CrtYd")
		)
		(fp_line
			(start 1.75 0.45)
			(end 1.75 -0.45)
			(stroke
				(width 0.05)
				(type solid)
			)
			(layer "B.CrtYd")
		)
		(fp_line
			(start -0.712 -1.519)
			(end 0.688 -1.519)
			(stroke
				(width 0.15)
				(type solid)
			)
			(layer "B.Fab")
		)
		(fp_line
			(start -0.712 1.325)
			(end -0.712 -1.523)
			(stroke
				(width 0.15)
				(type solid)
			)
			(layer "B.Fab")
		)
		(fp_line
			(start -0.437 1.526)
			(end -0.712 1.325)
			(stroke
				(width 0.15)
				(type solid)
			)
			(layer "B.Fab")
		)
		(fp_line
			(start -0.437 1.526)
			(end 0.688 1.526)
			(stroke
				(width 0.15)
				(type solid)
			)
			(layer "B.Fab")
		)
		(fp_line
			(start 0.688 -1.519)
			(end 0.688 1.52)
			(stroke
				(width 0.15)
				(type solid)
			)
			(layer "B.Fab")
		)
		(pad "1" smd roundrect
			(at -1.1 0.951)
			(size 1 0.6)
			(layers "B.Cu" "B.Mask" "B.Paste")
			(roundrect_rratio 0.15)
			(net 1 "GND")
			(pinfunction "A")
			(pintype "passive")
		)
		(pad "2" smd roundrect
			(at -1.1 -0.949)
			(size 1 0.6)
			(layers "B.Cu" "B.Mask" "B.Paste")
			(roundrect_rratio 0.15)
			(net 1195 "unconnected-(D33-Pad2)")
			(pinfunction "2")
			(pintype "no_connect")
		)
		(pad "3" smd roundrect
			(at 1.1 0.0005)
			(size 1 0.6)
			(layers "B.Cu" "B.Mask" "B.Paste")
			(roundrect_rratio 0.15)
			(net 797 "/DC-DC Converters/PB_CTRL_OE")
			(pinfunction "C")
			(pintype "passive")
		)
	)
	(footprint "antmicro-footprints:C_0201"
		(layer "B.Cu")
		(at 203.45 126.5 -90)
		(descr "Capacitor SMD 0201")
		(tags "capacitor SMD 0201")
		(property "Reference" "C9"
			(at -30.45 -28.2 90)
			(layer "B.SilkS")
			(effects
				(font
					(size 0.7 0.7)
					(thickness 0.15)
				)
				(justify left bottom mirror)
			)
		)
		(property "Value" "C_4u7_0201"
			(at 0 -1.4 90)
			(layer "B.Fab")
			(effects
				(font
					(size 0.7 0.7)
					(thickness 0.15)
				)
				(justify left bottom mirror)
			)
		)
		(property "Description" "SMD Multilayer Ceramic Capacitor, 4.7 µF, 6.3 V, 0201 [0603 Metric], ± 20%, X5R, GRM Series"
			(at 0 0 270)
			(layer "F.Fab")
			(hide yes)
			(effects
				(font
					(size 1.27 1.27)
					(thickness 0.15)
				)
			)
		)
		(property "Author" "Antmicro"
			(at 76.95 329.95 0)
			(layer "B.Fab")
			(hide yes)
			(effects
				(font
					(size 1 1)
					(thickness 0.15)
				)
				(justify mirror)
			)
		)
		(property "Dielectric" ""
			(at 76.95 329.95 0)
			(layer "B.Fab")
			(hide yes)
			(effects
				(font
					(size 1 1)
					(thickness 0.15)
				)
				(justify mirror)
			)
		)
		(property "License" "Apache-2.0"
			(at 76.95 329.95 0)
			(layer "B.Fab")
			(hide yes)
			(effects
				(font
					(size 1 1)
					(thickness 0.15)
				)
				(justify mirror)
			)
		)
		(property "MPN" "GRM035R60J475ME15D"
			(at 76.95 329.95 0)
			(layer "B.Fab")
			(hide yes)
			(effects
				(font
					(size 1 1)
					(thickness 0.15)
				)
				(justify mirror)
			)
		)
		(property "Manufacturer" "Murata"
			(at 76.95 329.95 0)
			(layer "B.Fab")
			(hide yes)
			(effects
				(font
					(size 1 1)
					(thickness 0.15)
				)
				(justify mirror)
			)
		)
		(property "Val" "4u7"
			(at 76.95 329.95 0)
			(layer "B.Fab")
			(hide yes)
			(effects
				(font
					(size 1 1)
					(thickness 0.15)
				)
				(justify mirror)
			)
		)
		(property "Voltage" ""
			(at 76.95 329.95 0)
			(layer "B.Fab")
			(hide yes)
			(effects
				(font
					(size 1 1)
					(thickness 0.15)
				)
				(justify mirror)
			)
		)
		(sheetname "FPGA supply")
		(sheetfile "fpga-supply.kicad_sch")
		(attr smd)
		(fp_rect
			(start -0.7 0.35)
			(end 0.7 -0.35)
			(stroke
				(width 0.05)
				(type default)
			)
			(fill no)
			(layer "B.CrtYd")
		)
		(fp_rect
			(start 0.3 -0.15)
			(end -0.301 0.149)
			(stroke
				(width 0.15)
				(type solid)
			)
			(fill no)
			(layer "B.Fab")
		)
		(pad "" smd roundrect
			(at -0.349 0.002 270)
			(size 0.318 0.36)
			(layers "B.Paste")
			(roundrect_rratio 0.25)
		)
		(pad "" smd roundrect
			(at 0.341 0.002 270)
			(size 0.318 0.36)
			(layers "B.Paste")
			(roundrect_rratio 0.25)
		)
		(pad "1" smd roundrect
			(at -0.321 0.002 270)
			(size 0.46 0.4)
			(layers "B.Cu" "B.Mask")
			(roundrect_rratio 0.25)
			(net 1 "GND")
			(pintype "passive")
		)
		(pad "2" smd roundrect
			(at 0.32 0.002 270)
			(size 0.46 0.4)
			(layers "B.Cu" "B.Mask")
			(roundrect_rratio 0.25)
			(net 650 "+1V0")
			(pintype "passive")
		)
	)
	(footprint "antmicro-footprints:R_0402_1005Metric"
		(layer "B.Cu")
		(at 253.801 166.8 -90)
		(descr "Resistor SMD 0402")
		(tags "resistor SMD 0402")
		(property "Reference" "R250"
			(at -0.925 1.551 90)
			(layer "B.SilkS")
			(effects
				(font
					(size 0.7 0.7)
					(thickness 0.15)
				)
				(justify left bottom mirror)
			)
		)
		(property "Value" "R_49R9_0402"
			(at 0 -1.4 90)
			(layer "B.Fab")
			(effects
				(font
					(size 0.7 0.7)
					(thickness 0.15)
				)
				(justify left bottom mirror)
			)
		)
		(property "Description" "SMD Chip Resistor, 49.9 ohm, ± 1%, 62.5 mW, 0402 [1005 Metric], Thick Film, General Purpose"
			(at 0 0 270)
			(layer "F.Fab")
			(hide yes)
			(effects
				(font
					(size 1.27 1.27)
					(thickness 0.15)
				)
			)
		)
		(property "Author" "Antmicro"
			(at 87.001 420.601 0)
			(layer "B.Fab")
			(hide yes)
			(effects
				(font
					(size 1 1)
					(thickness 0.15)
				)
				(justify mirror)
			)
		)
		(property "License" "Apache-2.0"
			(at 87.001 420.601 0)
			(layer "B.Fab")
			(hide yes)
			(effects
				(font
					(size 1 1)
					(thickness 0.15)
				)
				(justify mirror)
			)
		)
		(property "MPN" "CR0402-FX-49R9GLF"
			(at 87.001 420.601 0)
			(layer "B.Fab")
			(hide yes)
			(effects
				(font
					(size 1 1)
					(thickness 0.15)
				)
				(justify mirror)
			)
		)
		(property "Manufacturer" "Bourns"
			(at 87.001 420.601 0)
			(layer "B.Fab")
			(hide yes)
			(effects
				(font
					(size 1 1)
					(thickness 0.15)
				)
				(justify mirror)
			)
		)
		(property "Tolerance" "1%"
			(at 87.001 420.601 0)
			(layer "B.Fab")
			(hide yes)
			(effects
				(font
					(size 1 1)
					(thickness 0.15)
				)
				(justify mirror)
			)
		)
		(property "Val" "49R9"
			(at 87.001 420.601 0)
			(layer "B.Fab")
			(hide yes)
			(effects
				(font
					(size 1 1)
					(thickness 0.15)
				)
				(justify mirror)
			)
		)
		(sheetname "HDMI + Ethernet")
		(sheetfile "hdmi-ethernet.kicad_sch")
		(attr smd)
		(fp_rect
			(start -0.925 0.47)
			(end 0.925 -0.47)
			(stroke
				(width 0.05)
				(type default)
			)
			(fill no)
			(layer "B.CrtYd")
		)
		(fp_rect
			(start -0.5 0.25)
			(end 0.5 -0.25)
			(stroke
				(width 0.15)
				(type solid)
			)
			(fill no)
			(layer "B.Fab")
		)
		(pad "1" smd roundrect
			(at -0.48 0 270)
			(size 0.59 0.64)
			(layers "B.Cu" "B.Mask" "B.Paste")
			(roundrect_rratio 0.25)
			(net 729 "/HDMI + Ethernet/ETH2_N")
			(pintype "passive")
		)
		(pad "2" smd roundrect
			(at 0.48 0 270)
			(size 0.59 0.64)
			(layers "B.Cu" "B.Mask" "B.Paste")
			(roundrect_rratio 0.25)
			(net 721 "/HDMI + Ethernet/ETH_3V3")
			(pintype "passive")
		)
	)
	(footprint "antmicro-footprints:C_0603_1608Metric"
		(layer "B.Cu")
		(at 197.69 147.25)
		(descr "Capacitor SMD 0603")
		(tags "capacitor 0603")
		(property "Reference" "C107"
			(at 1.435 1.4 180)
			(layer "B.SilkS")
			(effects
				(font
					(size 0.7 0.7)
					(thickness 0.15)
				)
				(justify left bottom mirror)
			)
		)
		(property "Value" "C_47u_0603"
			(at 0 -1.6 180)
			(layer "B.Fab")
			(effects
				(font
					(size 0.7 0.7)
					(thickness 0.15)
				)
				(justify left bottom mirror)
			)
		)
		(property "Description" "SMD Multilayer Ceramic Capacitor, 47 µF, 6.3 V, 0603 [1608 Metric], ± 20%, X5R, GRM Series"
			(at 0 0 0)
			(layer "F.Fab")
			(hide yes)
			(effects
				(font
					(size 1.27 1.27)
					(thickness 0.15)
				)
			)
		)
		(property "Author" "Antmicro"
			(at 0 0 0)
			(layer "B.Fab")
			(hide yes)
			(effects
				(font
					(size 1 1)
					(thickness 0.15)
				)
				(justify mirror)
			)
		)
		(property "Dielectric" ""
			(at 0 0 0)
			(layer "B.Fab")
			(hide yes)
			(effects
				(font
					(size 1 1)
					(thickness 0.15)
				)
				(justify mirror)
			)
		)
		(property "License" "Apache-2.0"
			(at 0 0 0)
			(layer "B.Fab")
			(hide yes)
			(effects
				(font
					(size 1 1)
					(thickness 0.15)
				)
				(justify mirror)
			)
		)
		(property "MPN" "GRM188R60J476ME15D"
			(at 0 0 0)
			(layer "B.Fab")
			(hide yes)
			(effects
				(font
					(size 1 1)
					(thickness 0.15)
				)
				(justify mirror)
			)
		)
		(property "Manufacturer" "Murata"
			(at 0 0 0)
			(layer "B.Fab")
			(hide yes)
			(effects
				(font
					(size 1 1)
					(thickness 0.15)
				)
				(justify mirror)
			)
		)
		(property "Val" "47u"
			(at 0 0 0)
			(layer "B.Fab")
			(hide yes)
			(effects
				(font
					(size 1 1)
					(thickness 0.15)
				)
				(justify mirror)
			)
		)
		(property "Voltage" ""
			(at 0 0 0)
			(layer "B.Fab")
			(hide yes)
			(effects
				(font
					(size 1 1)
					(thickness 0.15)
				)
				(justify mirror)
			)
		)
		(sheetname "FPGA Bank 18 & 32")
		(sheetfile "fpga-bank-18-32.kicad_sch")
		(attr smd)
		(fp_line
			(start -0.15 -0.4)
			(end 0.15 -0.4)
			(stroke
				(width 0.15)
				(type solid)
			)
			(layer "B.SilkS")
		)
		(fp_line
			(start -0.15 0.4)
			(end 0.15 0.4)
			(stroke
				(width 0.15)
				(type solid)
			)
			(layer "B.SilkS")
		)
		(fp_rect
			(start -1.25 0.65)
			(end 1.25 -0.65)
			(stroke
				(width 0.05)
				(type solid)
			)
			(fill no)
			(layer "B.CrtYd")
		)
		(fp_rect
			(start -0.8 0.4)
			(end 0.8 -0.4)
			(stroke
				(width 0.15)
				(type solid)
			)
			(fill no)
			(layer "B.Fab")
		)
		(pad "1" smd roundrect
			(at -0.7 0)
			(size 0.8 1)
			(layers "B.Cu" "B.Mask" "B.Paste")
			(roundrect_rratio 0.2)
			(net 26 "+1V8")
			(pintype "passive")
		)
		(pad "2" smd roundrect
			(at 0.7 0)
			(size 0.8 1)
			(layers "B.Cu" "B.Mask" "B.Paste")
			(roundrect_rratio 0.2)
			(net 1 "GND")
			(pintype "passive")
		)
	)
	(footprint "antmicro-footprints:R_0402_1005Metric"
		(layer "B.Cu")
		(at 249.301 141.25 -90)
		(descr "Resistor SMD 0402")
		(tags "resistor SMD 0402")
		(property "Reference" "R88"
			(at 0.75 -0.399 90)
			(layer "B.SilkS")
			(effects
				(font
					(size 0.7 0.7)
					(thickness 0.15)
				)
				(justify left bottom mirror)
			)
		)
		(property "Value" "R_10k_0402"
			(at 0 -1.4 90)
			(layer "B.Fab")
			(effects
				(font
					(size 0.7 0.7)
					(thickness 0.15)
				)
				(justify left bottom mirror)
			)
		)
		(property "Description" "SMD Chip Resistor, 10 kohm, ± 1%, 62.5 mW, 0402 [1005 Metric], Thick Film, General Purpose"
			(at 0 0 270)
			(layer "F.Fab")
			(hide yes)
			(effects
				(font
					(size 1.27 1.27)
					(thickness 0.15)
				)
			)
		)
		(property "Author" "Antmicro"
			(at 108.051 390.551 0)
			(layer "B.Fab")
			(hide yes)
			(effects
				(font
					(size 1 1)
					(thickness 0.15)
				)
				(justify mirror)
			)
		)
		(property "License" "Apache-2.0"
			(at 108.051 390.551 0)
			(layer "B.Fab")
			(hide yes)
			(effects
				(font
					(size 1 1)
					(thickness 0.15)
				)
				(justify mirror)
			)
		)
		(property "MPN" "CR0402-FX-1002GLF"
			(at 108.051 390.551 0)
			(layer "B.Fab")
			(hide yes)
			(effects
				(font
					(size 1 1)
					(thickness 0.15)
				)
				(justify mirror)
			)
		)
		(property "Manufacturer" "Bourns"
			(at 108.051 390.551 0)
			(layer "B.Fab")
			(hide yes)
			(effects
				(font
					(size 1 1)
					(thickness 0.15)
				)
				(justify mirror)
			)
		)
		(property "Tolerance" "1%"
			(at 108.051 390.551 0)
			(layer "B.Fab")
			(hide yes)
			(effects
				(font
					(size 1 1)
					(thickness 0.15)
				)
				(justify mirror)
			)
		)
		(property "Val" "10k"
			(at 108.051 390.551 0)
			(layer "B.Fab")
			(hide yes)
			(effects
				(font
					(size 1 1)
					(thickness 0.15)
				)
				(justify mirror)
			)
		)
		(sheetname "SPI Flash + SD Card")
		(sheetfile "spi-flash.kicad_sch")
		(attr smd)
		(fp_rect
			(start -0.925 0.47)
			(end 0.925 -0.47)
			(stroke
				(width 0.05)
				(type default)
			)
			(fill no)
			(layer "B.CrtYd")
		)
		(fp_rect
			(start -0.5 0.25)
			(end 0.5 -0.25)
			(stroke
				(width 0.15)
				(type solid)
			)
			(fill no)
			(layer "B.Fab")
		)
		(pad "1" smd roundrect
			(at -0.48 0 270)
			(size 0.59 0.64)
			(layers "B.Cu" "B.Mask" "B.Paste")
			(roundrect_rratio 0.25)
			(net 393 "/FPGA Bank 33 & 34/SD_CARD.CMD")
			(pintype "passive")
		)
		(pad "2" smd roundrect
			(at 0.48 0 270)
			(size 0.59 0.64)
			(layers "B.Cu" "B.Mask" "B.Paste")
			(roundrect_rratio 0.25)
			(net 24 "+3V3")
			(pintype "passive")
		)
	)
	(footprint "antmicro-footprints:C_0402_1005Metric"
		(layer "B.Cu")
		(at 196.75 128.775 180)
		(descr "Capacitor SMD 0402")
		(tags "capacitor SMD 0402")
		(property "Reference" "C138"
			(at -25.45 28.75 0)
			(layer "B.SilkS")
			(effects
				(font
					(size 0.7 0.7)
					(thickness 0.15)
				)
				(justify left bottom mirror)
			)
		)
		(property "Value" "C_100n_0402"
			(at 0 -1.169 0)
			(layer "B.Fab")
			(effects
				(font
					(size 0.7 0.7)
					(thickness 0.15)
				)
				(justify left bottom mirror)
			)
		)
		(property "Description" "SMD Multilayer Ceramic Capacitor, 0.1 µF, 50 V, 0402 [1005 Metric], ± 10%, X5R, GRM Series"
			(at 0 0 180)
			(layer "F.Fab")
			(hide yes)
			(effects
				(font
					(size 1.27 1.27)
					(thickness 0.15)
				)
			)
		)
		(property "Author" "Antmicro"
			(at 393.5 257.55 0)
			(layer "B.Fab")
			(hide yes)
			(effects
				(font
					(size 1 1)
					(thickness 0.15)
				)
				(justify mirror)
			)
		)
		(property "Dielectric" "X5R"
			(at 393.5 257.55 0)
			(layer "B.Fab")
			(hide yes)
			(effects
				(font
					(size 1 1)
					(thickness 0.15)
				)
				(justify mirror)
			)
		)
		(property "License" "Apache-2.0"
			(at 393.5 257.55 0)
			(layer "B.Fab")
			(hide yes)
			(effects
				(font
					(size 1 1)
					(thickness 0.15)
				)
				(justify mirror)
			)
		)
		(property "MPN" "GRM155R61H104KE14D"
			(at 393.5 257.55 0)
			(layer "B.Fab")
			(hide yes)
			(effects
				(font
					(size 1 1)
					(thickness 0.15)
				)
				(justify mirror)
			)
		)
		(property "Manufacturer" "Murata"
			(at 393.5 257.55 0)
			(layer "B.Fab")
			(hide yes)
			(effects
				(font
					(size 1 1)
					(thickness 0.15)
				)
				(justify mirror)
			)
		)
		(property "Val" "100n"
			(at 393.5 257.55 0)
			(layer "B.Fab")
			(hide yes)
			(effects
				(font
					(size 1 1)
					(thickness 0.15)
				)
				(justify mirror)
			)
		)
		(property "Voltage" "50V"
			(at 393.5 257.55 0)
			(layer "B.Fab")
			(hide yes)
			(effects
				(font
					(size 1 1)
					(thickness 0.15)
				)
				(justify mirror)
			)
		)
		(sheetname "FPGA supply")
		(sheetfile "fpga-supply.kicad_sch")
		(attr smd)
		(fp_rect
			(start -0.925 0.47)
			(end 0.925 -0.47)
			(stroke
				(width 0.05)
				(type default)
			)
			(fill no)
			(layer "B.CrtYd")
		)
		(fp_line
			(start 0.504 0.25)
			(end 0.504 -0.248)
			(stroke
				(width 0.15)
				(type solid)
			)
			(layer "B.Fab")
		)
		(fp_line
			(start 0.504 -0.248)
			(end -0.494 -0.248)
			(stroke
				(width 0.15)
				(type solid)
			)
			(layer "B.Fab")
		)
		(fp_line
			(start -0.494 0.25)
			(end 0.504 0.25)
			(stroke
				(width 0.15)
				(type solid)
			)
			(layer "B.Fab")
		)
		(fp_line
			(start -0.494 -0.248)
			(end -0.494 0.25)
			(stroke
				(width 0.15)
				(type solid)
			)
			(layer "B.Fab")
		)
		(pad "1" smd roundrect
			(at -0.48 0 180)
			(size 0.59 0.64)
			(layers "B.Cu" "B.Mask" "B.Paste")
			(roundrect_rratio 0.25)
			(net 1 "GND")
			(pintype "passive")
		)
		(pad "2" smd roundrect
			(at 0.48 0 180)
			(size 0.59 0.64)
			(layers "B.Cu" "B.Mask" "B.Paste")
			(roundrect_rratio 0.25)
			(net 650 "+1V0")
			(pintype "passive")
		)
	)
	(footprint "antmicro-footprints:C_0402_1005Metric"
		(layer "B.Cu")
		(at 210.5 133 -90)
		(descr "Capacitor SMD 0402")
		(tags "capacitor SMD 0402")
		(property "Reference" "C25"
			(at -0.95 -1.2 90)
			(layer "B.SilkS")
			(effects
				(font
					(size 0.7 0.7)
					(thickness 0.15)
				)
				(justify left bottom mirror)
			)
		)
		(property "Value" "C_100n_0402"
			(at 0 -1.169 90)
			(layer "B.Fab")
			(effects
				(font
					(size 0.7 0.7)
					(thickness 0.15)
				)
				(justify left bottom mirror)
			)
		)
		(property "Description" "SMD Multilayer Ceramic Capacitor, 0.1 µF, 50 V, 0402 [1005 Metric], ± 10%, X5R, GRM Series"
			(at 0 0 270)
			(layer "F.Fab")
			(hide yes)
			(effects
				(font
					(size 1.27 1.27)
					(thickness 0.15)
				)
			)
		)
		(property "Author" "Antmicro"
			(at 77.5 343.5 0)
			(layer "B.Fab")
			(hide yes)
			(effects
				(font
					(size 1 1)
					(thickness 0.15)
				)
				(justify mirror)
			)
		)
		(property "Dielectric" "X5R"
			(at 77.5 343.5 0)
			(layer "B.Fab")
			(hide yes)
			(effects
				(font
					(size 1 1)
					(thickness 0.15)
				)
				(justify mirror)
			)
		)
		(property "License" "Apache-2.0"
			(at 77.5 343.5 0)
			(layer "B.Fab")
			(hide yes)
			(effects
				(font
					(size 1 1)
					(thickness 0.15)
				)
				(justify mirror)
			)
		)
		(property "MPN" "GRM155R61H104KE14D"
			(at 77.5 343.5 0)
			(layer "B.Fab")
			(hide yes)
			(effects
				(font
					(size 1 1)
					(thickness 0.15)
				)
				(justify mirror)
			)
		)
		(property "Manufacturer" "Murata"
			(at 77.5 343.5 0)
			(layer "B.Fab")
			(hide yes)
			(effects
				(font
					(size 1 1)
					(thickness 0.15)
				)
				(justify mirror)
			)
		)
		(property "Val" "100n"
			(at 77.5 343.5 0)
			(layer "B.Fab")
			(hide yes)
			(effects
				(font
					(size 1 1)
					(thickness 0.15)
				)
				(justify mirror)
			)
		)
		(property "Voltage" "50V"
			(at 77.5 343.5 0)
			(layer "B.Fab")
			(hide yes)
			(effects
				(font
					(size 1 1)
					(thickness 0.15)
				)
				(justify mirror)
			)
		)
		(sheetname "FPGA Bank 14 & 15")
		(sheetfile "fpga-bank-14-15.kicad_sch")
		(attr smd)
		(fp_rect
			(start -0.925 0.47)
			(end 0.925 -0.47)
			(stroke
				(width 0.05)
				(type default)
			)
			(fill no)
			(layer "B.CrtYd")
		)
		(fp_line
			(start -0.494 0.25)
			(end 0.504 0.25)
			(stroke
				(width 0.15)
				(type solid)
			)
			(layer "B.Fab")
		)
		(fp_line
			(start 0.504 0.25)
			(end 0.504 -0.248)
			(stroke
				(width 0.15)
				(type solid)
			)
			(layer "B.Fab")
		)
		(fp_line
			(start -0.494 -0.248)
			(end -0.494 0.25)
			(stroke
				(width 0.15)
				(type solid)
			)
			(layer "B.Fab")
		)
		(fp_line
			(start 0.504 -0.248)
			(end -0.494 -0.248)
			(stroke
				(width 0.15)
				(type solid)
			)
			(layer "B.Fab")
		)
		(pad "1" smd roundrect
			(at -0.48 0 270)
			(size 0.59 0.64)
			(layers "B.Cu" "B.Mask" "B.Paste")
			(roundrect_rratio 0.25)
			(net 1 "GND")
			(pintype "passive")
		)
		(pad "2" smd roundrect
			(at 0.48 0 270)
			(size 0.59 0.64)
			(layers "B.Cu" "B.Mask" "B.Paste")
			(roundrect_rratio 0.25)
			(net 24 "+3V3")
			(pintype "passive")
		)
	)
	(footprint "antmicro-footprints:R_0402_1005Metric"
		(layer "B.Cu")
		(at 165.685001 119.335001)
		(descr "Resistor SMD 0402")
		(tags "resistor SMD 0402")
		(property "Reference" "R268"
			(at -0.810001 0.439999 180)
			(layer "B.SilkS")
			(effects
				(font
					(size 0.7 0.7)
					(thickness 0.15)
				)
				(justify left bottom mirror)
			)
		)
		(property "Value" "R_4k7_0402"
			(at 0 -1.4 180)
			(layer "B.Fab")
			(effects
				(font
					(size 0.7 0.7)
					(thickness 0.15)
				)
				(justify left bottom mirror)
			)
		)
		(property "Description" "SMD Chip Resistor, 4.7 kohm, ± 1%, 62.5 mW, 0402 [1005 Metric], Thick Film, General Purpose"
			(at 0 0 0)
			(layer "F.Fab")
			(hide yes)
			(effects
				(font
					(size 1.27 1.27)
					(thickness 0.15)
				)
			)
		)
		(property "Author" "Antmicro"
			(at 0 0 0)
			(layer "B.Fab")
			(hide yes)
			(effects
				(font
					(size 1 1)
					(thickness 0.15)
				)
				(justify mirror)
			)
		)
		(property "License" "Apache-2.0"
			(at 0 0 0)
			(layer "B.Fab")
			(hide yes)
			(effects
				(font
					(size 1 1)
					(thickness 0.15)
				)
				(justify mirror)
			)
		)
		(property "MPN" "CR0402-FX-4701GLF"
			(at 0 0 0)
			(layer "B.Fab")
			(hide yes)
			(effects
				(font
					(size 1 1)
					(thickness 0.15)
				)
				(justify mirror)
			)
		)
		(property "Manufacturer" "Bourns"
			(at 0 0 0)
			(layer "B.Fab")
			(hide yes)
			(effects
				(font
					(size 1 1)
					(thickness 0.15)
				)
				(justify mirror)
			)
		)
		(property "Tolerance" "1%"
			(at 0 0 0)
			(layer "B.Fab")
			(hide yes)
			(effects
				(font
					(size 1 1)
					(thickness 0.15)
				)
				(justify mirror)
			)
		)
		(property "Val" "4k7"
			(at 0 0 0)
			(layer "B.Fab")
			(hide yes)
			(effects
				(font
					(size 1 1)
					(thickness 0.15)
				)
				(justify mirror)
			)
		)
		(sheetname "FMC+ HSPC")
		(sheetfile "fmc-hspc.kicad_sch")
		(attr smd)
		(fp_rect
			(start -0.925 0.47)
			(end 0.925 -0.47)
			(stroke
				(width 0.05)
				(type default)
			)
			(fill no)
			(layer "B.CrtYd")
		)
		(fp_rect
			(start -0.5 0.25)
			(end 0.5 -0.25)
			(stroke
				(width 0.15)
				(type solid)
			)
			(fill no)
			(layer "B.Fab")
		)
		(pad "1" smd roundrect
			(at -0.48 0)
			(size 0.59 0.64)
			(layers "B.Cu" "B.Mask" "B.Paste")
			(roundrect_rratio 0.25)
			(net 380 "FMC.SDA_3V3")
			(pintype "passive")
		)
		(pad "2" smd roundrect
			(at 0.48 0)
			(size 0.59 0.64)
			(layers "B.Cu" "B.Mask" "B.Paste")
			(roundrect_rratio 0.25)
			(net 24 "+3V3")
			(pintype "passive")
		)
	)
	(footprint "antmicro-footprints:C_0402_1005Metric"
		(layer "B.Cu")
		(at 214 143.5 180)
		(descr "Capacitor SMD 0402")
		(tags "capacitor SMD 0402")
		(property "Reference" "C18"
			(at -1.125 0.45 0)
			(layer "B.SilkS")
			(effects
				(font
					(size 0.7 0.7)
					(thickness 0.15)
				)
				(justify left bottom mirror)
			)
		)
		(property "Value" "C_100n_0402"
			(at 0 -1.169 0)
			(layer "B.Fab")
			(effects
				(font
					(size 0.7 0.7)
					(thickness 0.15)
				)
				(justify left bottom mirror)
			)
		)
		(property "Description" "SMD Multilayer Ceramic Capacitor, 0.1 µF, 50 V, 0402 [1005 Metric], ± 10%, X5R, GRM Series"
			(at 0 0 180)
			(layer "F.Fab")
			(hide yes)
			(effects
				(font
					(size 1.27 1.27)
					(thickness 0.15)
				)
			)
		)
		(property "Author" "Antmicro"
			(at 428 287 0)
			(layer "B.Fab")
			(hide yes)
			(effects
				(font
					(size 1 1)
					(thickness 0.15)
				)
				(justify mirror)
			)
		)
		(property "Dielectric" "X5R"
			(at 428 287 0)
			(layer "B.Fab")
			(hide yes)
			(effects
				(font
					(size 1 1)
					(thickness 0.15)
				)
				(justify mirror)
			)
		)
		(property "License" "Apache-2.0"
			(at 428 287 0)
			(layer "B.Fab")
			(hide yes)
			(effects
				(font
					(size 1 1)
					(thickness 0.15)
				)
				(justify mirror)
			)
		)
		(property "MPN" "GRM155R61H104KE14D"
			(at 428 287 0)
			(layer "B.Fab")
			(hide yes)
			(effects
				(font
					(size 1 1)
					(thickness 0.15)
				)
				(justify mirror)
			)
		)
		(property "Manufacturer" "Murata"
			(at 428 287 0)
			(layer "B.Fab")
			(hide yes)
			(effects
				(font
					(size 1 1)
					(thickness 0.15)
				)
				(justify mirror)
			)
		)
		(property "Val" "100n"
			(at 428 287 0)
			(layer "B.Fab")
			(hide yes)
			(effects
				(font
					(size 1 1)
					(thickness 0.15)
				)
				(justify mirror)
			)
		)
		(property "Voltage" "50V"
			(at 428 287 0)
			(layer "B.Fab")
			(hide yes)
			(effects
				(font
					(size 1 1)
					(thickness 0.15)
				)
				(justify mirror)
			)
		)
		(sheetname "FPGA Bank 12 & 13")
		(sheetfile "fpga-bank-12-13.kicad_sch")
		(attr smd)
		(fp_rect
			(start -0.925 0.47)
			(end 0.925 -0.47)
			(stroke
				(width 0.05)
				(type default)
			)
			(fill no)
			(layer "B.CrtYd")
		)
		(fp_line
			(start 0.504 0.25)
			(end 0.504 -0.248)
			(stroke
				(width 0.15)
				(type solid)
			)
			(layer "B.Fab")
		)
		(fp_line
			(start 0.504 -0.248)
			(end -0.494 -0.248)
			(stroke
				(width 0.15)
				(type solid)
			)
			(layer "B.Fab")
		)
		(fp_line
			(start -0.494 0.25)
			(end 0.504 0.25)
			(stroke
				(width 0.15)
				(type solid)
			)
			(layer "B.Fab")
		)
		(fp_line
			(start -0.494 -0.248)
			(end -0.494 0.25)
			(stroke
				(width 0.15)
				(type solid)
			)
			(layer "B.Fab")
		)
		(pad "1" smd roundrect
			(at -0.48 0 180)
			(size 0.59 0.64)
			(layers "B.Cu" "B.Mask" "B.Paste")
			(roundrect_rratio 0.25)
			(net 1 "GND")
			(pintype "passive")
		)
		(pad "2" smd roundrect
			(at 0.48 0 180)
			(size 0.59 0.64)
			(layers "B.Cu" "B.Mask" "B.Paste")
			(roundrect_rratio 0.25)
			(net 24 "+3V3")
			(pintype "passive")
		)
	)
	(footprint "antmicro-footprints:NetTie-2_SMD_Pad0.127mm"
		(layer "B.Cu")
		(at 254.101 148.4 -90)
		(descr "Net tie, 2 pin, 0.127mm  SMD pads")
		(tags "net tie")
		(property "Reference" "NT11"
			(at -0.128 1.345 90)
			(layer "B.SilkS")
			(hide yes)
			(effects
				(font
					(size 0.7 0.7)
					(thickness 0.15)
				)
				(justify left bottom mirror)
			)
		)
		(property "Value" "Net-Tie_2"
			(at 0 -1.199 90)
			(layer "B.Fab")
			(effects
				(font
					(size 0.7 0.7)
					(thickness 0.15)
				)
				(justify left bottom mirror)
			)
		)
		(property "Description" "Net tie, 2 pins"
			(at 0 0 270)
			(layer "F.Fab")
			(hide yes)
			(effects
				(font
					(size 1.27 1.27)
					(thickness 0.15)
				)
			)
		)
		(property "Author" "Antmicro"
			(at 105.701 402.501 0)
			(layer "B.Fab")
			(hide yes)
			(effects
				(font
					(size 1 1)
					(thickness 0.15)
				)
				(justify mirror)
			)
		)
		(property "License" "Apache-2.0"
			(at 105.701 402.501 0)
			(layer "B.Fab")
			(hide yes)
			(effects
				(font
					(size 1 1)
					(thickness 0.15)
				)
				(justify mirror)
			)
		)
		(property "MPN" ""
			(at 105.701 402.501 0)
			(layer "B.Fab")
			(hide yes)
			(effects
				(font
					(size 1 1)
					(thickness 0.15)
				)
				(justify mirror)
			)
		)
		(property "Manufacturer" ""
			(at 105.701 402.501 0)
			(layer "B.Fab")
			(hide yes)
			(effects
				(font
					(size 1 1)
					(thickness 0.15)
				)
				(justify mirror)
			)
		)
		(sheetname "FPGA Bank 14 & 15")
		(sheetfile "fpga-bank-14-15.kicad_sch")
		(attr exclude_from_pos_files)
		(net_tie_pad_groups "1, 2")
		(fp_poly
			(pts
				(xy -0.0635 0.0635) (xy 0.0625 0.0635) (xy 0.0625 -0.0635) (xy -0.0635 -0.0635)
			)
			(stroke
				(width 0)
				(type solid)
			)
			(fill yes)
			(layer "B.Cu")
		)
		(pad "1" smd roundrect
			(at -0.127 0 90)
			(size 0.127 0.127)
			(layers "B.Cu")
			(roundrect_rratio 0.5)
			(chamfer_ratio 0)
			(chamfer top_left bottom_left)
			(net 1296 "/USB_SPI.SCK")
			(pinfunction "1")
			(pintype "passive")
		)
		(pad "2" smd roundrect
			(at 0.126 0 270)
			(size 0.127 0.127)
			(layers "B.Cu")
			(roundrect_rratio 0.5)
			(chamfer_ratio 0)
			(chamfer top_left bottom_left)
			(net 1323 "/SUP_MCU.SCLK0")
			(pinfunction "2")
			(pintype "passive")
		)
	)
	(footprint "antmicro-footprints:C_0201"
		(layer "B.Cu")
		(at 189.8 117.5 180)
		(descr "Capacitor SMD 0201")
		(tags "capacitor SMD 0201")
		(property "Reference" "C144"
			(at 4.15 0.5 0)
			(layer "B.SilkS")
			(effects
				(font
					(size 0.7 0.7)
					(thickness 0.15)
				)
				(justify left bottom mirror)
			)
		)
		(property "Value" "C_100n_0201"
			(at 0 -1.4 0)
			(layer "B.Fab")
			(effects
				(font
					(size 0.7 0.7)
					(thickness 0.15)
				)
				(justify left bottom mirror)
			)
		)
		(property "Description" "SMD Multilayer Ceramic Capacitor, 0.1 µF, 6.3 V, 0201 [0603 Metric], ± 10%, X6S, CC Series"
			(at 0 0 180)
			(layer "F.Fab")
			(hide yes)
			(effects
				(font
					(size 1.27 1.27)
					(thickness 0.15)
				)
			)
		)
		(property "Author" "Antmicro"
			(at 379.6 235 0)
			(layer "B.Fab")
			(hide yes)
			(effects
				(font
					(size 1 1)
					(thickness 0.15)
				)
				(justify mirror)
			)
		)
		(property "Dielectric" ""
			(at 379.6 235 0)
			(layer "B.Fab")
			(hide yes)
			(effects
				(font
					(size 1 1)
					(thickness 0.15)
				)
				(justify mirror)
			)
		)
		(property "License" "Apache-2.0"
			(at 379.6 235 0)
			(layer "B.Fab")
			(hide yes)
			(effects
				(font
					(size 1 1)
					(thickness 0.15)
				)
				(justify mirror)
			)
		)
		(property "MPN" "CC0201KRX6S5BB104"
			(at 379.6 235 0)
			(layer "B.Fab")
			(hide yes)
			(effects
				(font
					(size 1 1)
					(thickness 0.15)
				)
				(justify mirror)
			)
		)
		(property "Manufacturer" "YAGEO"
			(at 379.6 235 0)
			(layer "B.Fab")
			(hide yes)
			(effects
				(font
					(size 1 1)
					(thickness 0.15)
				)
				(justify mirror)
			)
		)
		(property "Val" "100n"
			(at 379.6 235 0)
			(layer "B.Fab")
			(hide yes)
			(effects
				(font
					(size 1 1)
					(thickness 0.15)
				)
				(justify mirror)
			)
		)
		(property "Voltage" ""
			(at 379.6 235 0)
			(layer "B.Fab")
			(hide yes)
			(effects
				(font
					(size 1 1)
					(thickness 0.15)
				)
				(justify mirror)
			)
		)
		(sheetname "FPGA supply")
		(sheetfile "fpga-supply.kicad_sch")
		(attr smd)
		(fp_rect
			(start -0.7 0.35)
			(end 0.7 -0.35)
			(stroke
				(width 0.05)
				(type default)
			)
			(fill no)
			(layer "B.CrtYd")
		)
		(fp_rect
			(start 0.3 -0.15)
			(end -0.301 0.149)
			(stroke
				(width 0.15)
				(type solid)
			)
			(fill no)
			(layer "B.Fab")
		)
		(pad "" smd roundrect
			(at -0.349 0.002 180)
			(size 0.318 0.36)
			(layers "B.Paste")
			(roundrect_rratio 0.25)
		)
		(pad "" smd roundrect
			(at 0.341 0.002 180)
			(size 0.318 0.36)
			(layers "B.Paste")
			(roundrect_rratio 0.25)
		)
		(pad "1" smd roundrect
			(at -0.321 0.002 180)
			(size 0.46 0.4)
			(layers "B.Cu" "B.Mask")
			(roundrect_rratio 0.25)
			(net 1 "GND")
			(pintype "passive")
		)
		(pad "2" smd roundrect
			(at 0.32 0.002 180)
			(size 0.46 0.4)
			(layers "B.Cu" "B.Mask")
			(roundrect_rratio 0.25)
			(net 8 "+1V2_MGTAVTT")
			(pintype "passive")
		)
	)
	(footprint "antmicro-footprints:R_0402_1005Metric"
		(layer "B.Cu")
		(at 266.8 93.2 -90)
		(descr "Resistor SMD 0402")
		(tags "resistor SMD 0402")
		(property "Reference" "R149"
			(at -1.35 -1.3 90)
			(layer "B.SilkS")
			(effects
				(font
					(size 0.7 0.7)
					(thickness 0.15)
				)
				(justify left bottom mirror)
			)
		)
		(property "Value" "R_10k_0402"
			(at 0 -1.4 90)
			(layer "B.Fab")
			(effects
				(font
					(size 0.7 0.7)
					(thickness 0.15)
				)
				(justify left bottom mirror)
			)
		)
		(property "Description" "SMD Chip Resistor, 10 kohm, ± 1%, 62.5 mW, 0402 [1005 Metric], Thick Film, General Purpose"
			(at 0 0 270)
			(layer "F.Fab")
			(hide yes)
			(effects
				(font
					(size 1.27 1.27)
					(thickness 0.15)
				)
			)
		)
		(property "Author" "Antmicro"
			(at 173.6 360 0)
			(layer "B.Fab")
			(hide yes)
			(effects
				(font
					(size 1 1)
					(thickness 0.15)
				)
				(justify mirror)
			)
		)
		(property "License" "Apache-2.0"
			(at 173.6 360 0)
			(layer "B.Fab")
			(hide yes)
			(effects
				(font
					(size 1 1)
					(thickness 0.15)
				)
				(justify mirror)
			)
		)
		(property "MPN" "CR0402-FX-1002GLF"
			(at 173.6 360 0)
			(layer "B.Fab")
			(hide yes)
			(effects
				(font
					(size 1 1)
					(thickness 0.15)
				)
				(justify mirror)
			)
		)
		(property "Manufacturer" "Bourns"
			(at 173.6 360 0)
			(layer "B.Fab")
			(hide yes)
			(effects
				(font
					(size 1 1)
					(thickness 0.15)
				)
				(justify mirror)
			)
		)
		(property "Tolerance" "1%"
			(at 173.6 360 0)
			(layer "B.Fab")
			(hide yes)
			(effects
				(font
					(size 1 1)
					(thickness 0.15)
				)
				(justify mirror)
			)
		)
		(property "Val" "10k"
			(at 173.6 360 0)
			(layer "B.Fab")
			(hide yes)
			(effects
				(font
					(size 1 1)
					(thickness 0.15)
				)
				(justify mirror)
			)
		)
		(sheetname "User GPIO + LED + button + DIP switch")
		(sheetfile "user-gpio.kicad_sch")
		(attr smd)
		(fp_rect
			(start -0.925 0.47)
			(end 0.925 -0.47)
			(stroke
				(width 0.05)
				(type default)
			)
			(fill no)
			(layer "B.CrtYd")
		)
		(fp_rect
			(start -0.5 0.25)
			(end 0.5 -0.25)
			(stroke
				(width 0.15)
				(type solid)
			)
			(fill no)
			(layer "B.Fab")
		)
		(pad "1" smd roundrect
			(at -0.48 0 270)
			(size 0.59 0.64)
			(layers "B.Cu" "B.Mask" "B.Paste")
			(roundrect_rratio 0.25)
			(net 26 "+1V8")
			(pintype "passive")
		)
		(pad "2" smd roundrect
			(at 0.48 0 270)
			(size 0.59 0.64)
			(layers "B.Cu" "B.Mask" "B.Paste")
			(roundrect_rratio 0.25)
			(net 1232 "/USER_IO.BUTTON3")
			(pintype "passive")
		)
	)
	(footprint "antmicro-footprints:C_0201"
		(layer "B.Cu")
		(at 203.45 128.5 -90)
		(descr "Capacitor SMD 0201")
		(tags "capacitor SMD 0201")
		(property "Reference" "C8"
			(at -29.875 -28.2 90)
			(layer "B.SilkS")
			(effects
				(font
					(size 0.7 0.7)
					(thickness 0.15)
				)
				(justify left bottom mirror)
			)
		)
		(property "Value" "C_4u7_0201"
			(at 0 -1.4 90)
			(layer "B.Fab")
			(effects
				(font
					(size 0.7 0.7)
					(thickness 0.15)
				)
				(justify left bottom mirror)
			)
		)
		(property "Description" "SMD Multilayer Ceramic Capacitor, 4.7 µF, 6.3 V, 0201 [0603 Metric], ± 20%, X5R, GRM Series"
			(at 0 0 270)
			(layer "F.Fab")
			(hide yes)
			(effects
				(font
					(size 1.27 1.27)
					(thickness 0.15)
				)
			)
		)
		(property "Author" "Antmicro"
			(at 74.95 331.95 0)
			(layer "B.Fab")
			(hide yes)
			(effects
				(font
					(size 1 1)
					(thickness 0.15)
				)
				(justify mirror)
			)
		)
		(property "Dielectric" ""
			(at 74.95 331.95 0)
			(layer "B.Fab")
			(hide yes)
			(effects
				(font
					(size 1 1)
					(thickness 0.15)
				)
				(justify mirror)
			)
		)
		(property "License" "Apache-2.0"
			(at 74.95 331.95 0)
			(layer "B.Fab")
			(hide yes)
			(effects
				(font
					(size 1 1)
					(thickness 0.15)
				)
				(justify mirror)
			)
		)
		(property "MPN" "GRM035R60J475ME15D"
			(at 74.95 331.95 0)
			(layer "B.Fab")
			(hide yes)
			(effects
				(font
					(size 1 1)
					(thickness 0.15)
				)
				(justify mirror)
			)
		)
		(property "Manufacturer" "Murata"
			(at 74.95 331.95 0)
			(layer "B.Fab")
			(hide yes)
			(effects
				(font
					(size 1 1)
					(thickness 0.15)
				)
				(justify mirror)
			)
		)
		(property "Val" "4u7"
			(at 74.95 331.95 0)
			(layer "B.Fab")
			(hide yes)
			(effects
				(font
					(size 1 1)
					(thickness 0.15)
				)
				(justify mirror)
			)
		)
		(property "Voltage" ""
			(at 74.95 331.95 0)
			(layer "B.Fab")
			(hide yes)
			(effects
				(font
					(size 1 1)
					(thickness 0.15)
				)
				(justify mirror)
			)
		)
		(sheetname "FPGA supply")
		(sheetfile "fpga-supply.kicad_sch")
		(attr smd)
		(fp_rect
			(start -0.7 0.35)
			(end 0.7 -0.35)
			(stroke
				(width 0.05)
				(type default)
			)
			(fill no)
			(layer "B.CrtYd")
		)
		(fp_rect
			(start 0.3 -0.15)
			(end -0.301 0.149)
			(stroke
				(width 0.15)
				(type solid)
			)
			(fill no)
			(layer "B.Fab")
		)
		(pad "" smd roundrect
			(at -0.349 0.002 270)
			(size 0.318 0.36)
			(layers "B.Paste")
			(roundrect_rratio 0.25)
		)
		(pad "" smd roundrect
			(at 0.341 0.002 270)
			(size 0.318 0.36)
			(layers "B.Paste")
			(roundrect_rratio 0.25)
		)
		(pad "1" smd roundrect
			(at -0.321 0.002 270)
			(size 0.46 0.4)
			(layers "B.Cu" "B.Mask")
			(roundrect_rratio 0.25)
			(net 1 "GND")
			(pintype "passive")
		)
		(pad "2" smd roundrect
			(at 0.32 0.002 270)
			(size 0.46 0.4)
			(layers "B.Cu" "B.Mask")
			(roundrect_rratio 0.25)
			(net 650 "+1V0")
			(pintype "passive")
		)
	)
	(footprint "antmicro-footprints:R_0402_1005Metric"
		(layer "B.Cu")
		(at 179.05 175.2625 90)
		(descr "Resistor SMD 0402")
		(tags "resistor SMD 0402")
		(property "Reference" "R314"
			(at -0.7375 0.425 270)
			(layer "B.SilkS")
			(effects
				(font
					(size 0.7 0.7)
					(thickness 0.15)
				)
				(justify left bottom mirror)
			)
		)
		(property "Value" "R_0R_0402"
			(at 0 -1.4 270)
			(layer "B.Fab")
			(effects
				(font
					(size 0.7 0.7)
					(thickness 0.15)
				)
				(justify left bottom mirror)
			)
		)
		(property "Description" "SMD Chip Resistor, Jumper, 0 ohm, 100 mW, 0402 [1005 Metric], Thick Film, General Purpose"
			(at 0 0 90)
			(layer "F.Fab")
			(hide yes)
			(effects
				(font
					(size 1.27 1.27)
					(thickness 0.15)
				)
			)
		)
		(property "Author" "Antmicro"
			(at 354.3125 -3.7875 0)
			(layer "B.Fab")
			(hide yes)
			(effects
				(font
					(size 1 1)
					(thickness 0.15)
				)
				(justify mirror)
			)
		)
		(property "Current" "1A"
			(at 354.3125 -3.7875 0)
			(layer "B.Fab")
			(hide yes)
			(effects
				(font
					(size 1 1)
					(thickness 0.15)
				)
				(justify mirror)
			)
		)
		(property "DNP" "DNP"
			(at 354.3125 -3.7875 0)
			(layer "B.Fab")
			(hide yes)
			(effects
				(font
					(size 1 1)
					(thickness 0.15)
				)
				(justify mirror)
			)
		)
		(property "License" "Apache-2.0"
			(at 354.3125 -3.7875 0)
			(layer "B.Fab")
			(hide yes)
			(effects
				(font
					(size 1 1)
					(thickness 0.15)
				)
				(justify mirror)
			)
		)
		(property "MPN" "ERJ2GE0R00X"
			(at 354.3125 -3.7875 0)
			(layer "B.Fab")
			(hide yes)
			(effects
				(font
					(size 1 1)
					(thickness 0.15)
				)
				(justify mirror)
			)
		)
		(property "Manufacturer" "Panasonic"
			(at 354.3125 -3.7875 0)
			(layer "B.Fab")
			(hide yes)
			(effects
				(font
					(size 1 1)
					(thickness 0.15)
				)
				(justify mirror)
			)
		)
		(property "Tolerance" ""
			(at 354.3125 -3.7875 0)
			(layer "B.Fab")
			(hide yes)
			(effects
				(font
					(size 1 1)
					(thickness 0.15)
				)
				(justify mirror)
			)
		)
		(property "Val" "0R"
			(at 354.3125 -3.7875 0)
			(layer "B.Fab")
			(hide yes)
			(effects
				(font
					(size 1 1)
					(thickness 0.15)
				)
				(justify mirror)
			)
		)
		(property "dnp" ""
			(at 354.3125 -3.7875 0)
			(layer "B.Fab")
			(hide yes)
			(effects
				(font
					(size 1 1)
					(thickness 0.15)
				)
				(justify mirror)
			)
		)
		(property "exclude_from_bom" ""
			(at 354.3125 -3.7875 0)
			(layer "B.Fab")
			(hide yes)
			(effects
				(font
					(size 1 1)
					(thickness 0.15)
				)
				(justify mirror)
			)
		)
		(sheetname "DC-DC Converters")
		(sheetfile "dc-dc.kicad_sch")
		(attr smd exclude_from_bom)
		(fp_rect
			(start -0.925 0.47)
			(end 0.925 -0.47)
			(stroke
				(width 0.05)
				(type default)
			)
			(fill no)
			(layer "B.CrtYd")
		)
		(fp_rect
			(start -0.5 0.25)
			(end 0.5 -0.25)
			(stroke
				(width 0.15)
				(type solid)
			)
			(fill no)
			(layer "B.Fab")
		)
		(pad "1" smd roundrect
			(at -0.48 0 90)
			(size 0.59 0.64)
			(layers "B.Cu" "B.Mask" "B.Paste")
			(roundrect_rratio 0.25)
			(net 1213 "/DC-DC Converters/SENSE_5V_N")
			(pintype "passive")
		)
		(pad "2" smd roundrect
			(at 0.48 0 90)
			(size 0.59 0.64)
			(layers "B.Cu" "B.Mask" "B.Paste")
			(roundrect_rratio 0.25)
			(net 964 "/DC-DC Converters/FB7")
			(pintype "passive")
		)
	)
	(footprint "antmicro-footprints:C_0402_1005Metric"
		(layer "B.Cu")
		(at 189 144.5)
		(descr "Capacitor SMD 0402")
		(tags "capacitor SMD 0402")
		(property "Reference" "C102"
			(at 1.325 1.2 180)
			(layer "B.SilkS")
			(effects
				(font
					(size 0.7 0.7)
					(thickness 0.15)
				)
				(justify left bottom mirror)
			)
		)
		(property "Value" "C_100n_0402"
			(at 0 -1.169 180)
			(layer "B.Fab")
			(effects
				(font
					(size 0.7 0.7)
					(thickness 0.15)
				)
				(justify left bottom mirror)
			)
		)
		(property "Description" "SMD Multilayer Ceramic Capacitor, 0.1 µF, 50 V, 0402 [1005 Metric], ± 10%, X5R, GRM Series"
			(at 0 0 0)
			(layer "F.Fab")
			(hide yes)
			(effects
				(font
					(size 1.27 1.27)
					(thickness 0.15)
				)
			)
		)
		(property "Author" "Antmicro"
			(at 0 0 0)
			(layer "B.Fab")
			(hide yes)
			(effects
				(font
					(size 1 1)
					(thickness 0.15)
				)
				(justify mirror)
			)
		)
		(property "Dielectric" "X5R"
			(at 0 0 0)
			(layer "B.Fab")
			(hide yes)
			(effects
				(font
					(size 1 1)
					(thickness 0.15)
				)
				(justify mirror)
			)
		)
		(property "License" "Apache-2.0"
			(at 0 0 0)
			(layer "B.Fab")
			(hide yes)
			(effects
				(font
					(size 1 1)
					(thickness 0.15)
				)
				(justify mirror)
			)
		)
		(property "MPN" "GRM155R61H104KE14D"
			(at 0 0 0)
			(layer "B.Fab")
			(hide yes)
			(effects
				(font
					(size 1 1)
					(thickness 0.15)
				)
				(justify mirror)
			)
		)
		(property "Manufacturer" "Murata"
			(at 0 0 0)
			(layer "B.Fab")
			(hide yes)
			(effects
				(font
					(size 1 1)
					(thickness 0.15)
				)
				(justify mirror)
			)
		)
		(property "Val" "100n"
			(at 0 0 0)
			(layer "B.Fab")
			(hide yes)
			(effects
				(font
					(size 1 1)
					(thickness 0.15)
				)
				(justify mirror)
			)
		)
		(property "Voltage" "50V"
			(at 0 0 0)
			(layer "B.Fab")
			(hide yes)
			(effects
				(font
					(size 1 1)
					(thickness 0.15)
				)
				(justify mirror)
			)
		)
		(sheetname "FPGA Bank 33 & 34")
		(sheetfile "fpga-bank-33-34.kicad_sch")
		(attr smd)
		(fp_rect
			(start -0.925 0.47)
			(end 0.925 -0.47)
			(stroke
				(width 0.05)
				(type default)
			)
			(fill no)
			(layer "B.CrtYd")
		)
		(fp_line
			(start -0.494 -0.248)
			(end -0.494 0.25)
			(stroke
				(width 0.15)
				(type solid)
			)
			(layer "B.Fab")
		)
		(fp_line
			(start -0.494 0.25)
			(end 0.504 0.25)
			(stroke
				(width 0.15)
				(type solid)
			)
			(layer "B.Fab")
		)
		(fp_line
			(start 0.504 -0.248)
			(end -0.494 -0.248)
			(stroke
				(width 0.15)
				(type solid)
			)
			(layer "B.Fab")
		)
		(fp_line
			(start 0.504 0.25)
			(end 0.504 -0.248)
			(stroke
				(width 0.15)
				(type solid)
			)
			(layer "B.Fab")
		)
		(pad "1" smd roundrect
			(at -0.48 0)
			(size 0.59 0.64)
			(layers "B.Cu" "B.Mask" "B.Paste")
			(roundrect_rratio 0.25)
			(net 1 "GND")
			(pintype "passive")
		)
		(pad "2" smd roundrect
			(at 0.48 0)
			(size 0.59 0.64)
			(layers "B.Cu" "B.Mask" "B.Paste")
			(roundrect_rratio 0.25)
			(net 25 "+1V35")
			(pintype "passive")
		)
	)
	(footprint "antmicro-footprints:C_0402_1005Metric"
		(layer "B.Cu")
		(at 160.5 146.475 -90)
		(descr "Capacitor SMD 0402")
		(tags "capacitor SMD 0402")
		(property "Reference" "C168"
			(at -1.025 3.475 90)
			(layer "B.SilkS")
			(effects
				(font
					(size 0.7 0.7)
					(thickness 0.15)
				)
				(justify left bottom mirror)
			)
		)
		(property "Value" "C_10u_0402"
			(at 0 -1.4 90)
			(layer "B.Fab")
			(effects
				(font
					(size 0.7 0.7)
					(thickness 0.15)
				)
				(justify left bottom mirror)
			)
		)
		(property "Description" "SMD Multilayer Ceramic Capacitor, 10 µF, 6.3 V, 0402 [1005 Metric], ± 20%, X5R, CC Series"
			(at 0 0 270)
			(layer "F.Fab")
			(hide yes)
			(effects
				(font
					(size 1.27 1.27)
					(thickness 0.15)
				)
			)
		)
		(property "Author" "Antmicro"
			(at 14.025 306.975 0)
			(layer "B.Fab")
			(hide yes)
			(effects
				(font
					(size 1 1)
					(thickness 0.15)
				)
				(justify mirror)
			)
		)
		(property "Dielectric" ""
			(at 14.025 306.975 0)
			(layer "B.Fab")
			(hide yes)
			(effects
				(font
					(size 1 1)
					(thickness 0.15)
				)
				(justify mirror)
			)
		)
		(property "License" "Apache-2.0"
			(at 14.025 306.975 0)
			(layer "B.Fab")
			(hide yes)
			(effects
				(font
					(size 1 1)
					(thickness 0.15)
				)
				(justify mirror)
			)
		)
		(property "MPN" "CC0402MRX5R5BB106"
			(at 14.025 306.975 0)
			(layer "B.Fab")
			(hide yes)
			(effects
				(font
					(size 1 1)
					(thickness 0.15)
				)
				(justify mirror)
			)
		)
		(property "Manufacturer" "YAGEO"
			(at 14.025 306.975 0)
			(layer "B.Fab")
			(hide yes)
			(effects
				(font
					(size 1 1)
					(thickness 0.15)
				)
				(justify mirror)
			)
		)
		(property "Val" "10u"
			(at 14.025 306.975 0)
			(layer "B.Fab")
			(hide yes)
			(effects
				(font
					(size 1 1)
					(thickness 0.15)
				)
				(justify mirror)
			)
		)
		(property "Voltage" ""
			(at 14.025 306.975 0)
			(layer "B.Fab")
			(hide yes)
			(effects
				(font
					(size 1 1)
					(thickness 0.15)
				)
				(justify mirror)
			)
		)
		(sheetname "DRAM + SRAM")
		(sheetfile "ram.kicad_sch")
		(attr smd)
		(fp_rect
			(start -0.925 0.47)
			(end 0.925 -0.47)
			(stroke
				(width 0.05)
				(type default)
			)
			(fill no)
			(layer "B.CrtYd")
		)
		(fp_line
			(start -0.494 0.25)
			(end 0.504 0.25)
			(stroke
				(width 0.15)
				(type solid)
			)
			(layer "B.Fab")
		)
		(fp_line
			(start 0.504 0.25)
			(end 0.504 -0.248)
			(stroke
				(width 0.15)
				(type solid)
			)
			(layer "B.Fab")
		)
		(fp_line
			(start -0.494 -0.248)
			(end -0.494 0.25)
			(stroke
				(width 0.15)
				(type solid)
			)
			(layer "B.Fab")
		)
		(fp_line
			(start 0.504 -0.248)
			(end -0.494 -0.248)
			(stroke
				(width 0.15)
				(type solid)
			)
			(layer "B.Fab")
		)
		(pad "1" smd roundrect
			(at -0.48 0 270)
			(size 0.59 0.64)
			(layers "B.Cu" "B.Mask" "B.Paste")
			(roundrect_rratio 0.25)
			(net 7 "+0V675_VTT")
			(pintype "passive")
		)
		(pad "2" smd roundrect
			(at 0.48 0 270)
			(size 0.59 0.64)
			(layers "B.Cu" "B.Mask" "B.Paste")
			(roundrect_rratio 0.25)
			(net 25 "+1V35")
			(pintype "passive")
		)
	)
	(footprint "antmicro-footprints:C_0402_1005Metric"
		(layer "B.Cu")
		(at 187.5 142 90)
		(descr "Capacitor SMD 0402")
		(tags "capacitor SMD 0402")
		(property "Reference" "C71"
			(at 1.075 -0.425 270)
			(layer "B.SilkS")
			(effects
				(font
					(size 0.7 0.7)
					(thickness 0.15)
				)
				(justify left bottom mirror)
			)
		)
		(property "Value" "C_100n_0402"
			(at 0 -1.169 270)
			(layer "B.Fab")
			(effects
				(font
					(size 0.7 0.7)
					(thickness 0.15)
				)
				(justify left bottom mirror)
			)
		)
		(property "Description" "SMD Multilayer Ceramic Capacitor, 0.1 µF, 50 V, 0402 [1005 Metric], ± 10%, X5R, GRM Series"
			(at 0 0 90)
			(layer "F.Fab")
			(hide yes)
			(effects
				(font
					(size 1.27 1.27)
					(thickness 0.15)
				)
			)
		)
		(property "Author" "Antmicro"
			(at 329.5 -45.5 0)
			(layer "B.Fab")
			(hide yes)
			(effects
				(font
					(size 1 1)
					(thickness 0.15)
				)
				(justify mirror)
			)
		)
		(property "Dielectric" "X5R"
			(at 329.5 -45.5 0)
			(layer "B.Fab")
			(hide yes)
			(effects
				(font
					(size 1 1)
					(thickness 0.15)
				)
				(justify mirror)
			)
		)
		(property "License" "Apache-2.0"
			(at 329.5 -45.5 0)
			(layer "B.Fab")
			(hide yes)
			(effects
				(font
					(size 1 1)
					(thickness 0.15)
				)
				(justify mirror)
			)
		)
		(property "MPN" "GRM155R61H104KE14D"
			(at 329.5 -45.5 0)
			(layer "B.Fab")
			(hide yes)
			(effects
				(font
					(size 1 1)
					(thickness 0.15)
				)
				(justify mirror)
			)
		)
		(property "Manufacturer" "Murata"
			(at 329.5 -45.5 0)
			(layer "B.Fab")
			(hide yes)
			(effects
				(font
					(size 1 1)
					(thickness 0.15)
				)
				(justify mirror)
			)
		)
		(property "Val" "100n"
			(at 329.5 -45.5 0)
			(layer "B.Fab")
			(hide yes)
			(effects
				(font
					(size 1 1)
					(thickness 0.15)
				)
				(justify mirror)
			)
		)
		(property "Voltage" "50V"
			(at 329.5 -45.5 0)
			(layer "B.Fab")
			(hide yes)
			(effects
				(font
					(size 1 1)
					(thickness 0.15)
				)
				(justify mirror)
			)
		)
		(sheetname "FPGA Bank 33 & 34")
		(sheetfile "fpga-bank-33-34.kicad_sch")
		(attr smd)
		(fp_rect
			(start -0.925 0.47)
			(end 0.925 -0.47)
			(stroke
				(width 0.05)
				(type default)
			)
			(fill no)
			(layer "B.CrtYd")
		)
		(fp_line
			(start 0.504 -0.248)
			(end -0.494 -0.248)
			(stroke
				(width 0.15)
				(type solid)
			)
			(layer "B.Fab")
		)
		(fp_line
			(start -0.494 -0.248)
			(end -0.494 0.25)
			(stroke
				(width 0.15)
				(type solid)
			)
			(layer "B.Fab")
		)
		(fp_line
			(start 0.504 0.25)
			(end 0.504 -0.248)
			(stroke
				(width 0.15)
				(type solid)
			)
			(layer "B.Fab")
		)
		(fp_line
			(start -0.494 0.25)
			(end 0.504 0.25)
			(stroke
				(width 0.15)
				(type solid)
			)
			(layer "B.Fab")
		)
		(pad "1" smd roundrect
			(at -0.48 0 90)
			(size 0.59 0.64)
			(layers "B.Cu" "B.Mask" "B.Paste")
			(roundrect_rratio 0.25)
			(net 1 "GND")
			(pintype "passive")
		)
		(pad "2" smd roundrect
			(at 0.48 0 90)
			(size 0.59 0.64)
			(layers "B.Cu" "B.Mask" "B.Paste")
			(roundrect_rratio 0.25)
			(net 25 "+1V35")
			(pintype "passive")
		)
	)
	(footprint "antmicro-footprints:R_0402_1005Metric"
		(layer "B.Cu")
		(at 222.1 146.2 -90)
		(descr "Resistor SMD 0402")
		(tags "resistor SMD 0402")
		(property "Reference" "R238"
			(at -3.625 -0.375 90)
			(layer "B.SilkS")
			(effects
				(font
					(size 0.7 0.7)
					(thickness 0.15)
				)
				(justify left bottom mirror)
			)
		)
		(property "Value" "R_10R_0402"
			(at 0 -1.4 90)
			(layer "B.Fab")
			(effects
				(font
					(size 0.7 0.7)
					(thickness 0.15)
				)
				(justify left bottom mirror)
			)
		)
		(property "Description" "SMD Chip Resistor, 10 ohm, ± 1%, 62.5 mW, 0402 [1005 Metric], Thick Film, General Purpose"
			(at 0 0 270)
			(layer "F.Fab")
			(hide yes)
			(effects
				(font
					(size 1.27 1.27)
					(thickness 0.15)
				)
			)
		)
		(property "Author" "Antmicro"
			(at 75.9 368.3 0)
			(layer "B.Fab")
			(hide yes)
			(effects
				(font
					(size 1 1)
					(thickness 0.15)
				)
				(justify mirror)
			)
		)
		(property "License" "Apache-2.0"
			(at 75.9 368.3 0)
			(layer "B.Fab")
			(hide yes)
			(effects
				(font
					(size 1 1)
					(thickness 0.15)
				)
				(justify mirror)
			)
		)
		(property "MPN" "CR0402-FX-10R0GLF"
			(at 75.9 368.3 0)
			(layer "B.Fab")
			(hide yes)
			(effects
				(font
					(size 1 1)
					(thickness 0.15)
				)
				(justify mirror)
			)
		)
		(property "Manufacturer" "Bourns"
			(at 75.9 368.3 0)
			(layer "B.Fab")
			(hide yes)
			(effects
				(font
					(size 1 1)
					(thickness 0.15)
				)
				(justify mirror)
			)
		)
		(property "Tolerance" "1%"
			(at 75.9 368.3 0)
			(layer "B.Fab")
			(hide yes)
			(effects
				(font
					(size 1 1)
					(thickness 0.15)
				)
				(justify mirror)
			)
		)
		(property "Val" "10R"
			(at 75.9 368.3 0)
			(layer "B.Fab")
			(hide yes)
			(effects
				(font
					(size 1 1)
					(thickness 0.15)
				)
				(justify mirror)
			)
		)
		(sheetname "HDMI + Ethernet")
		(sheetfile "hdmi-ethernet.kicad_sch")
		(attr smd)
		(fp_rect
			(start -0.925 0.47)
			(end 0.925 -0.47)
			(stroke
				(width 0.05)
				(type default)
			)
			(fill no)
			(layer "B.CrtYd")
		)
		(fp_rect
			(start -0.5 0.25)
			(end 0.5 -0.25)
			(stroke
				(width 0.15)
				(type solid)
			)
			(fill no)
			(layer "B.Fab")
		)
		(pad "1" smd roundrect
			(at -0.48 0 270)
			(size 0.59 0.64)
			(layers "B.Cu" "B.Mask" "B.Paste")
			(roundrect_rratio 0.25)
			(net 521 "/FPGA Bank 18 & 32/ETH_RMII.RXER")
			(pintype "passive")
		)
		(pad "2" smd roundrect
			(at 0.48 0 270)
			(size 0.59 0.64)
			(layers "B.Cu" "B.Mask" "B.Paste")
			(roundrect_rratio 0.25)
			(net 947 "/HDMI + Ethernet/ETH_PHY_RXER")
			(pintype "passive")
		)
	)
	(footprint "antmicro-footprints:R_0402_1005Metric"
		(layer "B.Cu")
		(at 175.33 176.2 180)
		(descr "Resistor SMD 0402")
		(tags "resistor SMD 0402")
		(property "Reference" "R280"
			(at -1.37 -2.35 0)
			(layer "B.SilkS")
			(effects
				(font
					(size 0.7 0.7)
					(thickness 0.15)
				)
				(justify left bottom mirror)
			)
		)
		(property "Value" "R_0R_0402"
			(at 0 -1.4 0)
			(layer "B.Fab")
			(effects
				(font
					(size 0.7 0.7)
					(thickness 0.15)
				)
				(justify left bottom mirror)
			)
		)
		(property "Description" "SMD Chip Resistor, Jumper, 0 ohm, 100 mW, 0402 [1005 Metric], Thick Film, General Purpose"
			(at 0 0 180)
			(layer "F.Fab")
			(hide yes)
			(effects
				(font
					(size 1.27 1.27)
					(thickness 0.15)
				)
			)
		)
		(property "Author" "Antmicro"
			(at 350.66 352.4 0)
			(layer "B.Fab")
			(hide yes)
			(effects
				(font
					(size 1 1)
					(thickness 0.15)
				)
				(justify mirror)
			)
		)
		(property "Current" "1A"
			(at 350.66 352.4 0)
			(layer "B.Fab")
			(hide yes)
			(effects
				(font
					(size 1 1)
					(thickness 0.15)
				)
				(justify mirror)
			)
		)
		(property "License" "Apache-2.0"
			(at 350.66 352.4 0)
			(layer "B.Fab")
			(hide yes)
			(effects
				(font
					(size 1 1)
					(thickness 0.15)
				)
				(justify mirror)
			)
		)
		(property "MPN" "ERJ2GE0R00X"
			(at 350.66 352.4 0)
			(layer "B.Fab")
			(hide yes)
			(effects
				(font
					(size 1 1)
					(thickness 0.15)
				)
				(justify mirror)
			)
		)
		(property "Manufacturer" "Panasonic"
			(at 350.66 352.4 0)
			(layer "B.Fab")
			(hide yes)
			(effects
				(font
					(size 1 1)
					(thickness 0.15)
				)
				(justify mirror)
			)
		)
		(property "Tolerance" ""
			(at 350.66 352.4 0)
			(layer "B.Fab")
			(hide yes)
			(effects
				(font
					(size 1 1)
					(thickness 0.15)
				)
				(justify mirror)
			)
		)
		(property "Val" "0R"
			(at 350.66 352.4 0)
			(layer "B.Fab")
			(hide yes)
			(effects
				(font
					(size 1 1)
					(thickness 0.15)
				)
				(justify mirror)
			)
		)
		(sheetname "DC-DC Converters")
		(sheetfile "dc-dc.kicad_sch")
		(attr smd)
		(fp_rect
			(start -0.925 0.47)
			(end 0.925 -0.47)
			(stroke
				(width 0.05)
				(type default)
			)
			(fill no)
			(layer "B.CrtYd")
		)
		(fp_rect
			(start -0.5 0.25)
			(end 0.5 -0.25)
			(stroke
				(width 0.15)
				(type solid)
			)
			(fill no)
			(layer "B.Fab")
		)
		(pad "1" smd roundrect
			(at -0.48 0 180)
			(size 0.59 0.64)
			(layers "B.Cu" "B.Mask" "B.Paste")
			(roundrect_rratio 0.25)
			(net 1387 "/SUP_MCU.PG_3V3")
			(pintype "passive")
		)
		(pad "2" smd roundrect
			(at 0.48 0 180)
			(size 0.59 0.64)
			(layers "B.Cu" "B.Mask" "B.Paste")
			(roundrect_rratio 0.25)
			(net 954 "/DC-DC Converters/QDCDC2_GPIO")
			(pintype "passive")
		)
	)
	(footprint "antmicro-footprints:LED_0603_1608Metric_B"
		(layer "B.Cu")
		(at 268.301 148.3 180)
		(descr "LED SMD 0603 Blue")
		(tags "LED SMD 0603 Blue")
		(property "Reference" "D11"
			(at 4.051 -0.35 0)
			(layer "B.SilkS")
			(effects
				(font
					(size 0.7 0.7)
					(thickness 0.15)
				)
				(justify left bottom mirror)
			)
		)
		(property "Value" "LED_B_0603_KP-1608QBC-D"
			(at 0 -1.6 0)
			(layer "B.Fab")
			(effects
				(font
					(size 0.7 0.7)
					(thickness 0.15)
				)
				(justify left bottom mirror)
			)
		)
		(property "Description" "LED, Blue, SMD, 0603, 20 mA, 3.3 V, 465 nm"
			(at 0 0 180)
			(layer "F.Fab")
			(hide yes)
			(effects
				(font
					(size 1.27 1.27)
					(thickness 0.15)
				)
			)
		)
		(property "Author" "Antmicro"
			(at 536.602 296.6 0)
			(layer "B.Fab")
			(hide yes)
			(effects
				(font
					(size 1 1)
					(thickness 0.15)
				)
				(justify mirror)
			)
		)
		(property "Color" "Blue"
			(at 536.602 296.6 0)
			(layer "B.Fab")
			(hide yes)
			(effects
				(font
					(size 1 1)
					(thickness 0.15)
				)
				(justify mirror)
			)
		)
		(property "License" "Apache-2.0"
			(at 536.602 296.6 0)
			(layer "B.Fab")
			(hide yes)
			(effects
				(font
					(size 1 1)
					(thickness 0.15)
				)
				(justify mirror)
			)
		)
		(property "MPN" "KP-1608QBC-D"
			(at 536.602 296.6 0)
			(layer "B.Fab")
			(hide yes)
			(effects
				(font
					(size 1 1)
					(thickness 0.15)
				)
				(justify mirror)
			)
		)
		(property "Manufacturer" "Kingbright"
			(at 536.602 296.6 0)
			(layer "B.Fab")
			(hide yes)
			(effects
				(font
					(size 1 1)
					(thickness 0.15)
				)
				(justify mirror)
			)
		)
		(property "Public" "False"
			(at 536.602 296.6 0)
			(layer "B.Fab")
			(hide yes)
			(effects
				(font
					(size 1 1)
					(thickness 0.15)
				)
				(justify mirror)
			)
		)
		(sheetname "Power supply")
		(sheetfile "power-supply.kicad_sch")
		(attr smd)
		(fp_line
			(start 0.22 0.35)
			(end -0.22 0.35)
			(stroke
				(width 0.15)
				(type solid)
			)
			(layer "B.SilkS")
		)
		(fp_line
			(start 0.22 -0.35)
			(end -0.22 -0.35)
			(stroke
				(width 0.15)
				(type solid)
			)
			(layer "B.SilkS")
		)
		(fp_line
			(start 0.105328 -0.001008)
			(end 0.24 -0.001)
			(stroke
				(width 0.1)
				(type solid)
			)
			(layer "B.SilkS")
		)
		(fp_line
			(start 0.105328 -0.201008)
			(end 0.105328 0.198992)
			(stroke
				(width 0.1)
				(type solid)
			)
			(layer "B.SilkS")
		)
		(fp_line
			(start 0.105328 -0.201008)
			(end -0.094672 -0.001008)
			(stroke
				(width 0.1)
				(type solid)
			)
			(layer "B.SilkS")
		)
		(fp_line
			(start -0.094672 -0.001008)
			(end 0.105328 0.198992)
			(stroke
				(width 0.1)
				(type solid)
			)
			(layer "B.SilkS")
		)
		(fp_line
			(start -0.094672 -0.001008)
			(end -0.24 -0.001008)
			(stroke
				(width 0.1)
				(type solid)
			)
			(layer "B.SilkS")
		)
		(fp_line
			(start -0.094672 -0.201008)
			(end -0.094672 0.198992)
			(stroke
				(width 0.1)
				(type solid)
			)
			(layer "B.SilkS")
		)
		(fp_line
			(start -1.18 0.319)
			(end -1.18 -0.321)
			(stroke
				(width 0.15)
				(type solid)
			)
			(layer "B.SilkS")
		)
		(fp_rect
			(start 1.25 -0.65)
			(end -1.25 0.65)
			(stroke
				(width 0.05)
				(type solid)
			)
			(fill no)
			(layer "B.CrtYd")
		)
		(fp_line
			(start 0.599 0)
			(end 0.201 0)
			(stroke
				(width 0.15)
				(type solid)
			)
			(layer "B.Fab")
		)
		(fp_line
			(start 0.201 0.202)
			(end -0.101 0)
			(stroke
				(width 0.15)
				(type solid)
			)
			(layer "B.Fab")
		)
		(fp_line
			(start 0.201 0)
			(end 0.201 0.202)
			(stroke
				(width 0.15)
				(type solid)
			)
			(layer "B.Fab")
		)
		(fp_line
			(start 0.201 -0.2)
			(end 0.201 0)
			(stroke
				(width 0.15)
				(type solid)
			)
			(layer "B.Fab")
		)
		(fp_line
			(start -0.101 0)
			(end 0.201 -0.2)
			(stroke
				(width 0.15)
				(type solid)
			)
			(layer "B.Fab")
		)
		(fp_line
			(start -0.199 0.202)
			(end -0.199 -0.1)
			(stroke
				(width 0.15)
				(type solid)
			)
			(layer "B.Fab")
		)
		(fp_line
			(start -0.199 0)
			(end -0.597 0)
			(stroke
				(width 0.15)
				(type solid)
			)
			(layer "B.Fab")
		)
		(fp_line
			(start -0.199 -0.2)
			(end -0.199 -0.1)
			(stroke
				(width 0.15)
				(type solid)
			)
			(layer "B.Fab")
		)
		(fp_rect
			(start 0.848 -0.4)
			(end -0.85 0.402)
			(stroke
				(width 0.15)
				(type solid)
			)
			(fill no)
			(layer "B.Fab")
		)
		(pad "1" smd roundrect
			(at -0.7 0)
			(size 0.8 1)
			(layers "B.Cu" "B.Mask" "B.Paste")
			(roundrect_rratio 0.2)
			(net 769 "/Power supply/PD_PWR_OK2")
			(pinfunction "C")
			(pintype "passive")
		)
		(pad "2" smd roundrect
			(at 0.7 0)
			(size 0.8 1)
			(layers "B.Cu" "B.Mask" "B.Paste")
			(roundrect_rratio 0.2)
			(net 19 "Net-(D11-A)")
			(pinfunction "A")
			(pintype "passive")
		)
	)
	(footprint "antmicro-footprints:C_0402_1005Metric"
		(layer "B.Cu")
		(at 202.5 144 90)
		(descr "Capacitor SMD 0402")
		(tags "capacitor SMD 0402")
		(property "Reference" "C89"
			(at 1.15 1.2 270)
			(layer "B.SilkS")
			(effects
				(font
					(size 0.7 0.7)
					(thickness 0.15)
				)
				(justify left bottom mirror)
			)
		)
		(property "Value" "C_100n_0402"
			(at 0 -1.169 270)
			(layer "B.Fab")
			(effects
				(font
					(size 0.7 0.7)
					(thickness 0.15)
				)
				(justify left bottom mirror)
			)
		)
		(property "Description" "SMD Multilayer Ceramic Capacitor, 0.1 µF, 50 V, 0402 [1005 Metric], ± 10%, X5R, GRM Series"
			(at 0 0 90)
			(layer "F.Fab")
			(hide yes)
			(effects
				(font
					(size 1.27 1.27)
					(thickness 0.15)
				)
			)
		)
		(property "Author" "Antmicro"
			(at 346.5 -58.5 0)
			(layer "B.Fab")
			(hide yes)
			(effects
				(font
					(size 1 1)
					(thickness 0.15)
				)
				(justify mirror)
			)
		)
		(property "Dielectric" "X5R"
			(at 346.5 -58.5 0)
			(layer "B.Fab")
			(hide yes)
			(effects
				(font
					(size 1 1)
					(thickness 0.15)
				)
				(justify mirror)
			)
		)
		(property "License" "Apache-2.0"
			(at 346.5 -58.5 0)
			(layer "B.Fab")
			(hide yes)
			(effects
				(font
					(size 1 1)
					(thickness 0.15)
				)
				(justify mirror)
			)
		)
		(property "MPN" "GRM155R61H104KE14D"
			(at 346.5 -58.5 0)
			(layer "B.Fab")
			(hide yes)
			(effects
				(font
					(size 1 1)
					(thickness 0.15)
				)
				(justify mirror)
			)
		)
		(property "Manufacturer" "Murata"
			(at 346.5 -58.5 0)
			(layer "B.Fab")
			(hide yes)
			(effects
				(font
					(size 1 1)
					(thickness 0.15)
				)
				(justify mirror)
			)
		)
		(property "Val" "100n"
			(at 346.5 -58.5 0)
			(layer "B.Fab")
			(hide yes)
			(effects
				(font
					(size 1 1)
					(thickness 0.15)
				)
				(justify mirror)
			)
		)
		(property "Voltage" "50V"
			(at 346.5 -58.5 0)
			(layer "B.Fab")
			(hide yes)
			(effects
				(font
					(size 1 1)
					(thickness 0.15)
				)
				(justify mirror)
			)
		)
		(sheetname "FPGA Bank 18 & 32")
		(sheetfile "fpga-bank-18-32.kicad_sch")
		(attr smd)
		(fp_rect
			(start -0.925 0.47)
			(end 0.925 -0.47)
			(stroke
				(width 0.05)
				(type default)
			)
			(fill no)
			(layer "B.CrtYd")
		)
		(fp_line
			(start 0.504 -0.248)
			(end -0.494 -0.248)
			(stroke
				(width 0.15)
				(type solid)
			)
			(layer "B.Fab")
		)
		(fp_line
			(start -0.494 -0.248)
			(end -0.494 0.25)
			(stroke
				(width 0.15)
				(type solid)
			)
			(layer "B.Fab")
		)
		(fp_line
			(start 0.504 0.25)
			(end 0.504 -0.248)
			(stroke
				(width 0.15)
				(type solid)
			)
			(layer "B.Fab")
		)
		(fp_line
			(start -0.494 0.25)
			(end 0.504 0.25)
			(stroke
				(width 0.15)
				(type solid)
			)
			(layer "B.Fab")
		)
		(pad "1" smd roundrect
			(at -0.48 0 90)
			(size 0.59 0.64)
			(layers "B.Cu" "B.Mask" "B.Paste")
			(roundrect_rratio 0.25)
			(net 1 "GND")
			(pintype "passive")
		)
		(pad "2" smd roundrect
			(at 0.48 0 90)
			(size 0.59 0.64)
			(layers "B.Cu" "B.Mask" "B.Paste")
			(roundrect_rratio 0.25)
			(net 26 "+1V8")
			(pintype "passive")
		)
	)
	(footprint "antmicro-footprints:R_0402_1005Metric"
		(layer "B.Cu")
		(at 163.900001 90.760001)
		(descr "Resistor SMD 0402")
		(tags "resistor SMD 0402")
		(property "Reference" "R265"
			(at -0.775001 0.389999 180)
			(layer "B.SilkS")
			(effects
				(font
					(size 0.7 0.7)
					(thickness 0.15)
				)
				(justify left bottom mirror)
			)
		)
		(property "Value" "R_10k_0402"
			(at 0 -1.4 180)
			(layer "B.Fab")
			(effects
				(font
					(size 0.7 0.7)
					(thickness 0.15)
				)
				(justify left bottom mirror)
			)
		)
		(property "Description" "SMD Chip Resistor, 10 kohm, ± 1%, 62.5 mW, 0402 [1005 Metric], Thick Film, General Purpose"
			(at 0 0 0)
			(layer "F.Fab")
			(hide yes)
			(effects
				(font
					(size 1.27 1.27)
					(thickness 0.15)
				)
			)
		)
		(property "Author" "Antmicro"
			(at 0 0 0)
			(layer "B.Fab")
			(hide yes)
			(effects
				(font
					(size 1 1)
					(thickness 0.15)
				)
				(justify mirror)
			)
		)
		(property "License" "Apache-2.0"
			(at 0 0 0)
			(layer "B.Fab")
			(hide yes)
			(effects
				(font
					(size 1 1)
					(thickness 0.15)
				)
				(justify mirror)
			)
		)
		(property "MPN" "CR0402-FX-1002GLF"
			(at 0 0 0)
			(layer "B.Fab")
			(hide yes)
			(effects
				(font
					(size 1 1)
					(thickness 0.15)
				)
				(justify mirror)
			)
		)
		(property "Manufacturer" "Bourns"
			(at 0 0 0)
			(layer "B.Fab")
			(hide yes)
			(effects
				(font
					(size 1 1)
					(thickness 0.15)
				)
				(justify mirror)
			)
		)
		(property "Tolerance" "1%"
			(at 0 0 0)
			(layer "B.Fab")
			(hide yes)
			(effects
				(font
					(size 1 1)
					(thickness 0.15)
				)
				(justify mirror)
			)
		)
		(property "Val" "10k"
			(at 0 0 0)
			(layer "B.Fab")
			(hide yes)
			(effects
				(font
					(size 1 1)
					(thickness 0.15)
				)
				(justify mirror)
			)
		)
		(sheetname "FMC+ HSPC")
		(sheetfile "fmc-hspc.kicad_sch")
		(attr smd)
		(fp_rect
			(start -0.925 0.47)
			(end 0.925 -0.47)
			(stroke
				(width 0.05)
				(type default)
			)
			(fill no)
			(layer "B.CrtYd")
		)
		(fp_rect
			(start -0.5 0.25)
			(end 0.5 -0.25)
			(stroke
				(width 0.15)
				(type solid)
			)
			(fill no)
			(layer "B.Fab")
		)
		(pad "1" smd roundrect
			(at -0.48 0)
			(size 0.59 0.64)
			(layers "B.Cu" "B.Mask" "B.Paste")
			(roundrect_rratio 0.25)
			(net 695 "/FMC+ HSPC/FMC.~{PERST}")
			(pintype "passive")
		)
		(pad "2" smd roundrect
			(at 0.48 0)
			(size 0.59 0.64)
			(layers "B.Cu" "B.Mask" "B.Paste")
			(roundrect_rratio 0.25)
			(net 24 "+3V3")
			(pintype "passive")
		)
	)
	(footprint "antmicro-footprints:C_0402_1005Metric"
		(layer "B.Cu")
		(at 197 124.5 180)
		(descr "Capacitor SMD 0402")
		(tags "capacitor SMD 0402")
		(property "Reference" "C68"
			(at -25.1 29.6 0)
			(layer "B.SilkS")
			(effects
				(font
					(size 0.7 0.7)
					(thickness 0.15)
				)
				(justify left bottom mirror)
			)
		)
		(property "Value" "C_100n_0402"
			(at 0 -1.169 0)
			(layer "B.Fab")
			(effects
				(font
					(size 0.7 0.7)
					(thickness 0.15)
				)
				(justify left bottom mirror)
			)
		)
		(property "Description" "SMD Multilayer Ceramic Capacitor, 0.1 µF, 50 V, 0402 [1005 Metric], ± 10%, X5R, GRM Series"
			(at 0 0 180)
			(layer "F.Fab")
			(hide yes)
			(effects
				(font
					(size 1.27 1.27)
					(thickness 0.15)
				)
			)
		)
		(property "Author" "Antmicro"
			(at 394 249 0)
			(layer "B.Fab")
			(hide yes)
			(effects
				(font
					(size 1 1)
					(thickness 0.15)
				)
				(justify mirror)
			)
		)
		(property "Dielectric" "X5R"
			(at 394 249 0)
			(layer "B.Fab")
			(hide yes)
			(effects
				(font
					(size 1 1)
					(thickness 0.15)
				)
				(justify mirror)
			)
		)
		(property "License" "Apache-2.0"
			(at 394 249 0)
			(layer "B.Fab")
			(hide yes)
			(effects
				(font
					(size 1 1)
					(thickness 0.15)
				)
				(justify mirror)
			)
		)
		(property "MPN" "GRM155R61H104KE14D"
			(at 394 249 0)
			(layer "B.Fab")
			(hide yes)
			(effects
				(font
					(size 1 1)
					(thickness 0.15)
				)
				(justify mirror)
			)
		)
		(property "Manufacturer" "Murata"
			(at 394 249 0)
			(layer "B.Fab")
			(hide yes)
			(effects
				(font
					(size 1 1)
					(thickness 0.15)
				)
				(justify mirror)
			)
		)
		(property "Val" "100n"
			(at 394 249 0)
			(layer "B.Fab")
			(hide yes)
			(effects
				(font
					(size 1 1)
					(thickness 0.15)
				)
				(justify mirror)
			)
		)
		(property "Voltage" "50V"
			(at 394 249 0)
			(layer "B.Fab")
			(hide yes)
			(effects
				(font
					(size 1 1)
					(thickness 0.15)
				)
				(justify mirror)
			)
		)
		(sheetname "FPGA Bank 18 & 32")
		(sheetfile "fpga-bank-18-32.kicad_sch")
		(attr smd)
		(fp_rect
			(start -0.925 0.47)
			(end 0.925 -0.47)
			(stroke
				(width 0.05)
				(type default)
			)
			(fill no)
			(layer "B.CrtYd")
		)
		(fp_line
			(start 0.504 0.25)
			(end 0.504 -0.248)
			(stroke
				(width 0.15)
				(type solid)
			)
			(layer "B.Fab")
		)
		(fp_line
			(start 0.504 -0.248)
			(end -0.494 -0.248)
			(stroke
				(width 0.15)
				(type solid)
			)
			(layer "B.Fab")
		)
		(fp_line
			(start -0.494 0.25)
			(end 0.504 0.25)
			(stroke
				(width 0.15)
				(type solid)
			)
			(layer "B.Fab")
		)
		(fp_line
			(start -0.494 -0.248)
			(end -0.494 0.25)
			(stroke
				(width 0.15)
				(type solid)
			)
			(layer "B.Fab")
		)
		(pad "1" smd roundrect
			(at -0.48 0 180)
			(size 0.59 0.64)
			(layers "B.Cu" "B.Mask" "B.Paste")
			(roundrect_rratio 0.25)
			(net 1 "GND")
			(pintype "passive")
		)
		(pad "2" smd roundrect
			(at 0.48 0 180)
			(size 0.59 0.64)
			(layers "B.Cu" "B.Mask" "B.Paste")
			(roundrect_rratio 0.25)
			(net 24 "+3V3")
			(pintype "passive")
		)
	)
	(footprint "antmicro-footprints:R_0402_1005Metric"
		(layer "B.Cu")
		(at 254.801 170.9 -90)
		(descr "Resistor SMD 0402")
		(tags "resistor SMD 0402")
		(property "Reference" "R39"
			(at -2.95 -0.074 90)
			(layer "B.SilkS")
			(effects
				(font
					(size 0.7 0.7)
					(thickness 0.15)
				)
				(justify left bottom mirror)
			)
		)
		(property "Value" "R_0R_0402"
			(at 0 -1.4 90)
			(layer "B.Fab")
			(effects
				(font
					(size 0.7 0.7)
					(thickness 0.15)
				)
				(justify left bottom mirror)
			)
		)
		(property "Description" "SMD Chip Resistor, Jumper, 0 ohm, 100 mW, 0402 [1005 Metric], Thick Film, General Purpose"
			(at 0 0 270)
			(layer "F.Fab")
			(hide yes)
			(effects
				(font
					(size 1.27 1.27)
					(thickness 0.15)
				)
			)
		)
		(property "Author" "Antmicro"
			(at 83.901 425.701 0)
			(layer "B.Fab")
			(hide yes)
			(effects
				(font
					(size 1 1)
					(thickness 0.15)
				)
				(justify mirror)
			)
		)
		(property "Current" "1A"
			(at 83.901 425.701 0)
			(layer "B.Fab")
			(hide yes)
			(effects
				(font
					(size 1 1)
					(thickness 0.15)
				)
				(justify mirror)
			)
		)
		(property "DNP" "DNP"
			(at 83.901 425.701 0)
			(layer "B.Fab")
			(hide yes)
			(effects
				(font
					(size 1 1)
					(thickness 0.15)
				)
				(justify mirror)
			)
		)
		(property "License" "Apache-2.0"
			(at 83.901 425.701 0)
			(layer "B.Fab")
			(hide yes)
			(effects
				(font
					(size 1 1)
					(thickness 0.15)
				)
				(justify mirror)
			)
		)
		(property "MPN" "ERJ2GE0R00X"
			(at 83.901 425.701 0)
			(layer "B.Fab")
			(hide yes)
			(effects
				(font
					(size 1 1)
					(thickness 0.15)
				)
				(justify mirror)
			)
		)
		(property "Manufacturer" "Panasonic"
			(at 83.901 425.701 0)
			(layer "B.Fab")
			(hide yes)
			(effects
				(font
					(size 1 1)
					(thickness 0.15)
				)
				(justify mirror)
			)
		)
		(property "Tolerance" ""
			(at 83.901 425.701 0)
			(layer "B.Fab")
			(hide yes)
			(effects
				(font
					(size 1 1)
					(thickness 0.15)
				)
				(justify mirror)
			)
		)
		(property "Val" "0R"
			(at 83.901 425.701 0)
			(layer "B.Fab")
			(hide yes)
			(effects
				(font
					(size 1 1)
					(thickness 0.15)
				)
				(justify mirror)
			)
		)
		(property "dnp" ""
			(at 83.901 425.701 0)
			(layer "B.Fab")
			(hide yes)
			(effects
				(font
					(size 1 1)
					(thickness 0.15)
				)
				(justify mirror)
			)
		)
		(property "exclude_from_bom" ""
			(at 83.901 425.701 0)
			(layer "B.Fab")
			(hide yes)
			(effects
				(font
					(size 1 1)
					(thickness 0.15)
				)
				(justify mirror)
			)
		)
		(sheetname "Power supply")
		(sheetfile "power-supply.kicad_sch")
		(attr smd exclude_from_bom)
		(fp_rect
			(start -0.925 0.47)
			(end 0.925 -0.47)
			(stroke
				(width 0.05)
				(type default)
			)
			(fill no)
			(layer "B.CrtYd")
		)
		(fp_rect
			(start -0.5 0.25)
			(end 0.5 -0.25)
			(stroke
				(width 0.15)
				(type solid)
			)
			(fill no)
			(layer "B.Fab")
		)
		(pad "1" smd roundrect
			(at -0.48 0 270)
			(size 0.59 0.64)
			(layers "B.Cu" "B.Mask" "B.Paste")
			(roundrect_rratio 0.25)
			(net 889 "/Power supply/PG")
			(pintype "passive")
		)
		(pad "2" smd roundrect
			(at 0.48 0 270)
			(size 0.59 0.64)
			(layers "B.Cu" "B.Mask" "B.Paste")
			(roundrect_rratio 0.25)
			(net 798 "/Power supply/POE_ACTIVE")
			(pintype "passive")
		)
	)
	(footprint "antmicro-footprints:C_0201"
		(layer "B.Cu")
		(at 186.730001 117.730001 -45)
		(descr "Capacitor SMD 0201")
		(tags "capacitor SMD 0201")
		(property "Reference" "C163"
			(at -0.625791 0.901561 180)
			(layer "B.SilkS")
			(effects
				(font
					(size 0.7 0.7)
					(thickness 0.15)
				)
				(justify left bottom mirror)
			)
		)
		(property "Value" "C_4u7_0201"
			(at 0 -1.399999 135)
			(layer "B.Fab")
			(effects
				(font
					(size 0.7 0.7)
					(thickness 0.15)
				)
				(justify left bottom mirror)
			)
		)
		(property "Description" "SMD Multilayer Ceramic Capacitor, 4.7 µF, 6.3 V, 0201 [0603 Metric], ± 20%, X5R, GRM Series"
			(at 0 0 315)
			(layer "F.Fab")
			(hide yes)
			(effects
				(font
					(size 1.27 1.27)
					(thickness 0.15)
				)
			)
		)
		(property "Author" "Antmicro"
			(at -28.555731 166.520369 0)
			(layer "B.Fab")
			(hide yes)
			(effects
				(font
					(size 1 1)
					(thickness 0.15)
				)
				(justify mirror)
			)
		)
		(property "Dielectric" ""
			(at -28.555731 166.520369 0)
			(layer "B.Fab")
			(hide yes)
			(effects
				(font
					(size 1 1)
					(thickness 0.15)
				)
				(justify mirror)
			)
		)
		(property "License" "Apache-2.0"
			(at -28.555731 166.520369 0)
			(layer "B.Fab")
			(hide yes)
			(effects
				(font
					(size 1 1)
					(thickness 0.15)
				)
				(justify mirror)
			)
		)
		(property "MPN" "GRM035R60J475ME15D"
			(at -28.555731 166.520369 0)
			(layer "B.Fab")
			(hide yes)
			(effects
				(font
					(size 1 1)
					(thickness 0.15)
				)
				(justify mirror)
			)
		)
		(property "Manufacturer" "Murata"
			(at -28.555731 166.520369 0)
			(layer "B.Fab")
			(hide yes)
			(effects
				(font
					(size 1 1)
					(thickness 0.15)
				)
				(justify mirror)
			)
		)
		(property "Val" "4u7"
			(at -28.555731 166.520369 0)
			(layer "B.Fab")
			(hide yes)
			(effects
				(font
					(size 1 1)
					(thickness 0.15)
				)
				(justify mirror)
			)
		)
		(property "Voltage" ""
			(at -28.555731 166.520369 0)
			(layer "B.Fab")
			(hide yes)
			(effects
				(font
					(size 1 1)
					(thickness 0.15)
				)
				(justify mirror)
			)
		)
		(sheetname "FPGA supply")
		(sheetfile "fpga-supply.kicad_sch")
		(attr smd)
		(fp_poly
			(pts
				(xy -0.7 0.35) (xy 0.7 0.35) (xy 0.7 -0.35) (xy -0.7 -0.35)
			)
			(stroke
				(width 0.05)
				(type default)
			)
			(fill no)
			(layer "B.CrtYd")
		)
		(fp_poly
			(pts
				(xy 0.3 -0.15) (xy -0.301 -0.15) (xy -0.301 0.149) (xy 0.3 0.149)
			)
			(stroke
				(width 0.15)
				(type solid)
			)
			(fill no)
			(layer "B.Fab")
		)
		(pad "" smd roundrect
			(at -0.349 0.002 315)
			(size 0.318 0.36)
			(layers "B.Paste")
			(roundrect_rratio 0.25)
		)
		(pad "" smd roundrect
			(at 0.341 0.002 315)
			(size 0.318 0.36)
			(layers "B.Paste")
			(roundrect_rratio 0.25)
		)
		(pad "1" smd roundrect
			(at -0.321 0.002 315)
			(size 0.46 0.4)
			(layers "B.Cu" "B.Mask")
			(roundrect_rratio 0.25)
			(net 1 "GND")
			(pintype "passive")
		)
		(pad "2" smd roundrect
			(at 0.32 0.002 315)
			(size 0.46 0.4)
			(layers "B.Cu" "B.Mask")
			(roundrect_rratio 0.25)
			(net 8 "+1V2_MGTAVTT")
			(pintype "passive")
		)
	)
	(footprint "antmicro-footprints:NetTie-2_SMD_Pad0.127mm"
		(layer "B.Cu")
		(at 249.701 148.4 90)
		(descr "Net tie, 2 pin, 0.127mm  SMD pads")
		(tags "net tie")
		(property "Reference" "NT8"
			(at -0.128 1.345 270)
			(layer "B.SilkS")
			(hide yes)
			(effects
				(font
					(size 0.7 0.7)
					(thickness 0.15)
				)
				(justify left bottom mirror)
			)
		)
		(property "Value" "Net-Tie_2"
			(at 0 -1.199 270)
			(layer "B.Fab")
			(effects
				(font
					(size 0.7 0.7)
					(thickness 0.15)
				)
				(justify left bottom mirror)
			)
		)
		(property "Description" "Net tie, 2 pins"
			(at 0 0 90)
			(layer "F.Fab")
			(hide yes)
			(effects
				(font
					(size 1.27 1.27)
					(thickness 0.15)
				)
			)
		)
		(property "Author" "Antmicro"
			(at 398.101 -101.301 0)
			(layer "B.Fab")
			(hide yes)
			(effects
				(font
					(size 1 1)
					(thickness 0.15)
				)
				(justify mirror)
			)
		)
		(property "License" "Apache-2.0"
			(at 398.101 -101.301 0)
			(layer "B.Fab")
			(hide yes)
			(effects
				(font
					(size 1 1)
					(thickness 0.15)
				)
				(justify mirror)
			)
		)
		(property "MPN" ""
			(at 398.101 -101.301 0)
			(layer "B.Fab")
			(hide yes)
			(effects
				(font
					(size 1 1)
					(thickness 0.15)
				)
				(justify mirror)
			)
		)
		(property "Manufacturer" ""
			(at 398.101 -101.301 0)
			(layer "B.Fab")
			(hide yes)
			(effects
				(font
					(size 1 1)
					(thickness 0.15)
				)
				(justify mirror)
			)
		)
		(sheetname "FPGA Config")
		(sheetfile "fpga-config.kicad_sch")
		(attr exclude_from_pos_files)
		(net_tie_pad_groups "1, 2")
		(fp_poly
			(pts
				(xy -0.0635 0.0635) (xy 0.0625 0.0635) (xy 0.0625 -0.0635) (xy -0.0635 -0.0635)
			)
			(stroke
				(width 0)
				(type solid)
			)
			(fill yes)
			(layer "B.Cu")
		)
		(pad "1" smd roundrect
			(at -0.127 0 270)
			(size 0.127 0.127)
			(layers "B.Cu")
			(roundrect_rratio 0.5)
			(chamfer_ratio 0)
			(chamfer top_left bottom_left)
			(net 1317 "/SUP_MCU.PROGRAMB")
			(pinfunction "1")
			(pintype "passive")
		)
		(pad "2" smd roundrect
			(at 0.126 0 90)
			(size 0.127 0.127)
			(layers "B.Cu")
			(roundrect_rratio 0.5)
			(chamfer_ratio 0)
			(chamfer top_left bottom_left)
			(net 301 "/FPGA Config/PROGRAM_B")
			(pinfunction "2")
			(pintype "passive")
		)
	)
	(footprint "antmicro-footprints:C_0402_1005Metric"
		(layer "B.Cu")
		(at 206 139.5 180)
		(descr "Capacitor SMD 0402")
		(tags "capacitor SMD 0402")
		(property "Reference" "C29"
			(at -1.05 0.45 0)
			(layer "B.SilkS")
			(effects
				(font
					(size 0.7 0.7)
					(thickness 0.15)
				)
				(justify left bottom mirror)
			)
		)
		(property "Value" "C_100n_0402"
			(at 0 -1.169 0)
			(layer "B.Fab")
			(effects
				(font
					(size 0.7 0.7)
					(thickness 0.15)
				)
				(justify left bottom mirror)
			)
		)
		(property "Description" "SMD Multilayer Ceramic Capacitor, 0.1 µF, 50 V, 0402 [1005 Metric], ± 10%, X5R, GRM Series"
			(at 0 0 180)
			(layer "F.Fab")
			(hide yes)
			(effects
				(font
					(size 1.27 1.27)
					(thickness 0.15)
				)
			)
		)
		(property "Author" "Antmicro"
			(at 412 279 0)
			(layer "B.Fab")
			(hide yes)
			(effects
				(font
					(size 1 1)
					(thickness 0.15)
				)
				(justify mirror)
			)
		)
		(property "Dielectric" "X5R"
			(at 412 279 0)
			(layer "B.Fab")
			(hide yes)
			(effects
				(font
					(size 1 1)
					(thickness 0.15)
				)
				(justify mirror)
			)
		)
		(property "License" "Apache-2.0"
			(at 412 279 0)
			(layer "B.Fab")
			(hide yes)
			(effects
				(font
					(size 1 1)
					(thickness 0.15)
				)
				(justify mirror)
			)
		)
		(property "MPN" "GRM155R61H104KE14D"
			(at 412 279 0)
			(layer "B.Fab")
			(hide yes)
			(effects
				(font
					(size 1 1)
					(thickness 0.15)
				)
				(justify mirror)
			)
		)
		(property "Manufacturer" "Murata"
			(at 412 279 0)
			(layer "B.Fab")
			(hide yes)
			(effects
				(font
					(size 1 1)
					(thickness 0.15)
				)
				(justify mirror)
			)
		)
		(property "Val" "100n"
			(at 412 279 0)
			(layer "B.Fab")
			(hide yes)
			(effects
				(font
					(size 1 1)
					(thickness 0.15)
				)
				(justify mirror)
			)
		)
		(property "Voltage" "50V"
			(at 412 279 0)
			(layer "B.Fab")
			(hide yes)
			(effects
				(font
					(size 1 1)
					(thickness 0.15)
				)
				(justify mirror)
			)
		)
		(sheetname "FPGA Bank 12 & 13")
		(sheetfile "fpga-bank-12-13.kicad_sch")
		(attr smd)
		(fp_rect
			(start -0.925 0.47)
			(end 0.925 -0.47)
			(stroke
				(width 0.05)
				(type default)
			)
			(fill no)
			(layer "B.CrtYd")
		)
		(fp_line
			(start 0.504 0.25)
			(end 0.504 -0.248)
			(stroke
				(width 0.15)
				(type solid)
			)
			(layer "B.Fab")
		)
		(fp_line
			(start 0.504 -0.248)
			(end -0.494 -0.248)
			(stroke
				(width 0.15)
				(type solid)
			)
			(layer "B.Fab")
		)
		(fp_line
			(start -0.494 0.25)
			(end 0.504 0.25)
			(stroke
				(width 0.15)
				(type solid)
			)
			(layer "B.Fab")
		)
		(fp_line
			(start -0.494 -0.248)
			(end -0.494 0.25)
			(stroke
				(width 0.15)
				(type solid)
			)
			(layer "B.Fab")
		)
		(pad "1" smd roundrect
			(at -0.48 0 180)
			(size 0.59 0.64)
			(layers "B.Cu" "B.Mask" "B.Paste")
			(roundrect_rratio 0.25)
			(net 1 "GND")
			(pintype "passive")
		)
		(pad "2" smd roundrect
			(at 0.48 0 180)
			(size 0.59 0.64)
			(layers "B.Cu" "B.Mask" "B.Paste")
			(roundrect_rratio 0.25)
			(net 24 "+3V3")
			(pintype "passive")
		)
	)
	(footprint "antmicro-footprints:LED_0603_1608Metric_G"
		(layer "B.Cu")
		(at 268.301 146.85 180)
		(descr "LED SMD 0603 Green")
		(tags "LED SMD 0603 Green")
		(property "Reference" "D12"
			(at 4.101 -0.3 0)
			(layer "B.SilkS")
			(effects
				(font
					(size 0.7 0.7)
					(thickness 0.15)
				)
				(justify left bottom mirror)
			)
		)
		(property "Value" "LED_G_0603_KP-1608CGCK"
			(at 0 -1.6 0)
			(layer "B.Fab")
			(effects
				(font
					(size 0.7 0.7)
					(thickness 0.15)
				)
				(justify left bottom mirror)
			)
		)
		(property "Description" "LED, Green, SMD, 0603, 20 mA, 2.1 V, 570 nm"
			(at 0 0 180)
			(layer "F.Fab")
			(hide yes)
			(effects
				(font
					(size 1.27 1.27)
					(thickness 0.15)
				)
			)
		)
		(property "Author" "Antmicro"
			(at 536.602 293.7 0)
			(layer "B.Fab")
			(hide yes)
			(effects
				(font
					(size 1 1)
					(thickness 0.15)
				)
				(justify mirror)
			)
		)
		(property "Color" "Green"
			(at 536.602 293.7 0)
			(layer "B.Fab")
			(hide yes)
			(effects
				(font
					(size 1 1)
					(thickness 0.15)
				)
				(justify mirror)
			)
		)
		(property "License" "Apache-2.0"
			(at 536.602 293.7 0)
			(layer "B.Fab")
			(hide yes)
			(effects
				(font
					(size 1 1)
					(thickness 0.15)
				)
				(justify mirror)
			)
		)
		(property "MPN" "KP-1608CGCK"
			(at 536.602 293.7 0)
			(layer "B.Fab")
			(hide yes)
			(effects
				(font
					(size 1 1)
					(thickness 0.15)
				)
				(justify mirror)
			)
		)
		(property "Manufacturer" "Kingbright"
			(at 536.602 293.7 0)
			(layer "B.Fab")
			(hide yes)
			(effects
				(font
					(size 1 1)
					(thickness 0.15)
				)
				(justify mirror)
			)
		)
		(sheetname "Power supply")
		(sheetfile "power-supply.kicad_sch")
		(attr smd)
		(fp_line
			(start 0.22 0.35)
			(end -0.22 0.35)
			(stroke
				(width 0.15)
				(type solid)
			)
			(layer "B.SilkS")
		)
		(fp_line
			(start 0.22 -0.35)
			(end -0.22 -0.35)
			(stroke
				(width 0.15)
				(type solid)
			)
			(layer "B.SilkS")
		)
		(fp_line
			(start 0.105328 -0.001008)
			(end 0.24 -0.001)
			(stroke
				(width 0.1)
				(type solid)
			)
			(layer "B.SilkS")
		)
		(fp_line
			(start 0.105328 -0.201008)
			(end 0.105328 0.198992)
			(stroke
				(width 0.1)
				(type solid)
			)
			(layer "B.SilkS")
		)
		(fp_line
			(start 0.105328 -0.201008)
			(end -0.094672 -0.001008)
			(stroke
				(width 0.1)
				(type solid)
			)
			(layer "B.SilkS")
		)
		(fp_line
			(start -0.094672 -0.001008)
			(end 0.105328 0.198992)
			(stroke
				(width 0.1)
				(type solid)
			)
			(layer "B.SilkS")
		)
		(fp_line
			(start -0.094672 -0.001008)
			(end -0.24 -0.001008)
			(stroke
				(width 0.1)
				(type solid)
			)
			(layer "B.SilkS")
		)
		(fp_line
			(start -0.094672 -0.201008)
			(end -0.094672 0.198992)
			(stroke
				(width 0.1)
				(type solid)
			)
			(layer "B.SilkS")
		)
		(fp_line
			(start -1.18 0.319)
			(end -1.18 -0.321)
			(stroke
				(width 0.15)
				(type solid)
			)
			(layer "B.SilkS")
		)
		(fp_rect
			(start 1.25 -0.65)
			(end -1.25 0.65)
			(stroke
				(width 0.05)
				(type solid)
			)
			(fill no)
			(layer "B.CrtYd")
		)
		(fp_line
			(start 0.599 0)
			(end 0.201 0)
			(stroke
				(width 0.15)
				(type solid)
			)
			(layer "B.Fab")
		)
		(fp_line
			(start 0.201 0.202)
			(end -0.101 0)
			(stroke
				(width 0.15)
				(type solid)
			)
			(layer "B.Fab")
		)
		(fp_line
			(start 0.201 0)
			(end 0.201 0.202)
			(stroke
				(width 0.15)
				(type solid)
			)
			(layer "B.Fab")
		)
		(fp_line
			(start 0.201 -0.2)
			(end 0.201 0)
			(stroke
				(width 0.15)
				(type solid)
			)
			(layer "B.Fab")
		)
		(fp_line
			(start -0.101 0)
			(end 0.201 -0.2)
			(stroke
				(width 0.15)
				(type solid)
			)
			(layer "B.Fab")
		)
		(fp_line
			(start -0.199 0.202)
			(end -0.199 -0.1)
			(stroke
				(width 0.15)
				(type solid)
			)
			(layer "B.Fab")
		)
		(fp_line
			(start -0.199 0)
			(end -0.597 0)
			(stroke
				(width 0.15)
				(type solid)
			)
			(layer "B.Fab")
		)
		(fp_line
			(start -0.199 -0.2)
			(end -0.199 -0.1)
			(stroke
				(width 0.15)
				(type solid)
			)
			(layer "B.Fab")
		)
		(fp_rect
			(start 0.848 -0.4)
			(end -0.85 0.402)
			(stroke
				(width 0.15)
				(type solid)
			)
			(fill no)
			(layer "B.Fab")
		)
		(pad "1" smd roundrect
			(at -0.7 0)
			(size 0.8 1)
			(layers "B.Cu" "B.Mask" "B.Paste")
			(roundrect_rratio 0.2)
			(net 771 "/Power supply/PD_PWR_OK3")
			(pinfunction "C")
			(pintype "passive")
		)
		(pad "2" smd roundrect
			(at 0.7 0)
			(size 0.8 1)
			(layers "B.Cu" "B.Mask" "B.Paste")
			(roundrect_rratio 0.2)
			(net 755 "Net-(D12-A)")
			(pinfunction "A")
			(pintype "passive")
		)
	)
	(footprint "antmicro-footprints:R_0402_1005Metric"
		(layer "B.Cu")
		(at 158.245001 85.165001)
		(descr "Resistor SMD 0402")
		(tags "resistor SMD 0402")
		(property "Reference" "R273"
			(at -0.820001 0.309999 180)
			(layer "B.SilkS")
			(effects
				(font
					(size 0.7 0.7)
					(thickness 0.15)
				)
				(justify left bottom mirror)
			)
		)
		(property "Value" "R_33R_0402"
			(at 0 -1.4 180)
			(layer "B.Fab")
			(effects
				(font
					(size 0.7 0.7)
					(thickness 0.15)
				)
				(justify left bottom mirror)
			)
		)
		(property "Description" "SMD Chip Resistor, 33 ohm, ± 1%, 62.5 mW, 0402 [1005 Metric], Thick Film, General Purpose"
			(at 0 0 0)
			(layer "F.Fab")
			(hide yes)
			(effects
				(font
					(size 1.27 1.27)
					(thickness 0.15)
				)
			)
		)
		(property "Author" "Antmicro"
			(at 0 0 0)
			(layer "B.Fab")
			(hide yes)
			(effects
				(font
					(size 1 1)
					(thickness 0.15)
				)
				(justify mirror)
			)
		)
		(property "License" "Apache-2.0"
			(at 0 0 0)
			(layer "B.Fab")
			(hide yes)
			(effects
				(font
					(size 1 1)
					(thickness 0.15)
				)
				(justify mirror)
			)
		)
		(property "MPN" "CR0402-FX-33R0GLF"
			(at 0 0 0)
			(layer "B.Fab")
			(hide yes)
			(effects
				(font
					(size 1 1)
					(thickness 0.15)
				)
				(justify mirror)
			)
		)
		(property "Manufacturer" "Bourns"
			(at 0 0 0)
			(layer "B.Fab")
			(hide yes)
			(effects
				(font
					(size 1 1)
					(thickness 0.15)
				)
				(justify mirror)
			)
		)
		(property "Tolerance" "1%"
			(at 0 0 0)
			(layer "B.Fab")
			(hide yes)
			(effects
				(font
					(size 1 1)
					(thickness 0.15)
				)
				(justify mirror)
			)
		)
		(property "Val" "33R"
			(at 0 0 0)
			(layer "B.Fab")
			(hide yes)
			(effects
				(font
					(size 1 1)
					(thickness 0.15)
				)
				(justify mirror)
			)
		)
		(sheetname "FMC+ HSPC")
		(sheetfile "fmc-hspc.kicad_sch")
		(attr smd)
		(fp_rect
			(start -0.925 0.47)
			(end 0.925 -0.47)
			(stroke
				(width 0.05)
				(type default)
			)
			(fill no)
			(layer "B.CrtYd")
		)
		(fp_rect
			(start -0.5 0.25)
			(end 0.5 -0.25)
			(stroke
				(width 0.15)
				(type solid)
			)
			(fill no)
			(layer "B.Fab")
		)
		(pad "1" smd roundrect
			(at -0.48 0)
			(size 0.59 0.64)
			(layers "B.Cu" "B.Mask" "B.Paste")
			(roundrect_rratio 0.25)
			(net 593 "/FMC+ HSPC/GTR_REFCLK2_R_P")
			(pintype "passive")
		)
		(pad "2" smd roundrect
			(at 0.48 0)
			(size 0.59 0.64)
			(layers "B.Cu" "B.Mask" "B.Paste")
			(roundrect_rratio 0.25)
			(net 594 "/FMC+ HSPC/GTX116.REFCLK0_P")
			(pintype "passive")
		)
	)
	(footprint "antmicro-footprints:C_0402_1005Metric"
		(layer "B.Cu")
		(at 165.745001 125.685001 180)
		(descr "Capacitor SMD 0402")
		(tags "capacitor SMD 0402")
		(property "Reference" "C296"
			(at 0.820001 -0.364999 0)
			(layer "B.SilkS")
			(effects
				(font
					(size 0.7 0.7)
					(thickness 0.15)
				)
				(justify left bottom mirror)
			)
		)
		(property "Value" "C_100n_0402"
			(at 0 -1.169 0)
			(layer "B.Fab")
			(effects
				(font
					(size 0.7 0.7)
					(thickness 0.15)
				)
				(justify left bottom mirror)
			)
		)
		(property "Description" "SMD Multilayer Ceramic Capacitor, 0.1 µF, 50 V, 0402 [1005 Metric], ± 10%, X5R, GRM Series"
			(at 0 0 180)
			(layer "F.Fab")
			(hide yes)
			(effects
				(font
					(size 1.27 1.27)
					(thickness 0.15)
				)
			)
		)
		(property "Author" "Antmicro"
			(at 331.490002 251.370002 0)
			(layer "B.Fab")
			(hide yes)
			(effects
				(font
					(size 1 1)
					(thickness 0.15)
				)
				(justify mirror)
			)
		)
		(property "Dielectric" "X5R"
			(at 331.490002 251.370002 0)
			(layer "B.Fab")
			(hide yes)
			(effects
				(font
					(size 1 1)
					(thickness 0.15)
				)
				(justify mirror)
			)
		)
		(property "License" "Apache-2.0"
			(at 331.490002 251.370002 0)
			(layer "B.Fab")
			(hide yes)
			(effects
				(font
					(size 1 1)
					(thickness 0.15)
				)
				(justify mirror)
			)
		)
		(property "MPN" "GRM155R61H104KE14D"
			(at 331.490002 251.370002 0)
			(layer "B.Fab")
			(hide yes)
			(effects
				(font
					(size 1 1)
					(thickness 0.15)
				)
				(justify mirror)
			)
		)
		(property "Manufacturer" "Murata"
			(at 331.490002 251.370002 0)
			(layer "B.Fab")
			(hide yes)
			(effects
				(font
					(size 1 1)
					(thickness 0.15)
				)
				(justify mirror)
			)
		)
		(property "Val" "100n"
			(at 331.490002 251.370002 0)
			(layer "B.Fab")
			(hide yes)
			(effects
				(font
					(size 1 1)
					(thickness 0.15)
				)
				(justify mirror)
			)
		)
		(property "Voltage" "50V"
			(at 331.490002 251.370002 0)
			(layer "B.Fab")
			(hide yes)
			(effects
				(font
					(size 1 1)
					(thickness 0.15)
				)
				(justify mirror)
			)
		)
		(sheetname "FMC+ HSPC")
		(sheetfile "fmc-hspc.kicad_sch")
		(attr smd)
		(fp_rect
			(start -0.925 0.47)
			(end 0.925 -0.47)
			(stroke
				(width 0.05)
				(type default)
			)
			(fill no)
			(layer "B.CrtYd")
		)
		(fp_line
			(start 0.504 0.25)
			(end 0.504 -0.248)
			(stroke
				(width 0.15)
				(type solid)
			)
			(layer "B.Fab")
		)
		(fp_line
			(start 0.504 -0.248)
			(end -0.494 -0.248)
			(stroke
				(width 0.15)
				(type solid)
			)
			(layer "B.Fab")
		)
		(fp_line
			(start -0.494 0.25)
			(end 0.504 0.25)
			(stroke
				(width 0.15)
				(type solid)
			)
			(layer "B.Fab")
		)
		(fp_line
			(start -0.494 -0.248)
			(end -0.494 0.25)
			(stroke
				(width 0.15)
				(type solid)
			)
			(layer "B.Fab")
		)
		(pad "1" smd roundrect
			(at -0.48 0 180)
			(size 0.59 0.64)
			(layers "B.Cu" "B.Mask" "B.Paste")
			(roundrect_rratio 0.25)
			(net 1 "GND")
			(pintype "passive")
		)
		(pad "2" smd roundrect
			(at 0.48 0 180)
			(size 0.59 0.64)
			(layers "B.Cu" "B.Mask" "B.Paste")
			(roundrect_rratio 0.25)
			(net 59 "12P0V")
			(pintype "passive")
		)
	)
	(footprint "antmicro-footprints:C_0402_1005Metric"
		(layer "B.Cu")
		(at 205 115.5 180)
		(descr "Capacitor SMD 0402")
		(tags "capacitor SMD 0402")
		(property "Reference" "C67"
			(at -1.1 0.475 0)
			(layer "B.SilkS")
			(effects
				(font
					(size 0.7 0.7)
					(thickness 0.15)
				)
				(justify left bottom mirror)
			)
		)
		(property "Value" "C_100n_0402"
			(at 0 -1.169 0)
			(layer "B.Fab")
			(effects
				(font
					(size 0.7 0.7)
					(thickness 0.15)
				)
				(justify left bottom mirror)
			)
		)
		(property "Description" "SMD Multilayer Ceramic Capacitor, 0.1 µF, 50 V, 0402 [1005 Metric], ± 10%, X5R, GRM Series"
			(at 0 0 180)
			(layer "F.Fab")
			(hide yes)
			(effects
				(font
					(size 1.27 1.27)
					(thickness 0.15)
				)
			)
		)
		(property "Author" "Antmicro"
			(at 410 231 0)
			(layer "B.Fab")
			(hide yes)
			(effects
				(font
					(size 1 1)
					(thickness 0.15)
				)
				(justify mirror)
			)
		)
		(property "Dielectric" "X5R"
			(at 410 231 0)
			(layer "B.Fab")
			(hide yes)
			(effects
				(font
					(size 1 1)
					(thickness 0.15)
				)
				(justify mirror)
			)
		)
		(property "License" "Apache-2.0"
			(at 410 231 0)
			(layer "B.Fab")
			(hide yes)
			(effects
				(font
					(size 1 1)
					(thickness 0.15)
				)
				(justify mirror)
			)
		)
		(property "MPN" "GRM155R61H104KE14D"
			(at 410 231 0)
			(layer "B.Fab")
			(hide yes)
			(effects
				(font
					(size 1 1)
					(thickness 0.15)
				)
				(justify mirror)
			)
		)
		(property "Manufacturer" "Murata"
			(at 410 231 0)
			(layer "B.Fab")
			(hide yes)
			(effects
				(font
					(size 1 1)
					(thickness 0.15)
				)
				(justify mirror)
			)
		)
		(property "Val" "100n"
			(at 410 231 0)
			(layer "B.Fab")
			(hide yes)
			(effects
				(font
					(size 1 1)
					(thickness 0.15)
				)
				(justify mirror)
			)
		)
		(property "Voltage" "50V"
			(at 410 231 0)
			(layer "B.Fab")
			(hide yes)
			(effects
				(font
					(size 1 1)
					(thickness 0.15)
				)
				(justify mirror)
			)
		)
		(sheetname "FPGA Bank 16 & 17")
		(sheetfile "fpga-bank-16-17.kicad_sch")
		(attr smd)
		(fp_rect
			(start -0.925 0.47)
			(end 0.925 -0.47)
			(stroke
				(width 0.05)
				(type default)
			)
			(fill no)
			(layer "B.CrtYd")
		)
		(fp_line
			(start 0.504 0.25)
			(end 0.504 -0.248)
			(stroke
				(width 0.15)
				(type solid)
			)
			(layer "B.Fab")
		)
		(fp_line
			(start 0.504 -0.248)
			(end -0.494 -0.248)
			(stroke
				(width 0.15)
				(type solid)
			)
			(layer "B.Fab")
		)
		(fp_line
			(start -0.494 0.25)
			(end 0.504 0.25)
			(stroke
				(width 0.15)
				(type solid)
			)
			(layer "B.Fab")
		)
		(fp_line
			(start -0.494 -0.248)
			(end -0.494 0.25)
			(stroke
				(width 0.15)
				(type solid)
			)
			(layer "B.Fab")
		)
		(pad "1" smd roundrect
			(at -0.48 0 180)
			(size 0.59 0.64)
			(layers "B.Cu" "B.Mask" "B.Paste")
			(roundrect_rratio 0.25)
			(net 1 "GND")
			(pintype "passive")
		)
		(pad "2" smd roundrect
			(at 0.48 0 180)
			(size 0.59 0.64)
			(layers "B.Cu" "B.Mask" "B.Paste")
			(roundrect_rratio 0.25)
			(net 24 "+3V3")
			(pintype "passive")
		)
	)
	(footprint "antmicro-footprints:Conn_JST_SH_1x4_BM04B-SRSS-TB-LF-SN"
		(layer "B.Cu")
		(at 239.101 113.775 180)
		(property "Reference" "J4"
			(at -1.399 3.075 0)
			(layer "B.SilkS")
			(effects
				(font
					(size 0.7 0.7)
					(thickness 0.15)
				)
				(justify left bottom mirror)
			)
		)
		(property "Value" "JST_SH_1x4_BM04B-SRSS-TB-LF-SN"
			(at 0 -3.1 0)
			(layer "B.Fab")
			(effects
				(font
					(size 0.7 0.7)
					(thickness 0.15)
				)
				(justify left bottom mirror)
			)
		)
		(property "Description" "Pin Header, Top Entry, Wire-to-Board, 1 mm, 1 Rows, 4 Contacts, Surface Mount, SR"
			(at 0 0 180)
			(layer "F.Fab")
			(hide yes)
			(effects
				(font
					(size 1.27 1.27)
					(thickness 0.15)
				)
			)
		)
		(property "Author" "Antmicro"
			(at 478.202 227.55 0)
			(layer "B.Fab")
			(hide yes)
			(effects
				(font
					(size 1 1)
					(thickness 0.15)
				)
				(justify mirror)
			)
		)
		(property "License" "Apache-2.0"
			(at 478.202 227.55 0)
			(layer "B.Fab")
			(hide yes)
			(effects
				(font
					(size 1 1)
					(thickness 0.15)
				)
				(justify mirror)
			)
		)
		(property "MPN" "BM04B-SRSS-TB(LF)(SN) "
			(at 478.202 227.55 0)
			(layer "B.Fab")
			(hide yes)
			(effects
				(font
					(size 1 1)
					(thickness 0.15)
				)
				(justify mirror)
			)
		)
		(property "Manufacturer" "JST Automotive Connectors"
			(at 478.202 227.55 0)
			(layer "B.Fab")
			(hide yes)
			(effects
				(font
					(size 1 1)
					(thickness 0.15)
				)
				(justify mirror)
			)
		)
		(sheetname "User GPIO + LED + button + DIP switch")
		(sheetfile "user-gpio.kicad_sch")
		(attr smd)
		(fp_line
			(start 1.774 1.7)
			(end 1.774 -1.702)
			(stroke
				(width 0.15)
				(type solid)
			)
			(layer "B.SilkS")
		)
		(fp_line
			(start -0.251 2.999)
			(end -1.125 2.999)
			(stroke
				(width 0.15)
				(type solid)
			)
			(layer "B.SilkS")
		)
		(fp_line
			(start -0.251 -2.999)
			(end -1.125 -2.999)
			(stroke
				(width 0.15)
				(type solid)
			)
			(layer "B.SilkS")
		)
		(fp_line
			(start -1.125 2.999)
			(end -1.125 2.201)
			(stroke
				(width 0.15)
				(type solid)
			)
			(layer "B.SilkS")
		)
		(fp_line
			(start -1.125 -2.999)
			(end -1.125 -2.201)
			(stroke
				(width 0.15)
				(type solid)
			)
			(layer "B.SilkS")
		)
		(fp_circle
			(center -1.6 2.1)
			(end -1.55 2.1)
			(stroke
				(width 0.15)
				(type solid)
			)
			(fill yes)
			(layer "B.SilkS")
		)
		(fp_rect
			(start -2.05 3.95)
			(end 2.05 -3.95)
			(stroke
				(width 0.05)
				(type solid)
			)
			(fill no)
			(layer "B.CrtYd")
		)
		(fp_rect
			(start -1.8 3)
			(end 1.8 -3)
			(stroke
				(width 0.15)
				(type solid)
			)
			(fill no)
			(layer "B.Fab")
		)
		(pad "1" smd roundrect
			(at -1.45 1.5 270)
			(size 0.6 1.55)
			(layers "B.Cu" "B.Mask" "B.Paste")
			(roundrect_rratio 0.25)
			(net 1 "GND")
			(pinfunction "Pin_1")
			(pintype "passive")
		)
		(pad "2" smd roundrect
			(at -1.45 0.5 270)
			(size 0.6 1.55)
			(layers "B.Cu" "B.Mask" "B.Paste")
			(roundrect_rratio 0.25)
			(net 703 "+5V")
			(pinfunction "Pin_2")
			(pintype "passive")
		)
		(pad "3" smd roundrect
			(at -1.45 -0.5 270)
			(size 0.6 1.55)
			(layers "B.Cu" "B.Mask" "B.Paste")
			(roundrect_rratio 0.25)
			(net 28 "unconnected-(J4-Pin_3-Pad3)")
			(pinfunction "Pin_3")
			(pintype "passive+no_connect")
		)
		(pad "4" smd roundrect
			(at -1.45 -1.5 270)
			(size 0.6 1.55)
			(layers "B.Cu" "B.Mask" "B.Paste")
			(roundrect_rratio 0.25)
			(net 29 "Net-(J4-Pin_4)")
			(pinfunction "Pin_4")
			(pintype "passive")
		)
		(pad "MP" smd roundrect
			(at 1.075 -2.8 270)
			(size 1.2 1.8)
			(layers "B.Cu" "B.Mask" "B.Paste")
			(roundrect_rratio 0.25)
			(net 1 "GND")
			(pinfunction "MP")
			(pintype "passive")
		)
		(pad "MP" smd roundrect
			(at 1.075 2.8 270)
			(size 1.2 1.8)
			(layers "B.Cu" "B.Mask" "B.Paste")
			(roundrect_rratio 0.25)
			(net 1 "GND")
			(pinfunction "MP")
			(pintype "passive")
		)
	)
	(footprint "antmicro-footprints:C_0402_1005Metric"
		(layer "B.Cu")
		(at 192 118.3)
		(descr "Capacitor SMD 0402")
		(tags "capacitor SMD 0402")
		(property "Reference" "C119"
			(at 1.475 1.2 180)
			(layer "B.SilkS")
			(effects
				(font
					(size 0.7 0.7)
					(thickness 0.15)
				)
				(justify left bottom mirror)
			)
		)
		(property "Value" "C_100n_0402"
			(at 0 -1.169 180)
			(layer "B.Fab")
			(effects
				(font
					(size 0.7 0.7)
					(thickness 0.15)
				)
				(justify left bottom mirror)
			)
		)
		(property "Description" "SMD Multilayer Ceramic Capacitor, 0.1 µF, 50 V, 0402 [1005 Metric], ± 10%, X5R, GRM Series"
			(at 0 0 0)
			(layer "F.Fab")
			(hide yes)
			(effects
				(font
					(size 1.27 1.27)
					(thickness 0.15)
				)
			)
		)
		(property "Author" "Antmicro"
			(at 0 0 0)
			(layer "B.Fab")
			(hide yes)
			(effects
				(font
					(size 1 1)
					(thickness 0.15)
				)
				(justify mirror)
			)
		)
		(property "Dielectric" "X5R"
			(at 0 0 0)
			(layer "B.Fab")
			(hide yes)
			(effects
				(font
					(size 1 1)
					(thickness 0.15)
				)
				(justify mirror)
			)
		)
		(property "License" "Apache-2.0"
			(at 0 0 0)
			(layer "B.Fab")
			(hide yes)
			(effects
				(font
					(size 1 1)
					(thickness 0.15)
				)
				(justify mirror)
			)
		)
		(property "MPN" "GRM155R61H104KE14D"
			(at 0 0 0)
			(layer "B.Fab")
			(hide yes)
			(effects
				(font
					(size 1 1)
					(thickness 0.15)
				)
				(justify mirror)
			)
		)
		(property "Manufacturer" "Murata"
			(at 0 0 0)
			(layer "B.Fab")
			(hide yes)
			(effects
				(font
					(size 1 1)
					(thickness 0.15)
				)
				(justify mirror)
			)
		)
		(property "Val" "100n"
			(at 0 0 0)
			(layer "B.Fab")
			(hide yes)
			(effects
				(font
					(size 1 1)
					(thickness 0.15)
				)
				(justify mirror)
			)
		)
		(property "Voltage" "50V"
			(at 0 0 0)
			(layer "B.Fab")
			(hide yes)
			(effects
				(font
					(size 1 1)
					(thickness 0.15)
				)
				(justify mirror)
			)
		)
		(sheetname "FPGA supply")
		(sheetfile "fpga-supply.kicad_sch")
		(attr smd)
		(fp_rect
			(start -0.925 0.47)
			(end 0.925 -0.47)
			(stroke
				(width 0.05)
				(type default)
			)
			(fill no)
			(layer "B.CrtYd")
		)
		(fp_line
			(start -0.494 -0.248)
			(end -0.494 0.25)
			(stroke
				(width 0.15)
				(type solid)
			)
			(layer "B.Fab")
		)
		(fp_line
			(start -0.494 0.25)
			(end 0.504 0.25)
			(stroke
				(width 0.15)
				(type solid)
			)
			(layer "B.Fab")
		)
		(fp_line
			(start 0.504 -0.248)
			(end -0.494 -0.248)
			(stroke
				(width 0.15)
				(type solid)
			)
			(layer "B.Fab")
		)
		(fp_line
			(start 0.504 0.25)
			(end 0.504 -0.248)
			(stroke
				(width 0.15)
				(type solid)
			)
			(layer "B.Fab")
		)
		(pad "1" smd roundrect
			(at -0.48 0)
			(size 0.59 0.64)
			(layers "B.Cu" "B.Mask" "B.Paste")
			(roundrect_rratio 0.25)
			(net 6 "+1V0_MGTAVCC")
			(pintype "passive")
		)
		(pad "2" smd roundrect
			(at 0.48 0)
			(size 0.59 0.64)
			(layers "B.Cu" "B.Mask" "B.Paste")
			(roundrect_rratio 0.25)
			(net 1 "GND")
			(pintype "passive")
		)
	)
	(footprint "antmicro-footprints:R_0402_1005Metric"
		(layer "B.Cu")
		(at 175.33 177.26 180)
		(descr "Resistor SMD 0402")
		(tags "resistor SMD 0402")
		(property "Reference" "R277"
			(at -1.37 -2.215 0)
			(layer "B.SilkS")
			(effects
				(font
					(size 0.7 0.7)
					(thickness 0.15)
				)
				(justify left bottom mirror)
			)
		)
		(property "Value" "R_100k_0402"
			(at 0 -1.4 0)
			(layer "B.Fab")
			(effects
				(font
					(size 0.7 0.7)
					(thickness 0.15)
				)
				(justify left bottom mirror)
			)
		)
		(property "Description" "SMD Chip Resistor, 100 kohm, ± 1%, 62.5 mW, 0402 [1005 Metric], Thick Film, General Purpose"
			(at 0 0 180)
			(layer "F.Fab")
			(hide yes)
			(effects
				(font
					(size 1.27 1.27)
					(thickness 0.15)
				)
			)
		)
		(property "Author" "Antmicro"
			(at 350.66 354.52 0)
			(layer "B.Fab")
			(hide yes)
			(effects
				(font
					(size 1 1)
					(thickness 0.15)
				)
				(justify mirror)
			)
		)
		(property "DNP" "DNP"
			(at 350.66 354.52 0)
			(layer "B.Fab")
			(hide yes)
			(effects
				(font
					(size 1 1)
					(thickness 0.15)
				)
				(justify mirror)
			)
		)
		(property "License" "Apache-2.0"
			(at 350.66 354.52 0)
			(layer "B.Fab")
			(hide yes)
			(effects
				(font
					(size 1 1)
					(thickness 0.15)
				)
				(justify mirror)
			)
		)
		(property "MPN" "CR0402-FX-1003GLF"
			(at 350.66 354.52 0)
			(layer "B.Fab")
			(hide yes)
			(effects
				(font
					(size 1 1)
					(thickness 0.15)
				)
				(justify mirror)
			)
		)
		(property "Manufacturer" "Bourns"
			(at 350.66 354.52 0)
			(layer "B.Fab")
			(hide yes)
			(effects
				(font
					(size 1 1)
					(thickness 0.15)
				)
				(justify mirror)
			)
		)
		(property "Tolerance" "1%"
			(at 350.66 354.52 0)
			(layer "B.Fab")
			(hide yes)
			(effects
				(font
					(size 1 1)
					(thickness 0.15)
				)
				(justify mirror)
			)
		)
		(property "Val" "100k"
			(at 350.66 354.52 0)
			(layer "B.Fab")
			(hide yes)
			(effects
				(font
					(size 1 1)
					(thickness 0.15)
				)
				(justify mirror)
			)
		)
		(property "dnp" ""
			(at 350.66 354.52 0)
			(layer "B.Fab")
			(hide yes)
			(effects
				(font
					(size 1 1)
					(thickness 0.15)
				)
				(justify mirror)
			)
		)
		(property "exclude_from_bom" ""
			(at 350.66 354.52 0)
			(layer "B.Fab")
			(hide yes)
			(effects
				(font
					(size 1 1)
					(thickness 0.15)
				)
				(justify mirror)
			)
		)
		(sheetname "DC-DC Converters")
		(sheetfile "dc-dc.kicad_sch")
		(attr smd exclude_from_bom)
		(fp_rect
			(start -0.925 0.47)
			(end 0.925 -0.47)
			(stroke
				(width 0.05)
				(type default)
			)
			(fill no)
			(layer "B.CrtYd")
		)
		(fp_rect
			(start -0.5 0.25)
			(end 0.5 -0.25)
			(stroke
				(width 0.15)
				(type solid)
			)
			(fill no)
			(layer "B.Fab")
		)
		(pad "1" smd roundrect
			(at -0.48 0 180)
			(size 0.59 0.64)
			(layers "B.Cu" "B.Mask" "B.Paste")
			(roundrect_rratio 0.25)
			(net 954 "/DC-DC Converters/QDCDC2_GPIO")
			(pintype "passive")
		)
		(pad "2" smd roundrect
			(at 0.48 0 180)
			(size 0.59 0.64)
			(layers "B.Cu" "B.Mask" "B.Paste")
			(roundrect_rratio 0.25)
			(net 732 "/DC-DC Converters/QDCDC2_VCC")
			(pintype "passive")
		)
	)
	(footprint "antmicro-footprints:R_Array_4x0201_Panasonic_EXB18V"
		(layer "B.Cu")
		(at 247.901 127.9)
		(property "Reference" "R20"
			(at 1.024 -0.725 0)
			(layer "B.SilkS")
			(effects
				(font
					(size 0.7 0.7)
					(thickness 0.15)
				)
				(justify left bottom mirror)
			)
		)
		(property "Value" "R_4x33R_0201_array"
			(at -1.1 -1.8 0)
			(layer "B.Fab")
			(effects
				(font
					(size 0.7 0.7)
					(thickness 0.15)
				)
				(justify right bottom mirror)
			)
		)
		(property "Description" "Fixed Network Resistor, 33 ohm, Isolated, 4 Resistors, 0502 [1406 Metric], Flat, ± 5%"
			(at 0 0 0)
			(layer "F.Fab")
			(hide yes)
			(effects
				(font
					(size 1.27 1.27)
					(thickness 0.15)
				)
			)
		)
		(property "Author" "Antmicro"
			(at 0 0 0)
			(layer "B.Fab")
			(hide yes)
			(effects
				(font
					(size 1 1)
					(thickness 0.15)
				)
				(justify mirror)
			)
		)
		(property "License" "Apache-2.0"
			(at 0 0 0)
			(layer "B.Fab")
			(hide yes)
			(effects
				(font
					(size 1 1)
					(thickness 0.15)
				)
				(justify mirror)
			)
		)
		(property "MPN" "EXB-18V330JX"
			(at 0 0 0)
			(layer "B.Fab")
			(hide yes)
			(effects
				(font
					(size 1 1)
					(thickness 0.15)
				)
				(justify mirror)
			)
		)
		(property "Manufacturer" "Panasonic"
			(at 0 0 0)
			(layer "B.Fab")
			(hide yes)
			(effects
				(font
					(size 1 1)
					(thickness 0.15)
				)
				(justify mirror)
			)
		)
		(property "Val" "R_4x33R_0201"
			(at 0 0 0)
			(layer "B.Fab")
			(hide yes)
			(effects
				(font
					(size 1 1)
					(thickness 0.15)
				)
				(justify mirror)
			)
		)
		(sheetname "Supervisior MCU")
		(sheetfile "supervisor-mcu.kicad_sch")
		(attr smd)
		(fp_line
			(start -0.8 0.45)
			(end -0.8 -0.45)
			(stroke
				(width 0.12)
				(type solid)
			)
			(layer "B.SilkS")
		)
		(fp_line
			(start 0.8 0.45)
			(end 0.8 -0.45)
			(stroke
				(width 0.12)
				(type solid)
			)
			(layer "B.SilkS")
		)
		(fp_rect
			(start -0.898 0.66)
			(end 0.898 -0.65)
			(stroke
				(width 0.05)
				(type solid)
			)
			(fill no)
			(layer "B.CrtYd")
		)
		(pad "1" smd roundrect
			(at -0.6 -0.298)
			(size 0.2 0.4)
			(layers "B.Cu" "B.Mask" "B.Paste")
			(roundrect_rratio 0.25)
			(net 346 "unconnected-(R20-R1.1-Pad1)")
			(pinfunction "R1.1")
			(pintype "passive+no_connect")
		)
		(pad "2" smd roundrect
			(at -0.202 -0.298)
			(size 0.2 0.4)
			(layers "B.Cu" "B.Mask" "B.Paste")
			(roundrect_rratio 0.25)
			(net 1351 "/SUP_MCU.A0")
			(pinfunction "R2.1")
			(pintype "passive")
		)
		(pad "3" smd roundrect
			(at 0.2 -0.298)
			(size 0.2 0.4)
			(layers "B.Cu" "B.Mask" "B.Paste")
			(roundrect_rratio 0.25)
			(net 1330 "/SUP_MCU.RX1")
			(pinfunction "R3.1")
			(pintype "passive")
		)
		(pad "4" smd roundrect
			(at 0.598 -0.298)
			(size 0.2 0.4)
			(layers "B.Cu" "B.Mask" "B.Paste")
			(roundrect_rratio 0.25)
			(net 1352 "/SUP_MCU.A13")
			(pinfunction "R4.1")
			(pintype "passive")
		)
		(pad "5" smd roundrect
			(at 0.598 0.3)
			(size 0.2 0.4)
			(layers "B.Cu" "B.Mask" "B.Paste")
			(roundrect_rratio 0.25)
			(net 1074 "/Supervisior MCU/USB_A13")
			(pinfunction "R4.2")
			(pintype "passive")
		)
		(pad "6" smd roundrect
			(at 0.2 0.3)
			(size 0.2 0.4)
			(layers "B.Cu" "B.Mask" "B.Paste")
			(roundrect_rratio 0.25)
			(net 1083 "/Supervisior MCU/RXD1")
			(pinfunction "R3.2")
			(pintype "passive")
		)
		(pad "7" smd roundrect
			(at -0.202 0.3)
			(size 0.2 0.4)
			(layers "B.Cu" "B.Mask" "B.Paste")
			(roundrect_rratio 0.25)
			(net 1061 "/Supervisior MCU/USB_A0")
			(pinfunction "R2.2")
			(pintype "passive")
		)
		(pad "8" smd roundrect
			(at -0.6 0.3)
			(size 0.2 0.4)
			(layers "B.Cu" "B.Mask" "B.Paste")
			(roundrect_rratio 0.25)
			(net 347 "unconnected-(R20-R1.2-Pad8)")
			(pinfunction "R1.2")
			(pintype "passive+no_connect")
		)
	)
	(footprint "antmicro-footprints:R_Array_4x0201_Panasonic_EXB18V"
		(layer "B.Cu")
		(at 167.799999 144.999999)
		(property "Reference" "R12"
			(at -4.024999 6.250001 0)
			(layer "B.SilkS")
			(effects
				(font
					(size 0.7 0.7)
					(thickness 0.15)
				)
				(justify left bottom mirror)
			)
		)
		(property "Value" "4x39R_0201_array"
			(at -1.1 -1.8 0)
			(layer "B.Fab")
			(effects
				(font
					(size 0.7 0.7)
					(thickness 0.15)
				)
				(justify right bottom mirror)
			)
		)
		(property "Description" "Fixed Network Resistor, 39 ohm, Isolated, 4 Resistors, 0502 [1406 Metric], Flat, ± 5%"
			(at 0 0 0)
			(layer "F.Fab")
			(hide yes)
			(effects
				(font
					(size 1.27 1.27)
					(thickness 0.15)
				)
			)
		)
		(property "Author" "Antmicro"
			(at 0 0 0)
			(layer "B.Fab")
			(hide yes)
			(effects
				(font
					(size 1 1)
					(thickness 0.15)
				)
				(justify mirror)
			)
		)
		(property "License" "Apache-2.0"
			(at 0 0 0)
			(layer "B.Fab")
			(hide yes)
			(effects
				(font
					(size 1 1)
					(thickness 0.15)
				)
				(justify mirror)
			)
		)
		(property "MPN" "EXB-18V390JX"
			(at 0 0 0)
			(layer "B.Fab")
			(hide yes)
			(effects
				(font
					(size 1 1)
					(thickness 0.15)
				)
				(justify mirror)
			)
		)
		(property "Manufacturer" "Panasonic"
			(at 0 0 0)
			(layer "B.Fab")
			(hide yes)
			(effects
				(font
					(size 1 1)
					(thickness 0.15)
				)
				(justify mirror)
			)
		)
		(property "Val" "4x39R_0201"
			(at 0 0 0)
			(layer "B.Fab")
			(hide yes)
			(effects
				(font
					(size 1 1)
					(thickness 0.15)
				)
				(justify mirror)
			)
		)
		(sheetname "DRAM + SRAM")
		(sheetfile "ram.kicad_sch")
		(attr smd)
		(fp_line
			(start -0.8 0.45)
			(end -0.8 -0.45)
			(stroke
				(width 0.12)
				(type solid)
			)
			(layer "B.SilkS")
		)
		(fp_line
			(start 0.8 0.45)
			(end 0.8 -0.45)
			(stroke
				(width 0.12)
				(type solid)
			)
			(layer "B.SilkS")
		)
		(fp_rect
			(start -0.898 0.66)
			(end 0.898 -0.65)
			(stroke
				(width 0.05)
				(type solid)
			)
			(fill no)
			(layer "B.CrtYd")
		)
		(pad "1" smd roundrect
			(at -0.6 -0.298)
			(size 0.2 0.4)
			(layers "B.Cu" "B.Mask" "B.Paste")
			(roundrect_rratio 0.25)
			(net 549 "/DRAM + SRAM/DDR.BA2")
			(pinfunction "R1.1")
			(pintype "passive")
		)
		(pad "2" smd roundrect
			(at -0.202 -0.298)
			(size 0.2 0.4)
			(layers "B.Cu" "B.Mask" "B.Paste")
			(roundrect_rratio 0.25)
			(net 561 "/DRAM + SRAM/DDR.~{CS}")
			(pinfunction "R2.1")
			(pintype "passive")
		)
		(pad "3" smd roundrect
			(at 0.2 -0.298)
			(size 0.2 0.4)
			(layers "B.Cu" "B.Mask" "B.Paste")
			(roundrect_rratio 0.25)
			(net 558 "/DRAM + SRAM/DDR.~{WE}")
			(pinfunction "R3.1")
			(pintype "passive")
		)
		(pad "4" smd roundrect
			(at 0.598 -0.298)
			(size 0.2 0.4)
			(layers "B.Cu" "B.Mask" "B.Paste")
			(roundrect_rratio 0.25)
			(net 553 "/DRAM + SRAM/DDR.ODT")
			(pinfunction "R4.1")
			(pintype "passive")
		)
		(pad "5" smd roundrect
			(at 0.598 0.3)
			(size 0.2 0.4)
			(layers "B.Cu" "B.Mask" "B.Paste")
			(roundrect_rratio 0.25)
			(net 7 "+0V675_VTT")
			(pinfunction "R4.2")
			(pintype "passive")
		)
		(pad "6" smd roundrect
			(at 0.2 0.3)
			(size 0.2 0.4)
			(layers "B.Cu" "B.Mask" "B.Paste")
			(roundrect_rratio 0.25)
			(net 7 "+0V675_VTT")
			(pinfunction "R3.2")
			(pintype "passive")
		)
		(pad "7" smd roundrect
			(at -0.202 0.3)
			(size 0.2 0.4)
			(layers "B.Cu" "B.Mask" "B.Paste")
			(roundrect_rratio 0.25)
			(net 7 "+0V675_VTT")
			(pinfunction "R2.2")
			(pintype "passive")
		)
		(pad "8" smd roundrect
			(at -0.6 0.3)
			(size 0.2 0.4)
			(layers "B.Cu" "B.Mask" "B.Paste")
			(roundrect_rratio 0.25)
			(net 7 "+0V675_VTT")
			(pinfunction "R1.2")
			(pintype "passive")
		)
	)
	(footprint "antmicro-footprints:C_0402_1005Metric"
		(layer "B.Cu")
		(at 194.85 131.25)
		(descr "Capacitor SMD 0402")
		(tags "capacitor SMD 0402")
		(property "Reference" "C140"
			(at 24.425 -28.05 180)
			(layer "B.SilkS")
			(effects
				(font
					(size 0.7 0.7)
					(thickness 0.15)
				)
				(justify left bottom mirror)
			)
		)
		(property "Value" "C_100n_0402"
			(at 0 -1.169 180)
			(layer "B.Fab")
			(effects
				(font
					(size 0.7 0.7)
					(thickness 0.15)
				)
				(justify left bottom mirror)
			)
		)
		(property "Description" "SMD Multilayer Ceramic Capacitor, 0.1 µF, 50 V, 0402 [1005 Metric], ± 10%, X5R, GRM Series"
			(at 0 0 0)
			(layer "F.Fab")
			(hide yes)
			(effects
				(font
					(size 1.27 1.27)
					(thickness 0.15)
				)
			)
		)
		(property "Author" "Antmicro"
			(at 0 0 0)
			(layer "B.Fab")
			(hide yes)
			(effects
				(font
					(size 1 1)
					(thickness 0.15)
				)
				(justify mirror)
			)
		)
		(property "Dielectric" "X5R"
			(at 0 0 0)
			(layer "B.Fab")
			(hide yes)
			(effects
				(font
					(size 1 1)
					(thickness 0.15)
				)
				(justify mirror)
			)
		)
		(property "License" "Apache-2.0"
			(at 0 0 0)
			(layer "B.Fab")
			(hide yes)
			(effects
				(font
					(size 1 1)
					(thickness 0.15)
				)
				(justify mirror)
			)
		)
		(property "MPN" "GRM155R61H104KE14D"
			(at 0 0 0)
			(layer "B.Fab")
			(hide yes)
			(effects
				(font
					(size 1 1)
					(thickness 0.15)
				)
				(justify mirror)
			)
		)
		(property "Manufacturer" "Murata"
			(at 0 0 0)
			(layer "B.Fab")
			(hide yes)
			(effects
				(font
					(size 1 1)
					(thickness 0.15)
				)
				(justify mirror)
			)
		)
		(property "Val" "100n"
			(at 0 0 0)
			(layer "B.Fab")
			(hide yes)
			(effects
				(font
					(size 1 1)
					(thickness 0.15)
				)
				(justify mirror)
			)
		)
		(property "Voltage" "50V"
			(at 0 0 0)
			(layer "B.Fab")
			(hide yes)
			(effects
				(font
					(size 1 1)
					(thickness 0.15)
				)
				(justify mirror)
			)
		)
		(sheetname "FPGA supply")
		(sheetfile "fpga-supply.kicad_sch")
		(attr smd)
		(fp_rect
			(start -0.925 0.47)
			(end 0.925 -0.47)
			(stroke
				(width 0.05)
				(type default)
			)
			(fill no)
			(layer "B.CrtYd")
		)
		(fp_line
			(start -0.494 -0.248)
			(end -0.494 0.25)
			(stroke
				(width 0.15)
				(type solid)
			)
			(layer "B.Fab")
		)
		(fp_line
			(start -0.494 0.25)
			(end 0.504 0.25)
			(stroke
				(width 0.15)
				(type solid)
			)
			(layer "B.Fab")
		)
		(fp_line
			(start 0.504 -0.248)
			(end -0.494 -0.248)
			(stroke
				(width 0.15)
				(type solid)
			)
			(layer "B.Fab")
		)
		(fp_line
			(start 0.504 0.25)
			(end 0.504 -0.248)
			(stroke
				(width 0.15)
				(type solid)
			)
			(layer "B.Fab")
		)
		(pad "1" smd roundrect
			(at -0.48 0)
			(size 0.59 0.64)
			(layers "B.Cu" "B.Mask" "B.Paste")
			(roundrect_rratio 0.25)
			(net 1 "GND")
			(pintype "passive")
		)
		(pad "2" smd roundrect
			(at 0.48 0)
			(size 0.59 0.64)
			(layers "B.Cu" "B.Mask" "B.Paste")
			(roundrect_rratio 0.25)
			(net 650 "+1V0")
			(pintype "passive")
		)
	)
	(footprint "antmicro-footprints:R_0402_1005Metric"
		(layer "B.Cu")
		(at 254.801 173.04762 90)
		(descr "Resistor SMD 0402")
		(tags "resistor SMD 0402")
		(property "Reference" "R60"
			(at 0.99762 -0.626 270)
			(layer "B.SilkS")
			(effects
				(font
					(size 0.7 0.7)
					(thickness 0.15)
				)
				(justify left bottom mirror)
			)
		)
		(property "Value" "R_0R_0402"
			(at 0 -1.4 270)
			(layer "B.Fab")
			(effects
				(font
					(size 0.7 0.7)
					(thickness 0.15)
				)
				(justify left bottom mirror)
			)
		)
		(property "Description" "SMD Chip Resistor, Jumper, 0 ohm, 100 mW, 0402 [1005 Metric], Thick Film, General Purpose"
			(at 0 0 90)
			(layer "F.Fab")
			(hide yes)
			(effects
				(font
					(size 1.27 1.27)
					(thickness 0.15)
				)
			)
		)
		(property "Author" "Antmicro"
			(at 427.84862 -81.75338 0)
			(layer "B.Fab")
			(hide yes)
			(effects
				(font
					(size 1 1)
					(thickness 0.15)
				)
				(justify mirror)
			)
		)
		(property "Current" "1A"
			(at 427.84862 -81.75338 0)
			(layer "B.Fab")
			(hide yes)
			(effects
				(font
					(size 1 1)
					(thickness 0.15)
				)
				(justify mirror)
			)
		)
		(property "License" "Apache-2.0"
			(at 427.84862 -81.75338 0)
			(layer "B.Fab")
			(hide yes)
			(effects
				(font
					(size 1 1)
					(thickness 0.15)
				)
				(justify mirror)
			)
		)
		(property "MPN" "ERJ2GE0R00X"
			(at 427.84862 -81.75338 0)
			(layer "B.Fab")
			(hide yes)
			(effects
				(font
					(size 1 1)
					(thickness 0.15)
				)
				(justify mirror)
			)
		)
		(property "Manufacturer" "Panasonic"
			(at 427.84862 -81.75338 0)
			(layer "B.Fab")
			(hide yes)
			(effects
				(font
					(size 1 1)
					(thickness 0.15)
				)
				(justify mirror)
			)
		)
		(property "Tolerance" ""
			(at 427.84862 -81.75338 0)
			(layer "B.Fab")
			(hide yes)
			(effects
				(font
					(size 1 1)
					(thickness 0.15)
				)
				(justify mirror)
			)
		)
		(property "Val" "0R"
			(at 427.84862 -81.75338 0)
			(layer "B.Fab")
			(hide yes)
			(effects
				(font
					(size 1 1)
					(thickness 0.15)
				)
				(justify mirror)
			)
		)
		(sheetname "Power supply")
		(sheetfile "power-supply.kicad_sch")
		(attr smd)
		(fp_rect
			(start -0.925 0.47)
			(end 0.925 -0.47)
			(stroke
				(width 0.05)
				(type default)
			)
			(fill no)
			(layer "B.CrtYd")
		)
		(fp_rect
			(start -0.5 0.25)
			(end 0.5 -0.25)
			(stroke
				(width 0.15)
				(type solid)
			)
			(fill no)
			(layer "B.Fab")
		)
		(pad "1" smd roundrect
			(at -0.48 0 90)
			(size 0.59 0.64)
			(layers "B.Cu" "B.Mask" "B.Paste")
			(roundrect_rratio 0.25)
			(net 344 "Net-(Q18-D)")
			(pintype "passive")
		)
		(pad "2" smd roundrect
			(at 0.48 0 90)
			(size 0.59 0.64)
			(layers "B.Cu" "B.Mask" "B.Paste")
			(roundrect_rratio 0.25)
			(net 798 "/Power supply/POE_ACTIVE")
			(pintype "passive")
		)
	)
	(footprint "antmicro-footprints:C_0603_1608Metric"
		(layer "B.Cu")
		(at 217.7 113.9 -90)
		(descr "Capacitor SMD 0603")
		(tags "capacitor 0603")
		(property "Reference" "C7"
			(at -0.8 -1.41 90)
			(layer "B.SilkS")
			(effects
				(font
					(size 0.7 0.7)
					(thickness 0.15)
				)
				(justify left bottom mirror)
			)
		)
		(property "Value" "C_47u_0603"
			(at 0 -1.6 90)
			(layer "B.Fab")
			(effects
				(font
					(size 0.7 0.7)
					(thickness 0.15)
				)
				(justify left bottom mirror)
			)
		)
		(property "Description" "SMD Multilayer Ceramic Capacitor, 47 µF, 6.3 V, 0603 [1608 Metric], ± 20%, X5R, GRM Series"
			(at 0 0 270)
			(layer "F.Fab")
			(hide yes)
			(effects
				(font
					(size 1.27 1.27)
					(thickness 0.15)
				)
			)
		)
		(property "Author" "Antmicro"
			(at 103.8 331.6 0)
			(layer "B.Fab")
			(hide yes)
			(effects
				(font
					(size 1 1)
					(thickness 0.15)
				)
				(justify mirror)
			)
		)
		(property "Dielectric" ""
			(at 103.8 331.6 0)
			(layer "B.Fab")
			(hide yes)
			(effects
				(font
					(size 1 1)
					(thickness 0.15)
				)
				(justify mirror)
			)
		)
		(property "License" "Apache-2.0"
			(at 103.8 331.6 0)
			(layer "B.Fab")
			(hide yes)
			(effects
				(font
					(size 1 1)
					(thickness 0.15)
				)
				(justify mirror)
			)
		)
		(property "MPN" "GRM188R60J476ME15D"
			(at 103.8 331.6 0)
			(layer "B.Fab")
			(hide yes)
			(effects
				(font
					(size 1 1)
					(thickness 0.15)
				)
				(justify mirror)
			)
		)
		(property "Manufacturer" "Murata"
			(at 103.8 331.6 0)
			(layer "B.Fab")
			(hide yes)
			(effects
				(font
					(size 1 1)
					(thickness 0.15)
				)
				(justify mirror)
			)
		)
		(property "Val" "47u"
			(at 103.8 331.6 0)
			(layer "B.Fab")
			(hide yes)
			(effects
				(font
					(size 1 1)
					(thickness 0.15)
				)
				(justify mirror)
			)
		)
		(property "Voltage" ""
			(at 103.8 331.6 0)
			(layer "B.Fab")
			(hide yes)
			(effects
				(font
					(size 1 1)
					(thickness 0.15)
				)
				(justify mirror)
			)
		)
		(sheetname "FPGA Bank 16 & 17")
		(sheetfile "fpga-bank-16-17.kicad_sch")
		(attr smd)
		(fp_line
			(start -0.15 0.4)
			(end 0.15 0.4)
			(stroke
				(width 0.15)
				(type solid)
			)
			(layer "B.SilkS")
		)
		(fp_line
			(start -0.15 -0.4)
			(end 0.15 -0.4)
			(stroke
				(width 0.15)
				(type solid)
			)
			(layer "B.SilkS")
		)
		(fp_rect
			(start -1.25 0.65)
			(end 1.25 -0.65)
			(stroke
				(width 0.05)
				(type solid)
			)
			(fill no)
			(layer "B.CrtYd")
		)
		(fp_rect
			(start -0.8 0.4)
			(end 0.8 -0.4)
			(stroke
				(width 0.15)
				(type solid)
			)
			(fill no)
			(layer "B.Fab")
		)
		(pad "1" smd roundrect
			(at -0.7 0 270)
			(size 0.8 1)
			(layers "B.Cu" "B.Mask" "B.Paste")
			(roundrect_rratio 0.2)
			(net 1 "GND")
			(pintype "passive")
		)
		(pad "2" smd roundrect
			(at 0.7 0 270)
			(size 0.8 1)
			(layers "B.Cu" "B.Mask" "B.Paste")
			(roundrect_rratio 0.2)
			(net 3 "VCC_USR_B")
			(pintype "passive")
		)
	)
	(footprint "antmicro-footprints:R_0402_1005Metric"
		(layer "B.Cu")
		(at 219.399999 77.899999 -90)
		(descr "Resistor SMD 0402")
		(tags "resistor SMD 0402")
		(property "Reference" "R122"
			(at -3.599999 -0.325001 90)
			(layer "B.SilkS")
			(effects
				(font
					(size 0.7 0.7)
					(thickness 0.15)
				)
				(justify left bottom mirror)
			)
		)
		(property "Value" "R_100R_0402"
			(at 0 -1.4 90)
			(layer "B.Fab")
			(effects
				(font
					(size 0.7 0.7)
					(thickness 0.15)
				)
				(justify left bottom mirror)
			)
		)
		(property "Description" "SMD Chip Resistor, 100 ohm, ± 1%, 62.5 mW, 0402 [1005 Metric], Thick Film, General Purpose"
			(at 0 0 270)
			(layer "F.Fab")
			(hide yes)
			(effects
				(font
					(size 1.27 1.27)
					(thickness 0.15)
				)
			)
		)
		(property "Author" "Antmicro"
			(at 141.5 297.299998 0)
			(layer "B.Fab")
			(hide yes)
			(effects
				(font
					(size 1 1)
					(thickness 0.15)
				)
				(justify mirror)
			)
		)
		(property "License" "Apache-2.0"
			(at 141.5 297.299998 0)
			(layer "B.Fab")
			(hide yes)
			(effects
				(font
					(size 1 1)
					(thickness 0.15)
				)
				(justify mirror)
			)
		)
		(property "MPN" "CR0402-FX-1000GLF"
			(at 141.5 297.299998 0)
			(layer "B.Fab")
			(hide yes)
			(effects
				(font
					(size 1 1)
					(thickness 0.15)
				)
				(justify mirror)
			)
		)
		(property "Manufacturer" "Bourns"
			(at 141.5 297.299998 0)
			(layer "B.Fab")
			(hide yes)
			(effects
				(font
					(size 1 1)
					(thickness 0.15)
				)
				(justify mirror)
			)
		)
		(property "Tolerance" "1%"
			(at 141.5 297.299998 0)
			(layer "B.Fab")
			(hide yes)
			(effects
				(font
					(size 1 1)
					(thickness 0.15)
				)
				(justify mirror)
			)
		)
		(property "Val" "100R"
			(at 141.5 297.299998 0)
			(layer "B.Fab")
			(hide yes)
			(effects
				(font
					(size 1 1)
					(thickness 0.15)
				)
				(justify mirror)
			)
		)
		(sheetname "User GPIO + LED + button + DIP switch")
		(sheetfile "user-gpio.kicad_sch")
		(attr smd)
		(fp_rect
			(start -0.925 0.47)
			(end 0.925 -0.47)
			(stroke
				(width 0.05)
				(type default)
			)
			(fill no)
			(layer "B.CrtYd")
		)
		(fp_rect
			(start -0.5 0.25)
			(end 0.5 -0.25)
			(stroke
				(width 0.15)
				(type solid)
			)
			(fill no)
			(layer "B.Fab")
		)
		(pad "1" smd roundrect
			(at -0.48 0 270)
			(size 0.59 0.64)
			(layers "B.Cu" "B.Mask" "B.Paste")
			(roundrect_rratio 0.25)
			(net 458 "/FPGA Bank 12 & 13/PMOD_A.IO3")
			(pintype "passive")
		)
		(pad "2" smd roundrect
			(at 0.48 0 270)
			(size 0.59 0.64)
			(layers "B.Cu" "B.Mask" "B.Paste")
			(roundrect_rratio 0.25)
			(net 805 "/User GPIO + LED + button + DIP switch/PMOD_A_3")
			(pintype "passive")
		)
	)
	(footprint "antmicro-footprints:R_0402_1005Metric"
		(layer "B.Cu")
		(at 170.25 169.3125 -90)
		(descr "Resistor SMD 0402")
		(tags "resistor SMD 0402")
		(property "Reference" "R301"
			(at 0.7375 -0.375 90)
			(layer "B.SilkS")
			(effects
				(font
					(size 0.7 0.7)
					(thickness 0.15)
				)
				(justify left bottom mirror)
			)
		)
		(property "Value" "R_0R_0402"
			(at 0 -1.4 90)
			(layer "B.Fab")
			(effects
				(font
					(size 0.7 0.7)
					(thickness 0.15)
				)
				(justify left bottom mirror)
			)
		)
		(property "Description" "SMD Chip Resistor, Jumper, 0 ohm, 100 mW, 0402 [1005 Metric], Thick Film, General Purpose"
			(at 0 0 270)
			(layer "F.Fab")
			(hide yes)
			(effects
				(font
					(size 1.27 1.27)
					(thickness 0.15)
				)
			)
		)
		(property "Author" "Antmicro"
			(at 0.9375 339.5625 0)
			(layer "B.Fab")
			(hide yes)
			(effects
				(font
					(size 1 1)
					(thickness 0.15)
				)
				(justify mirror)
			)
		)
		(property "Current" "1A"
			(at 0.9375 339.5625 0)
			(layer "B.Fab")
			(hide yes)
			(effects
				(font
					(size 1 1)
					(thickness 0.15)
				)
				(justify mirror)
			)
		)
		(property "DNP" "DNP"
			(at 0.9375 339.5625 0)
			(layer "B.Fab")
			(hide yes)
			(effects
				(font
					(size 1 1)
					(thickness 0.15)
				)
				(justify mirror)
			)
		)
		(property "License" "Apache-2.0"
			(at 0.9375 339.5625 0)
			(layer "B.Fab")
			(hide yes)
			(effects
				(font
					(size 1 1)
					(thickness 0.15)
				)
				(justify mirror)
			)
		)
		(property "MPN" "ERJ2GE0R00X"
			(at 0.9375 339.5625 0)
			(layer "B.Fab")
			(hide yes)
			(effects
				(font
					(size 1 1)
					(thickness 0.15)
				)
				(justify mirror)
			)
		)
		(property "Manufacturer" "Panasonic"
			(at 0.9375 339.5625 0)
			(layer "B.Fab")
			(hide yes)
			(effects
				(font
					(size 1 1)
					(thickness 0.15)
				)
				(justify mirror)
			)
		)
		(property "Tolerance" ""
			(at 0.9375 339.5625 0)
			(layer "B.Fab")
			(hide yes)
			(effects
				(font
					(size 1 1)
					(thickness 0.15)
				)
				(justify mirror)
			)
		)
		(property "Val" "0R"
			(at 0.9375 339.5625 0)
			(layer "B.Fab")
			(hide yes)
			(effects
				(font
					(size 1 1)
					(thickness 0.15)
				)
				(justify mirror)
			)
		)
		(property "dnp" ""
			(at 0.9375 339.5625 0)
			(layer "B.Fab")
			(hide yes)
			(effects
				(font
					(size 1 1)
					(thickness 0.15)
				)
				(justify mirror)
			)
		)
		(property "exclude_from_bom" ""
			(at 0.9375 339.5625 0)
			(layer "B.Fab")
			(hide yes)
			(effects
				(font
					(size 1 1)
					(thickness 0.15)
				)
				(justify mirror)
			)
		)
		(sheetname "DC-DC Converters")
		(sheetfile "dc-dc.kicad_sch")
		(attr smd exclude_from_bom)
		(fp_rect
			(start -0.925 0.47)
			(end 0.925 -0.47)
			(stroke
				(width 0.05)
				(type default)
			)
			(fill no)
			(layer "B.CrtYd")
		)
		(fp_rect
			(start -0.5 0.25)
			(end 0.5 -0.25)
			(stroke
				(width 0.15)
				(type solid)
			)
			(fill no)
			(layer "B.Fab")
		)
		(pad "1" smd roundrect
			(at -0.48 0 270)
			(size 0.59 0.64)
			(layers "B.Cu" "B.Mask" "B.Paste")
			(roundrect_rratio 0.25)
			(net 1217 "/DC-DC Converters/SENSE_3V3_1_N")
			(pintype "passive")
		)
		(pad "2" smd roundrect
			(at 0.48 0 270)
			(size 0.59 0.64)
			(layers "B.Cu" "B.Mask" "B.Paste")
			(roundrect_rratio 0.25)
			(net 958 "/DC-DC Converters/FB5")
			(pintype "passive")
		)
	)
	(footprint "antmicro-footprints:R_0402_1005Metric"
		(layer "B.Cu")
		(at 266.8 84 -90)
		(descr "Resistor SMD 0402")
		(tags "resistor SMD 0402")
		(property "Reference" "R141"
			(at -1.275 -1.3 90)
			(layer "B.SilkS")
			(effects
				(font
					(size 0.7 0.7)
					(thickness 0.15)
				)
				(justify left bottom mirror)
			)
		)
		(property "Value" "R_10k_0402"
			(at 0 -1.4 90)
			(layer "B.Fab")
			(effects
				(font
					(size 0.7 0.7)
					(thickness 0.15)
				)
				(justify left bottom mirror)
			)
		)
		(property "Description" "SMD Chip Resistor, 10 kohm, ± 1%, 62.5 mW, 0402 [1005 Metric], Thick Film, General Purpose"
			(at 0 0 270)
			(layer "F.Fab")
			(hide yes)
			(effects
				(font
					(size 1.27 1.27)
					(thickness 0.15)
				)
			)
		)
		(property "Author" "Antmicro"
			(at 182.8 350.8 0)
			(layer "B.Fab")
			(hide yes)
			(effects
				(font
					(size 1 1)
					(thickness 0.15)
				)
				(justify mirror)
			)
		)
		(property "License" "Apache-2.0"
			(at 182.8 350.8 0)
			(layer "B.Fab")
			(hide yes)
			(effects
				(font
					(size 1 1)
					(thickness 0.15)
				)
				(justify mirror)
			)
		)
		(property "MPN" "CR0402-FX-1002GLF"
			(at 182.8 350.8 0)
			(layer "B.Fab")
			(hide yes)
			(effects
				(font
					(size 1 1)
					(thickness 0.15)
				)
				(justify mirror)
			)
		)
		(property "Manufacturer" "Bourns"
			(at 182.8 350.8 0)
			(layer "B.Fab")
			(hide yes)
			(effects
				(font
					(size 1 1)
					(thickness 0.15)
				)
				(justify mirror)
			)
		)
		(property "Tolerance" "1%"
			(at 182.8 350.8 0)
			(layer "B.Fab")
			(hide yes)
			(effects
				(font
					(size 1 1)
					(thickness 0.15)
				)
				(justify mirror)
			)
		)
		(property "Val" "10k"
			(at 182.8 350.8 0)
			(layer "B.Fab")
			(hide yes)
			(effects
				(font
					(size 1 1)
					(thickness 0.15)
				)
				(justify mirror)
			)
		)
		(sheetname "User GPIO + LED + button + DIP switch")
		(sheetfile "user-gpio.kicad_sch")
		(attr smd)
		(fp_rect
			(start -0.925 0.47)
			(end 0.925 -0.47)
			(stroke
				(width 0.05)
				(type default)
			)
			(fill no)
			(layer "B.CrtYd")
		)
		(fp_rect
			(start -0.5 0.25)
			(end 0.5 -0.25)
			(stroke
				(width 0.15)
				(type solid)
			)
			(fill no)
			(layer "B.Fab")
		)
		(pad "1" smd roundrect
			(at -0.48 0 270)
			(size 0.59 0.64)
			(layers "B.Cu" "B.Mask" "B.Paste")
			(roundrect_rratio 0.25)
			(net 26 "+1V8")
			(pintype "passive")
		)
		(pad "2" smd roundrect
			(at 0.48 0 270)
			(size 0.59 0.64)
			(layers "B.Cu" "B.Mask" "B.Paste")
			(roundrect_rratio 0.25)
			(net 13 "/USER_IO.BUTTON1")
			(pintype "passive")
		)
	)
	(footprint "antmicro-footprints:NetTie-2_SMD_Pad0.127mm"
		(layer "B.Cu")
		(at 251.701 148.4 90)
		(descr "Net tie, 2 pin, 0.127mm  SMD pads")
		(tags "net tie")
		(property "Reference" "NT5"
			(at -0.128 1.345 270)
			(layer "B.SilkS")
			(hide yes)
			(effects
				(font
					(size 0.7 0.7)
					(thickness 0.15)
				)
				(justify left bottom mirror)
			)
		)
		(property "Value" "Net-Tie_2"
			(at 0 -1.199 270)
			(layer "B.Fab")
			(effects
				(font
					(size 0.7 0.7)
					(thickness 0.15)
				)
				(justify left bottom mirror)
			)
		)
		(property "Description" "Net tie, 2 pins"
			(at 0 0 90)
			(layer "F.Fab")
			(hide yes)
			(effects
				(font
					(size 1.27 1.27)
					(thickness 0.15)
				)
			)
		)
		(property "Author" "Antmicro"
			(at 400.101 -103.301 0)
			(layer "B.Fab")
			(hide yes)
			(effects
				(font
					(size 1 1)
					(thickness 0.15)
				)
				(justify mirror)
			)
		)
		(property "License" "Apache-2.0"
			(at 400.101 -103.301 0)
			(layer "B.Fab")
			(hide yes)
			(effects
				(font
					(size 1 1)
					(thickness 0.15)
				)
				(justify mirror)
			)
		)
		(property "MPN" ""
			(at 400.101 -103.301 0)
			(layer "B.Fab")
			(hide yes)
			(effects
				(font
					(size 1 1)
					(thickness 0.15)
				)
				(justify mirror)
			)
		)
		(property "Manufacturer" ""
			(at 400.101 -103.301 0)
			(layer "B.Fab")
			(hide yes)
			(effects
				(font
					(size 1 1)
					(thickness 0.15)
				)
				(justify mirror)
			)
		)
		(sheetname "FPGA Config")
		(sheetfile "fpga-config.kicad_sch")
		(attr exclude_from_pos_files)
		(net_tie_pad_groups "1, 2")
		(fp_poly
			(pts
				(xy -0.0635 0.0635) (xy 0.0625 0.0635) (xy 0.0625 -0.0635) (xy -0.0635 -0.0635)
			)
			(stroke
				(width 0)
				(type solid)
			)
			(fill yes)
			(layer "B.Cu")
		)
		(pad "1" smd roundrect
			(at -0.127 0 270)
			(size 0.127 0.127)
			(layers "B.Cu")
			(roundrect_rratio 0.5)
			(chamfer_ratio 0)
			(chamfer top_left bottom_left)
			(net 1314 "/SUP_MCU.FPGA_M2")
			(pinfunction "1")
			(pintype "passive")
		)
		(pad "2" smd roundrect
			(at 0.126 0 90)
			(size 0.127 0.127)
			(layers "B.Cu")
			(roundrect_rratio 0.5)
			(chamfer_ratio 0)
			(chamfer top_left bottom_left)
			(net 298 "/FPGA Config/MODE2")
			(pinfunction "2")
			(pintype "passive")
		)
	)
	(footprint "antmicro-footprints:R_0402_1005Metric"
		(layer "B.Cu")
		(at 221.999999 77.899999 -90)
		(descr "Resistor SMD 0402")
		(tags "resistor SMD 0402")
		(property "Reference" "R123"
			(at -3.599999 -0.350001 90)
			(layer "B.SilkS")
			(effects
				(font
					(size 0.7 0.7)
					(thickness 0.15)
				)
				(justify left bottom mirror)
			)
		)
		(property "Value" "R_100R_0402"
			(at 0 -1.4 90)
			(layer "B.Fab")
			(effects
				(font
					(size 0.7 0.7)
					(thickness 0.15)
				)
				(justify left bottom mirror)
			)
		)
		(property "Description" "SMD Chip Resistor, 100 ohm, ± 1%, 62.5 mW, 0402 [1005 Metric], Thick Film, General Purpose"
			(at 0 0 270)
			(layer "F.Fab")
			(hide yes)
			(effects
				(font
					(size 1.27 1.27)
					(thickness 0.15)
				)
			)
		)
		(property "Author" "Antmicro"
			(at 144.1 299.899998 0)
			(layer "B.Fab")
			(hide yes)
			(effects
				(font
					(size 1 1)
					(thickness 0.15)
				)
				(justify mirror)
			)
		)
		(property "License" "Apache-2.0"
			(at 144.1 299.899998 0)
			(layer "B.Fab")
			(hide yes)
			(effects
				(font
					(size 1 1)
					(thickness 0.15)
				)
				(justify mirror)
			)
		)
		(property "MPN" "CR0402-FX-1000GLF"
			(at 144.1 299.899998 0)
			(layer "B.Fab")
			(hide yes)
			(effects
				(font
					(size 1 1)
					(thickness 0.15)
				)
				(justify mirror)
			)
		)
		(property "Manufacturer" "Bourns"
			(at 144.1 299.899998 0)
			(layer "B.Fab")
			(hide yes)
			(effects
				(font
					(size 1 1)
					(thickness 0.15)
				)
				(justify mirror)
			)
		)
		(property "Tolerance" "1%"
			(at 144.1 299.899998 0)
			(layer "B.Fab")
			(hide yes)
			(effects
				(font
					(size 1 1)
					(thickness 0.15)
				)
				(justify mirror)
			)
		)
		(property "Val" "100R"
			(at 144.1 299.899998 0)
			(layer "B.Fab")
			(hide yes)
			(effects
				(font
					(size 1 1)
					(thickness 0.15)
				)
				(justify mirror)
			)
		)
		(sheetname "User GPIO + LED + button + DIP switch")
		(sheetfile "user-gpio.kicad_sch")
		(attr smd)
		(fp_rect
			(start -0.925 0.47)
			(end 0.925 -0.47)
			(stroke
				(width 0.05)
				(type default)
			)
			(fill no)
			(layer "B.CrtYd")
		)
		(fp_rect
			(start -0.5 0.25)
			(end 0.5 -0.25)
			(stroke
				(width 0.15)
				(type solid)
			)
			(fill no)
			(layer "B.Fab")
		)
		(pad "1" smd roundrect
			(at -0.48 0 270)
			(size 0.59 0.64)
			(layers "B.Cu" "B.Mask" "B.Paste")
			(roundrect_rratio 0.25)
			(net 461 "/FPGA Bank 12 & 13/PMOD_A.IO4")
			(pintype "passive")
		)
		(pad "2" smd roundrect
			(at 0.48 0 270)
			(size 0.59 0.64)
			(layers "B.Cu" "B.Mask" "B.Paste")
			(roundrect_rratio 0.25)
			(net 803 "/User GPIO + LED + button + DIP switch/PMOD_A_4")
			(pintype "passive")
		)
	)
	(footprint "antmicro-footprints:NetTie-2_SMD_Pad0.127mm"
		(layer "B.Cu")
		(at 250.101 148.4 -90)
		(descr "Net tie, 2 pin, 0.127mm  SMD pads")
		(tags "net tie")
		(property "Reference" "NT13"
			(at -0.128 1.345 90)
			(layer "B.SilkS")
			(hide yes)
			(effects
				(font
					(size 0.7 0.7)
					(thickness 0.15)
				)
				(justify left bottom mirror)
			)
		)
		(property "Value" "Net-Tie_2"
			(at 0 -1.199 90)
			(layer "B.Fab")
			(effects
				(font
					(size 0.7 0.7)
					(thickness 0.15)
				)
				(justify left bottom mirror)
			)
		)
		(property "Description" "Net tie, 2 pins"
			(at 0 0 270)
			(layer "F.Fab")
			(hide yes)
			(effects
				(font
					(size 1.27 1.27)
					(thickness 0.15)
				)
			)
		)
		(property "Author" "Antmicro"
			(at 101.701 398.501 0)
			(layer "B.Fab")
			(hide yes)
			(effects
				(font
					(size 1 1)
					(thickness 0.15)
				)
				(justify mirror)
			)
		)
		(property "License" "Apache-2.0"
			(at 101.701 398.501 0)
			(layer "B.Fab")
			(hide yes)
			(effects
				(font
					(size 1 1)
					(thickness 0.15)
				)
				(justify mirror)
			)
		)
		(property "MPN" ""
			(at 101.701 398.501 0)
			(layer "B.Fab")
			(hide yes)
			(effects
				(font
					(size 1 1)
					(thickness 0.15)
				)
				(justify mirror)
			)
		)
		(property "Manufacturer" ""
			(at 101.701 398.501 0)
			(layer "B.Fab")
			(hide yes)
			(effects
				(font
					(size 1 1)
					(thickness 0.15)
				)
				(justify mirror)
			)
		)
		(sheetname "FPGA Bank 14 & 15")
		(sheetfile "fpga-bank-14-15.kicad_sch")
		(attr exclude_from_pos_files)
		(net_tie_pad_groups "1, 2")
		(fp_poly
			(pts
				(xy -0.0635 0.0635) (xy 0.0625 0.0635) (xy 0.0625 -0.0635) (xy -0.0635 -0.0635)
			)
			(stroke
				(width 0)
				(type solid)
			)
			(fill yes)
			(layer "B.Cu")
		)
		(pad "1" smd roundrect
			(at -0.127 0 90)
			(size 0.127 0.127)
			(layers "B.Cu")
			(roundrect_rratio 0.5)
			(chamfer_ratio 0)
			(chamfer top_left bottom_left)
			(net 38 "/FPGA Bank 14 & 15/SYSTEM_FLASH.DQ0")
			(pinfunction "1")
			(pintype "passive")
		)
		(pad "2" smd roundrect
			(at 0.126 0 270)
			(size 0.127 0.127)
			(layers "B.Cu")
			(roundrect_rratio 0.5)
			(chamfer_ratio 0)
			(chamfer top_left bottom_left)
			(net 1326 "/SUP_MCU.FPGA_MISO")
			(pinfunction "2")
			(pintype "passive")
		)
	)
	(footprint "antmicro-footprints:R_0402_1005Metric"
		(layer "B.Cu")
		(at 186.800001 84.800001 90)
		(descr "Resistor SMD 0402")
		(tags "resistor SMD 0402")
		(property "Reference" "R134"
			(at -0.725 0.4 270)
			(layer "B.SilkS")
			(effects
				(font
					(size 0.7 0.7)
					(thickness 0.15)
				)
				(justify left bottom mirror)
			)
		)
		(property "Value" "R_100R_0402"
			(at 0 -1.4 270)
			(layer "B.Fab")
			(effects
				(font
					(size 0.7 0.7)
					(thickness 0.15)
				)
				(justify left bottom mirror)
			)
		)
		(property "Description" "SMD Chip Resistor, 100 ohm, ± 1%, 62.5 mW, 0402 [1005 Metric], Thick Film, General Purpose"
			(at 0 0 90)
			(layer "F.Fab")
			(hide yes)
			(effects
				(font
					(size 1.27 1.27)
					(thickness 0.15)
				)
			)
		)
		(property "Author" "Antmicro"
			(at 271.600002 -102 0)
			(layer "B.Fab")
			(hide yes)
			(effects
				(font
					(size 1 1)
					(thickness 0.15)
				)
				(justify mirror)
			)
		)
		(property "License" "Apache-2.0"
			(at 271.600002 -102 0)
			(layer "B.Fab")
			(hide yes)
			(effects
				(font
					(size 1 1)
					(thickness 0.15)
				)
				(justify mirror)
			)
		)
		(property "MPN" "CR0402-FX-1000GLF"
			(at 271.600002 -102 0)
			(layer "B.Fab")
			(hide yes)
			(effects
				(font
					(size 1 1)
					(thickness 0.15)
				)
				(justify mirror)
			)
		)
		(property "Manufacturer" "Bourns"
			(at 271.600002 -102 0)
			(layer "B.Fab")
			(hide yes)
			(effects
				(font
					(size 1 1)
					(thickness 0.15)
				)
				(justify mirror)
			)
		)
		(property "Tolerance" "1%"
			(at 271.600002 -102 0)
			(layer "B.Fab")
			(hide yes)
			(effects
				(font
					(size 1 1)
					(thickness 0.15)
				)
				(justify mirror)
			)
		)
		(property "Val" "100R"
			(at 271.600002 -102 0)
			(layer "B.Fab")
			(hide yes)
			(effects
				(font
					(size 1 1)
					(thickness 0.15)
				)
				(justify mirror)
			)
		)
		(sheetname "User GPIO + LED + button + DIP switch")
		(sheetfile "user-gpio.kicad_sch")
		(attr smd)
		(fp_rect
			(start -0.925 0.47)
			(end 0.925 -0.47)
			(stroke
				(width 0.05)
				(type default)
			)
			(fill no)
			(layer "B.CrtYd")
		)
		(fp_rect
			(start -0.5 0.25)
			(end 0.5 -0.25)
			(stroke
				(width 0.15)
				(type solid)
			)
			(fill no)
			(layer "B.Fab")
		)
		(pad "1" smd roundrect
			(at -0.48 0 90)
			(size 0.59 0.64)
			(layers "B.Cu" "B.Mask" "B.Paste")
			(roundrect_rratio 0.25)
			(net 823 "/User GPIO + LED + button + DIP switch/CW_20PIN_RST")
			(pintype "passive")
		)
		(pad "2" smd roundrect
			(at 0.48 0 90)
			(size 0.59 0.64)
			(layers "B.Cu" "B.Mask" "B.Paste")
			(roundrect_rratio 0.25)
			(net 474 "/FPGA Bank 12 & 13/CW_HEADER.RST")
			(pintype "passive")
		)
	)
	(footprint "antmicro-footprints:R_0402_1005Metric"
		(layer "B.Cu")
		(at 261.5 88.6)
		(descr "Resistor SMD 0402")
		(tags "resistor SMD 0402")
		(property "Reference" "R109"
			(at 1.375 1.275 180)
			(layer "B.SilkS")
			(effects
				(font
					(size 0.7 0.7)
					(thickness 0.15)
				)
				(justify left bottom mirror)
			)
		)
		(property "Value" "R_1k_0402"
			(at 0 -1.4 180)
			(layer "B.Fab")
			(effects
				(font
					(size 0.7 0.7)
					(thickness 0.15)
				)
				(justify left bottom mirror)
			)
		)
		(property "Description" "SMD Chip Resistor, 1 kohm, ± 1%, 63 mW, 0402 [1005 Metric], Thick Film, General Purpose"
			(at 0 0 0)
			(layer "F.Fab")
			(hide yes)
			(effects
				(font
					(size 1.27 1.27)
					(thickness 0.15)
				)
			)
		)
		(property "Author" "Antmicro"
			(at 0 0 0)
			(layer "B.Fab")
			(hide yes)
			(effects
				(font
					(size 1 1)
					(thickness 0.15)
				)
				(justify mirror)
			)
		)
		(property "License" "Apache-2.0"
			(at 0 0 0)
			(layer "B.Fab")
			(hide yes)
			(effects
				(font
					(size 1 1)
					(thickness 0.15)
				)
				(justify mirror)
			)
		)
		(property "MPN" "CR0402-FX-1001GLF"
			(at 0 0 0)
			(layer "B.Fab")
			(hide yes)
			(effects
				(font
					(size 1 1)
					(thickness 0.15)
				)
				(justify mirror)
			)
		)
		(property "Manufacturer" "Bourns"
			(at 0 0 0)
			(layer "B.Fab")
			(hide yes)
			(effects
				(font
					(size 1 1)
					(thickness 0.15)
				)
				(justify mirror)
			)
		)
		(property "Tolerance" "1%"
			(at 0 0 0)
			(layer "B.Fab")
			(hide yes)
			(effects
				(font
					(size 1 1)
					(thickness 0.15)
				)
				(justify mirror)
			)
		)
		(property "Val" "1k"
			(at 0 0 0)
			(layer "B.Fab")
			(hide yes)
			(effects
				(font
					(size 1 1)
					(thickness 0.15)
				)
				(justify mirror)
			)
		)
		(sheetname "User GPIO + LED + button + DIP switch")
		(sheetfile "user-gpio.kicad_sch")
		(attr smd)
		(fp_rect
			(start -0.925 0.47)
			(end 0.925 -0.47)
			(stroke
				(width 0.05)
				(type default)
			)
			(fill no)
			(layer "B.CrtYd")
		)
		(fp_rect
			(start -0.5 0.25)
			(end 0.5 -0.25)
			(stroke
				(width 0.15)
				(type solid)
			)
			(fill no)
			(layer "B.Fab")
		)
		(pad "1" smd roundrect
			(at -0.48 0)
			(size 0.59 0.64)
			(layers "B.Cu" "B.Mask" "B.Paste")
			(roundrect_rratio 0.25)
			(net 24 "+3V3")
			(pintype "passive")
		)
		(pad "2" smd roundrect
			(at 0.48 0)
			(size 0.59 0.64)
			(layers "B.Cu" "B.Mask" "B.Paste")
			(roundrect_rratio 0.25)
			(net 779 "Net-(D20-A)")
			(pintype "passive")
		)
	)
	(footprint "antmicro-footprints:C_0201"
		(layer "B.Cu")
		(at 188.000001 120.500001 180)
		(descr "Capacitor SMD 0201")
		(tags "capacitor SMD 0201")
		(property "Reference" "C150"
			(at 0.575001 -0.349999 0)
			(layer "B.SilkS")
			(effects
				(font
					(size 0.7 0.7)
					(thickness 0.15)
				)
				(justify left bottom mirror)
			)
		)
		(property "Value" "C_100n_0201"
			(at 0 -1.4 0)
			(layer "B.Fab")
			(effects
				(font
					(size 0.7 0.7)
					(thickness 0.15)
				)
				(justify left bottom mirror)
			)
		)
		(property "Description" "SMD Multilayer Ceramic Capacitor, 0.1 µF, 6.3 V, 0201 [0603 Metric], ± 10%, X6S, CC Series"
			(at 0 0 180)
			(layer "F.Fab")
			(hide yes)
			(effects
				(font
					(size 1.27 1.27)
					(thickness 0.15)
				)
			)
		)
		(property "Author" "Antmicro"
			(at 376.000002 241.000002 0)
			(layer "B.Fab")
			(hide yes)
			(effects
				(font
					(size 1 1)
					(thickness 0.15)
				)
				(justify mirror)
			)
		)
		(property "Dielectric" ""
			(at 376.000002 241.000002 0)
			(layer "B.Fab")
			(hide yes)
			(effects
				(font
					(size 1 1)
					(thickness 0.15)
				)
				(justify mirror)
			)
		)
		(property "License" "Apache-2.0"
			(at 376.000002 241.000002 0)
			(layer "B.Fab")
			(hide yes)
			(effects
				(font
					(size 1 1)
					(thickness 0.15)
				)
				(justify mirror)
			)
		)
		(property "MPN" "CC0201KRX6S5BB104"
			(at 376.000002 241.000002 0)
			(layer "B.Fab")
			(hide yes)
			(effects
				(font
					(size 1 1)
					(thickness 0.15)
				)
				(justify mirror)
			)
		)
		(property "Manufacturer" "YAGEO"
			(at 376.000002 241.000002 0)
			(layer "B.Fab")
			(hide yes)
			(effects
				(font
					(size 1 1)
					(thickness 0.15)
				)
				(justify mirror)
			)
		)
		(property "Val" "100n"
			(at 376.000002 241.000002 0)
			(layer "B.Fab")
			(hide yes)
			(effects
				(font
					(size 1 1)
					(thickness 0.15)
				)
				(justify mirror)
			)
		)
		(property "Voltage" ""
			(at 376.000002 241.000002 0)
			(layer "B.Fab")
			(hide yes)
			(effects
				(font
					(size 1 1)
					(thickness 0.15)
				)
				(justify mirror)
			)
		)
		(sheetname "FPGA supply")
		(sheetfile "fpga-supply.kicad_sch")
		(attr smd)
		(fp_rect
			(start -0.7 0.35)
			(end 0.7 -0.35)
			(stroke
				(width 0.05)
				(type default)
			)
			(fill no)
			(layer "B.CrtYd")
		)
		(fp_rect
			(start 0.3 -0.15)
			(end -0.301 0.149)
			(stroke
				(width 0.15)
				(type solid)
			)
			(fill no)
			(layer "B.Fab")
		)
		(pad "" smd roundrect
			(at -0.349 0.002 180)
			(size 0.318 0.36)
			(layers "B.Paste")
			(roundrect_rratio 0.25)
		)
		(pad "" smd roundrect
			(at 0.341 0.002 180)
			(size 0.318 0.36)
			(layers "B.Paste")
			(roundrect_rratio 0.25)
		)
		(pad "1" smd roundrect
			(at -0.321 0.002 180)
			(size 0.46 0.4)
			(layers "B.Cu" "B.Mask")
			(roundrect_rratio 0.25)
			(net 1 "GND")
			(pintype "passive")
		)
		(pad "2" smd roundrect
			(at 0.32 0.002 180)
			(size 0.46 0.4)
			(layers "B.Cu" "B.Mask")
			(roundrect_rratio 0.25)
			(net 8 "+1V2_MGTAVTT")
			(pintype "passive")
		)
	)
	(footprint "antmicro-footprints:C_0402_1005Metric"
		(layer "B.Cu")
		(at 194.85 132.225 180)
		(descr "Capacitor SMD 0402")
		(tags "capacitor SMD 0402")
		(property "Reference" "C114"
			(at -24.475 28.075 0)
			(layer "B.SilkS")
			(effects
				(font
					(size 0.7 0.7)
					(thickness 0.15)
				)
				(justify left bottom mirror)
			)
		)
		(property "Value" "C_100n_0402"
			(at 0 -1.169 0)
			(layer "B.Fab")
			(effects
				(font
					(size 0.7 0.7)
					(thickness 0.15)
				)
				(justify left bottom mirror)
			)
		)
		(property "Description" "SMD Multilayer Ceramic Capacitor, 0.1 µF, 50 V, 0402 [1005 Metric], ± 10%, X5R, GRM Series"
			(at 0 0 180)
			(layer "F.Fab")
			(hide yes)
			(effects
				(font
					(size 1.27 1.27)
					(thickness 0.15)
				)
			)
		)
		(property "Author" "Antmicro"
			(at 389.7 264.45 0)
			(layer "B.Fab")
			(hide yes)
			(effects
				(font
					(size 1 1)
					(thickness 0.15)
				)
				(justify mirror)
			)
		)
		(property "Dielectric" "X5R"
			(at 389.7 264.45 0)
			(layer "B.Fab")
			(hide yes)
			(effects
				(font
					(size 1 1)
					(thickness 0.15)
				)
				(justify mirror)
			)
		)
		(property "License" "Apache-2.0"
			(at 389.7 264.45 0)
			(layer "B.Fab")
			(hide yes)
			(effects
				(font
					(size 1 1)
					(thickness 0.15)
				)
				(justify mirror)
			)
		)
		(property "MPN" "GRM155R61H104KE14D"
			(at 389.7 264.45 0)
			(layer "B.Fab")
			(hide yes)
			(effects
				(font
					(size 1 1)
					(thickness 0.15)
				)
				(justify mirror)
			)
		)
		(property "Manufacturer" "Murata"
			(at 389.7 264.45 0)
			(layer "B.Fab")
			(hide yes)
			(effects
				(font
					(size 1 1)
					(thickness 0.15)
				)
				(justify mirror)
			)
		)
		(property "Val" "100n"
			(at 389.7 264.45 0)
			(layer "B.Fab")
			(hide yes)
			(effects
				(font
					(size 1 1)
					(thickness 0.15)
				)
				(justify mirror)
			)
		)
		(property "Voltage" "50V"
			(at 389.7 264.45 0)
			(layer "B.Fab")
			(hide yes)
			(effects
				(font
					(size 1 1)
					(thickness 0.15)
				)
				(justify mirror)
			)
		)
		(sheetname "FPGA supply")
		(sheetfile "fpga-supply.kicad_sch")
		(attr smd)
		(fp_rect
			(start -0.925 0.47)
			(end 0.925 -0.47)
			(stroke
				(width 0.05)
				(type default)
			)
			(fill no)
			(layer "B.CrtYd")
		)
		(fp_line
			(start 0.504 0.25)
			(end 0.504 -0.248)
			(stroke
				(width 0.15)
				(type solid)
			)
			(layer "B.Fab")
		)
		(fp_line
			(start 0.504 -0.248)
			(end -0.494 -0.248)
			(stroke
				(width 0.15)
				(type solid)
			)
			(layer "B.Fab")
		)
		(fp_line
			(start -0.494 0.25)
			(end 0.504 0.25)
			(stroke
				(width 0.15)
				(type solid)
			)
			(layer "B.Fab")
		)
		(fp_line
			(start -0.494 -0.248)
			(end -0.494 0.25)
			(stroke
				(width 0.15)
				(type solid)
			)
			(layer "B.Fab")
		)
		(pad "1" smd roundrect
			(at -0.48 0 180)
			(size 0.59 0.64)
			(layers "B.Cu" "B.Mask" "B.Paste")
			(roundrect_rratio 0.25)
			(net 1 "GND")
			(pintype "passive")
		)
		(pad "2" smd roundrect
			(at 0.48 0 180)
			(size 0.59 0.64)
			(layers "B.Cu" "B.Mask" "B.Paste")
			(roundrect_rratio 0.25)
			(net 650 "+1V0")
			(pintype "passive")
		)
	)
	(footprint "antmicro-footprints:C_0201"
		(layer "B.Cu")
		(at 201.5 132.05 180)
		(descr "Capacitor SMD 0201")
		(tags "capacitor SMD 0201")
		(property "Reference" "C65"
			(at -26.875 28.525 0)
			(layer "B.SilkS")
			(effects
				(font
					(size 0.7 0.7)
					(thickness 0.15)
				)
				(justify left bottom mirror)
			)
		)
		(property "Value" "C_100n_0201"
			(at 0 -1.4 0)
			(layer "B.Fab")
			(effects
				(font
					(size 0.7 0.7)
					(thickness 0.15)
				)
				(justify left bottom mirror)
			)
		)
		(property "Description" "SMD Multilayer Ceramic Capacitor, 0.1 µF, 6.3 V, 0201 [0603 Metric], ± 10%, X6S, CC Series"
			(at 0 0 180)
			(layer "F.Fab")
			(hide yes)
			(effects
				(font
					(size 1.27 1.27)
					(thickness 0.15)
				)
			)
		)
		(property "Author" "Antmicro"
			(at 403 264.1 0)
			(layer "B.Fab")
			(hide yes)
			(effects
				(font
					(size 1 1)
					(thickness 0.15)
				)
				(justify mirror)
			)
		)
		(property "Dielectric" ""
			(at 403 264.1 0)
			(layer "B.Fab")
			(hide yes)
			(effects
				(font
					(size 1 1)
					(thickness 0.15)
				)
				(justify mirror)
			)
		)
		(property "License" "Apache-2.0"
			(at 403 264.1 0)
			(layer "B.Fab")
			(hide yes)
			(effects
				(font
					(size 1 1)
					(thickness 0.15)
				)
				(justify mirror)
			)
		)
		(property "MPN" "CC0201KRX6S5BB104"
			(at 403 264.1 0)
			(layer "B.Fab")
			(hide yes)
			(effects
				(font
					(size 1 1)
					(thickness 0.15)
				)
				(justify mirror)
			)
		)
		(property "Manufacturer" "YAGEO"
			(at 403 264.1 0)
			(layer "B.Fab")
			(hide yes)
			(effects
				(font
					(size 1 1)
					(thickness 0.15)
				)
				(justify mirror)
			)
		)
		(property "Val" "100n"
			(at 403 264.1 0)
			(layer "B.Fab")
			(hide yes)
			(effects
				(font
					(size 1 1)
					(thickness 0.15)
				)
				(justify mirror)
			)
		)
		(property "Voltage" ""
			(at 403 264.1 0)
			(layer "B.Fab")
			(hide yes)
			(effects
				(font
					(size 1 1)
					(thickness 0.15)
				)
				(justify mirror)
			)
		)
		(sheetname "FPGA supply")
		(sheetfile "fpga-supply.kicad_sch")
		(attr smd)
		(fp_rect
			(start -0.7 0.35)
			(end 0.7 -0.35)
			(stroke
				(width 0.05)
				(type default)
			)
			(fill no)
			(layer "B.CrtYd")
		)
		(fp_rect
			(start 0.3 -0.15)
			(end -0.301 0.149)
			(stroke
				(width 0.15)
				(type solid)
			)
			(fill no)
			(layer "B.Fab")
		)
		(pad "" smd roundrect
			(at -0.349 0.002 180)
			(size 0.318 0.36)
			(layers "B.Paste")
			(roundrect_rratio 0.25)
		)
		(pad "" smd roundrect
			(at 0.341 0.002 180)
			(size 0.318 0.36)
			(layers "B.Paste")
			(roundrect_rratio 0.25)
		)
		(pad "1" smd roundrect
			(at -0.321 0.002 180)
			(size 0.46 0.4)
			(layers "B.Cu" "B.Mask")
			(roundrect_rratio 0.25)
			(net 1 "GND")
			(pintype "passive")
		)
		(pad "2" smd roundrect
			(at 0.32 0.002 180)
			(size 0.46 0.4)
			(layers "B.Cu" "B.Mask")
			(roundrect_rratio 0.25)
			(net 650 "+1V0")
			(pintype "passive")
		)
	)
	(footprint "antmicro-footprints:C_0402_1005Metric"
		(layer "B.Cu")
		(at 211 123.5 180)
		(descr "Capacitor SMD 0402")
		(tags "capacitor SMD 0402")
		(property "Reference" "C38"
			(at -1 0.475 0)
			(layer "B.SilkS")
			(effects
				(font
					(size 0.7 0.7)
					(thickness 0.15)
				)
				(justify left bottom mirror)
			)
		)
		(property "Value" "C_100n_0402"
			(at 0 -1.169 0)
			(layer "B.Fab")
			(effects
				(font
					(size 0.7 0.7)
					(thickness 0.15)
				)
				(justify left bottom mirror)
			)
		)
		(property "Description" "SMD Multilayer Ceramic Capacitor, 0.1 µF, 50 V, 0402 [1005 Metric], ± 10%, X5R, GRM Series"
			(at 0 0 180)
			(layer "F.Fab")
			(hide yes)
			(effects
				(font
					(size 1.27 1.27)
					(thickness 0.15)
				)
			)
		)
		(property "Author" "Antmicro"
			(at 422 247 0)
			(layer "B.Fab")
			(hide yes)
			(effects
				(font
					(size 1 1)
					(thickness 0.15)
				)
				(justify mirror)
			)
		)
		(property "Dielectric" "X5R"
			(at 422 247 0)
			(layer "B.Fab")
			(hide yes)
			(effects
				(font
					(size 1 1)
					(thickness 0.15)
				)
				(justify mirror)
			)
		)
		(property "License" "Apache-2.0"
			(at 422 247 0)
			(layer "B.Fab")
			(hide yes)
			(effects
				(font
					(size 1 1)
					(thickness 0.15)
				)
				(justify mirror)
			)
		)
		(property "MPN" "GRM155R61H104KE14D"
			(at 422 247 0)
			(layer "B.Fab")
			(hide yes)
			(effects
				(font
					(size 1 1)
					(thickness 0.15)
				)
				(justify mirror)
			)
		)
		(property "Manufacturer" "Murata"
			(at 422 247 0)
			(layer "B.Fab")
			(hide yes)
			(effects
				(font
					(size 1 1)
					(thickness 0.15)
				)
				(justify mirror)
			)
		)
		(property "Val" "100n"
			(at 422 247 0)
			(layer "B.Fab")
			(hide yes)
			(effects
				(font
					(size 1 1)
					(thickness 0.15)
				)
				(justify mirror)
			)
		)
		(property "Voltage" "50V"
			(at 422 247 0)
			(layer "B.Fab")
			(hide yes)
			(effects
				(font
					(size 1 1)
					(thickness 0.15)
				)
				(justify mirror)
			)
		)
		(sheetname "FPGA Bank 14 & 15")
		(sheetfile "fpga-bank-14-15.kicad_sch")
		(attr smd)
		(fp_rect
			(start -0.925 0.47)
			(end 0.925 -0.47)
			(stroke
				(width 0.05)
				(type default)
			)
			(fill no)
			(layer "B.CrtYd")
		)
		(fp_line
			(start 0.504 0.25)
			(end 0.504 -0.248)
			(stroke
				(width 0.15)
				(type solid)
			)
			(layer "B.Fab")
		)
		(fp_line
			(start 0.504 -0.248)
			(end -0.494 -0.248)
			(stroke
				(width 0.15)
				(type solid)
			)
			(layer "B.Fab")
		)
		(fp_line
			(start -0.494 0.25)
			(end 0.504 0.25)
			(stroke
				(width 0.15)
				(type solid)
			)
			(layer "B.Fab")
		)
		(fp_line
			(start -0.494 -0.248)
			(end -0.494 0.25)
			(stroke
				(width 0.15)
				(type solid)
			)
			(layer "B.Fab")
		)
		(pad "1" smd roundrect
			(at -0.48 0 180)
			(size 0.59 0.64)
			(layers "B.Cu" "B.Mask" "B.Paste")
			(roundrect_rratio 0.25)
			(net 1 "GND")
			(pintype "passive")
		)
		(pad "2" smd roundrect
			(at 0.48 0 180)
			(size 0.59 0.64)
			(layers "B.Cu" "B.Mask" "B.Paste")
			(roundrect_rratio 0.25)
			(net 2 "VCC_USR_A")
			(pintype "passive")
		)
	)
	(footprint "antmicro-footprints:R_0402_1005Metric"
		(layer "B.Cu")
		(at 167.55 185.95 -90)
		(descr "Resistor SMD 0402")
		(tags "resistor SMD 0402")
		(property "Reference" "R321"
			(at -3.625 -0.525 90)
			(layer "B.SilkS")
			(effects
				(font
					(size 0.7 0.7)
					(thickness 0.15)
				)
				(justify left bottom mirror)
			)
		)
		(property "Value" "R_47k_0402"
			(at 0 -1.4 90)
			(layer "B.Fab")
			(effects
				(font
					(size 0.7 0.7)
					(thickness 0.15)
				)
				(justify left bottom mirror)
			)
		)
		(property "Description" "SMD Chip Resistor, 47 kohm, ± 1%, 62.5 mW, 0402 [1005 Metric], Thick Film, General Purpose"
			(at 0 0 270)
			(layer "F.Fab")
			(hide yes)
			(effects
				(font
					(size 1.27 1.27)
					(thickness 0.15)
				)
			)
		)
		(property "Author" "Antmicro"
			(at -18.4 353.5 0)
			(layer "B.Fab")
			(hide yes)
			(effects
				(font
					(size 1 1)
					(thickness 0.15)
				)
				(justify mirror)
			)
		)
		(property "License" "Apache-2.0"
			(at -18.4 353.5 0)
			(layer "B.Fab")
			(hide yes)
			(effects
				(font
					(size 1 1)
					(thickness 0.15)
				)
				(justify mirror)
			)
		)
		(property "MPN" "CR0402-FX-4702GLF"
			(at -18.4 353.5 0)
			(layer "B.Fab")
			(hide yes)
			(effects
				(font
					(size 1 1)
					(thickness 0.15)
				)
				(justify mirror)
			)
		)
		(property "Manufacturer" "Bourns"
			(at -18.4 353.5 0)
			(layer "B.Fab")
			(hide yes)
			(effects
				(font
					(size 1 1)
					(thickness 0.15)
				)
				(justify mirror)
			)
		)
		(property "Tolerance" "1%"
			(at -18.4 353.5 0)
			(layer "B.Fab")
			(hide yes)
			(effects
				(font
					(size 1 1)
					(thickness 0.15)
				)
				(justify mirror)
			)
		)
		(property "Val" "47k"
			(at -18.4 353.5 0)
			(layer "B.Fab")
			(hide yes)
			(effects
				(font
					(size 1 1)
					(thickness 0.15)
				)
				(justify mirror)
			)
		)
		(sheetname "DC-DC Converters")
		(sheetfile "dc-dc.kicad_sch")
		(attr smd)
		(fp_rect
			(start -0.925 0.47)
			(end 0.925 -0.47)
			(stroke
				(width 0.05)
				(type default)
			)
			(fill no)
			(layer "B.CrtYd")
		)
		(fp_rect
			(start -0.5 0.25)
			(end 0.5 -0.25)
			(stroke
				(width 0.15)
				(type solid)
			)
			(fill no)
			(layer "B.Fab")
		)
		(pad "1" smd roundrect
			(at -0.48 0 270)
			(size 0.59 0.64)
			(layers "B.Cu" "B.Mask" "B.Paste")
			(roundrect_rratio 0.25)
			(net 967 "/DC-DC Converters/EN2")
			(pintype "passive")
		)
		(pad "2" smd roundrect
			(at 0.48 0 270)
			(size 0.59 0.64)
			(layers "B.Cu" "B.Mask" "B.Paste")
			(roundrect_rratio 0.25)
			(net 37 "+3V3_AON")
			(pintype "passive")
		)
	)
	(footprint "antmicro-footprints:C_0603_1608Metric"
		(layer "B.Cu")
		(at 200 139.2 90)
		(descr "Capacitor SMD 0603")
		(tags "capacitor 0603")
		(property "Reference" "C46"
			(at -1.025 -0.55 90)
			(layer "B.SilkS")
			(effects
				(font
					(size 0.7 0.7)
					(thickness 0.15)
				)
				(justify right bottom mirror)
			)
		)
		(property "Value" "C_47u_0603"
			(at 0 -1.6 90)
			(layer "B.Fab")
			(effects
				(font
					(size 0.7 0.7)
					(thickness 0.15)
				)
				(justify right bottom mirror)
			)
		)
		(property "Description" "SMD Multilayer Ceramic Capacitor, 47 µF, 6.3 V, 0603 [1608 Metric], ± 20%, X5R, GRM Series"
			(at 0 0 90)
			(layer "F.Fab")
			(hide yes)
			(effects
				(font
					(size 1.27 1.27)
					(thickness 0.15)
				)
			)
		)
		(property "Author" "Antmicro"
			(at 339.2 -60.8 0)
			(layer "B.Fab")
			(hide yes)
			(effects
				(font
					(size 1 1)
					(thickness 0.15)
				)
				(justify mirror)
			)
		)
		(property "Dielectric" ""
			(at 339.2 -60.8 0)
			(layer "B.Fab")
			(hide yes)
			(effects
				(font
					(size 1 1)
					(thickness 0.15)
				)
				(justify mirror)
			)
		)
		(property "License" "Apache-2.0"
			(at 339.2 -60.8 0)
			(layer "B.Fab")
			(hide yes)
			(effects
				(font
					(size 1 1)
					(thickness 0.15)
				)
				(justify mirror)
			)
		)
		(property "MPN" "GRM188R60J476ME15D"
			(at 339.2 -60.8 0)
			(layer "B.Fab")
			(hide yes)
			(effects
				(font
					(size 1 1)
					(thickness 0.15)
				)
				(justify mirror)
			)
		)
		(property "Manufacturer" "Murata"
			(at 339.2 -60.8 0)
			(layer "B.Fab")
			(hide yes)
			(effects
				(font
					(size 1 1)
					(thickness 0.15)
				)
				(justify mirror)
			)
		)
		(property "Val" "47u"
			(at 339.2 -60.8 0)
			(layer "B.Fab")
			(hide yes)
			(effects
				(font
					(size 1 1)
					(thickness 0.15)
				)
				(justify mirror)
			)
		)
		(property "Voltage" ""
			(at 339.2 -60.8 0)
			(layer "B.Fab")
			(hide yes)
			(effects
				(font
					(size 1 1)
					(thickness 0.15)
				)
				(justify mirror)
			)
		)
		(sheetname "FPGA supply")
		(sheetfile "fpga-supply.kicad_sch")
		(attr smd)
		(fp_line
			(start -0.15 -0.4)
			(end 0.15 -0.4)
			(stroke
				(width 0.15)
				(type solid)
			)
			(layer "B.SilkS")
		)
		(fp_line
			(start -0.15 0.4)
			(end 0.15 0.4)
			(stroke
				(width 0.15)
				(type solid)
			)
			(layer "B.SilkS")
		)
		(fp_rect
			(start -1.25 0.65)
			(end 1.25 -0.65)
			(stroke
				(width 0.05)
				(type solid)
			)
			(fill no)
			(layer "B.CrtYd")
		)
		(fp_rect
			(start -0.8 0.4)
			(end 0.8 -0.4)
			(stroke
				(width 0.15)
				(type solid)
			)
			(fill no)
			(layer "B.Fab")
		)
		(pad "1" smd roundrect
			(at -0.7 0 90)
			(size 0.8 1)
			(layers "B.Cu" "B.Mask" "B.Paste")
			(roundrect_rratio 0.2)
			(net 1 "GND")
			(pintype "passive")
		)
		(pad "2" smd roundrect
			(at 0.7 0 90)
			(size 0.8 1)
			(layers "B.Cu" "B.Mask" "B.Paste")
			(roundrect_rratio 0.2)
			(net 26 "+1V8")
			(pintype "passive")
		)
	)
	(footprint "antmicro-footprints:R_0402_1005Metric"
		(layer "B.Cu")
		(at 261.5 81.4)
		(descr "Resistor SMD 0402")
		(tags "resistor SMD 0402")
		(property "Reference" "R131"
			(at 1.45 1.25 180)
			(layer "B.SilkS")
			(effects
				(font
					(size 0.7 0.7)
					(thickness 0.15)
				)
				(justify left bottom mirror)
			)
		)
		(property "Value" "R_1k_0402"
			(at 0 -1.4 180)
			(layer "B.Fab")
			(effects
				(font
					(size 0.7 0.7)
					(thickness 0.15)
				)
				(justify left bottom mirror)
			)
		)
		(property "Description" "SMD Chip Resistor, 1 kohm, ± 1%, 63 mW, 0402 [1005 Metric], Thick Film, General Purpose"
			(at 0 0 0)
			(layer "F.Fab")
			(hide yes)
			(effects
				(font
					(size 1.27 1.27)
					(thickness 0.15)
				)
			)
		)
		(property "Author" "Antmicro"
			(at 0 0 0)
			(layer "B.Fab")
			(hide yes)
			(effects
				(font
					(size 1 1)
					(thickness 0.15)
				)
				(justify mirror)
			)
		)
		(property "License" "Apache-2.0"
			(at 0 0 0)
			(layer "B.Fab")
			(hide yes)
			(effects
				(font
					(size 1 1)
					(thickness 0.15)
				)
				(justify mirror)
			)
		)
		(property "MPN" "CR0402-FX-1001GLF"
			(at 0 0 0)
			(layer "B.Fab")
			(hide yes)
			(effects
				(font
					(size 1 1)
					(thickness 0.15)
				)
				(justify mirror)
			)
		)
		(property "Manufacturer" "Bourns"
			(at 0 0 0)
			(layer "B.Fab")
			(hide yes)
			(effects
				(font
					(size 1 1)
					(thickness 0.15)
				)
				(justify mirror)
			)
		)
		(property "Tolerance" "1%"
			(at 0 0 0)
			(layer "B.Fab")
			(hide yes)
			(effects
				(font
					(size 1 1)
					(thickness 0.15)
				)
				(justify mirror)
			)
		)
		(property "Val" "1k"
			(at 0 0 0)
			(layer "B.Fab")
			(hide yes)
			(effects
				(font
					(size 1 1)
					(thickness 0.15)
				)
				(justify mirror)
			)
		)
		(sheetname "User GPIO + LED + button + DIP switch")
		(sheetfile "user-gpio.kicad_sch")
		(attr smd)
		(fp_rect
			(start -0.925 0.47)
			(end 0.925 -0.47)
			(stroke
				(width 0.05)
				(type default)
			)
			(fill no)
			(layer "B.CrtYd")
		)
		(fp_rect
			(start -0.5 0.25)
			(end 0.5 -0.25)
			(stroke
				(width 0.15)
				(type solid)
			)
			(fill no)
			(layer "B.Fab")
		)
		(pad "1" smd roundrect
			(at -0.48 0)
			(size 0.59 0.64)
			(layers "B.Cu" "B.Mask" "B.Paste")
			(roundrect_rratio 0.25)
			(net 24 "+3V3")
			(pintype "passive")
		)
		(pad "2" smd roundrect
			(at 0.48 0)
			(size 0.59 0.64)
			(layers "B.Cu" "B.Mask" "B.Paste")
			(roundrect_rratio 0.25)
			(net 789 "Net-(D25-A)")
			(pintype "passive")
		)
	)
	(footprint "antmicro-footprints:C_0402_1005Metric"
		(layer "B.Cu")
		(at 208.5 132 90)
		(descr "Capacitor SMD 0402")
		(tags "capacitor SMD 0402")
		(property "Reference" "C31"
			(at 0.75 1.2 270)
			(layer "B.SilkS")
			(effects
				(font
					(size 0.7 0.7)
					(thickness 0.15)
				)
				(justify left bottom mirror)
			)
		)
		(property "Value" "C_100n_0402"
			(at 0 -1.169 270)
			(layer "B.Fab")
			(effects
				(font
					(size 0.7 0.7)
					(thickness 0.15)
				)
				(justify left bottom mirror)
			)
		)
		(property "Description" "SMD Multilayer Ceramic Capacitor, 0.1 µF, 50 V, 0402 [1005 Metric], ± 10%, X5R, GRM Series"
			(at 0 0 90)
			(layer "F.Fab")
			(hide yes)
			(effects
				(font
					(size 1.27 1.27)
					(thickness 0.15)
				)
			)
		)
		(property "Author" "Antmicro"
			(at 340.5 -76.5 0)
			(layer "B.Fab")
			(hide yes)
			(effects
				(font
					(size 1 1)
					(thickness 0.15)
				)
				(justify mirror)
			)
		)
		(property "Dielectric" "X5R"
			(at 340.5 -76.5 0)
			(layer "B.Fab")
			(hide yes)
			(effects
				(font
					(size 1 1)
					(thickness 0.15)
				)
				(justify mirror)
			)
		)
		(property "License" "Apache-2.0"
			(at 340.5 -76.5 0)
			(layer "B.Fab")
			(hide yes)
			(effects
				(font
					(size 1 1)
					(thickness 0.15)
				)
				(justify mirror)
			)
		)
		(property "MPN" "GRM155R61H104KE14D"
			(at 340.5 -76.5 0)
			(layer "B.Fab")
			(hide yes)
			(effects
				(font
					(size 1 1)
					(thickness 0.15)
				)
				(justify mirror)
			)
		)
		(property "Manufacturer" "Murata"
			(at 340.5 -76.5 0)
			(layer "B.Fab")
			(hide yes)
			(effects
				(font
					(size 1 1)
					(thickness 0.15)
				)
				(justify mirror)
			)
		)
		(property "Val" "100n"
			(at 340.5 -76.5 0)
			(layer "B.Fab")
			(hide yes)
			(effects
				(font
					(size 1 1)
					(thickness 0.15)
				)
				(justify mirror)
			)
		)
		(property "Voltage" "50V"
			(at 340.5 -76.5 0)
			(layer "B.Fab")
			(hide yes)
			(effects
				(font
					(size 1 1)
					(thickness 0.15)
				)
				(justify mirror)
			)
		)
		(sheetname "FPGA Bank 14 & 15")
		(sheetfile "fpga-bank-14-15.kicad_sch")
		(attr smd)
		(fp_rect
			(start -0.925 0.47)
			(end 0.925 -0.47)
			(stroke
				(width 0.05)
				(type default)
			)
			(fill no)
			(layer "B.CrtYd")
		)
		(fp_line
			(start 0.504 -0.248)
			(end -0.494 -0.248)
			(stroke
				(width 0.15)
				(type solid)
			)
			(layer "B.Fab")
		)
		(fp_line
			(start -0.494 -0.248)
			(end -0.494 0.25)
			(stroke
				(width 0.15)
				(type solid)
			)
			(layer "B.Fab")
		)
		(fp_line
			(start 0.504 0.25)
			(end 0.504 -0.248)
			(stroke
				(width 0.15)
				(type solid)
			)
			(layer "B.Fab")
		)
		(fp_line
			(start -0.494 0.25)
			(end 0.504 0.25)
			(stroke
				(width 0.15)
				(type solid)
			)
			(layer "B.Fab")
		)
		(pad "1" smd roundrect
			(at -0.48 0 90)
			(size 0.59 0.64)
			(layers "B.Cu" "B.Mask" "B.Paste")
			(roundrect_rratio 0.25)
			(net 1 "GND")
			(pintype "passive")
		)
		(pad "2" smd roundrect
			(at 0.48 0 90)
			(size 0.59 0.64)
			(layers "B.Cu" "B.Mask" "B.Paste")
			(roundrect_rratio 0.25)
			(net 24 "+3V3")
			(pintype "passive")
		)
	)
	(footprint "antmicro-footprints:R_0402_1005Metric"
		(layer "B.Cu")
		(at 225.626 149.217)
		(descr "Resistor SMD 0402")
		(tags "resistor SMD 0402")
		(property "Reference" "R226"
			(at 3.599 0.358 180)
			(layer "B.SilkS")
			(effects
				(font
					(size 0.7 0.7)
					(thickness 0.15)
				)
				(justify left bottom mirror)
			)
		)
		(property "Value" "R_2k2_0402"
			(at 0 -1.4 180)
			(layer "B.Fab")
			(effects
				(font
					(size 0.7 0.7)
					(thickness 0.15)
				)
				(justify left bottom mirror)
			)
		)
		(property "Description" "SMD Chip Resistor, 2.2 kohm, ± 1%, 62.5 mW, 0402 [1005 Metric], Thick Film, General Purpose"
			(at 0 0 0)
			(layer "F.Fab")
			(hide yes)
			(effects
				(font
					(size 1.27 1.27)
					(thickness 0.15)
				)
			)
		)
		(property "Author" "Antmicro"
			(at 0 0 0)
			(layer "B.Fab")
			(hide yes)
			(effects
				(font
					(size 1 1)
					(thickness 0.15)
				)
				(justify mirror)
			)
		)
		(property "DNP" "DNP"
			(at 0 0 0)
			(layer "B.Fab")
			(hide yes)
			(effects
				(font
					(size 1 1)
					(thickness 0.15)
				)
				(justify mirror)
			)
		)
		(property "License" "Apache-2.0"
			(at 0 0 0)
			(layer "B.Fab")
			(hide yes)
			(effects
				(font
					(size 1 1)
					(thickness 0.15)
				)
				(justify mirror)
			)
		)
		(property "MPN" "CR0402-FX-2201GLF"
			(at 0 0 0)
			(layer "B.Fab")
			(hide yes)
			(effects
				(font
					(size 1 1)
					(thickness 0.15)
				)
				(justify mirror)
			)
		)
		(property "Manufacturer" "Bourns"
			(at 0 0 0)
			(layer "B.Fab")
			(hide yes)
			(effects
				(font
					(size 1 1)
					(thickness 0.15)
				)
				(justify mirror)
			)
		)
		(property "Tolerance" "1%"
			(at 0 0 0)
			(layer "B.Fab")
			(hide yes)
			(effects
				(font
					(size 1 1)
					(thickness 0.15)
				)
				(justify mirror)
			)
		)
		(property "Val" "2k2"
			(at 0 0 0)
			(layer "B.Fab")
			(hide yes)
			(effects
				(font
					(size 1 1)
					(thickness 0.15)
				)
				(justify mirror)
			)
		)
		(property "dnp" ""
			(at 0 0 0)
			(layer "B.Fab")
			(hide yes)
			(effects
				(font
					(size 1 1)
					(thickness 0.15)
				)
				(justify mirror)
			)
		)
		(property "exclude_from_bom" ""
			(at 0 0 0)
			(layer "B.Fab")
			(hide yes)
			(effects
				(font
					(size 1 1)
					(thickness 0.15)
				)
				(justify mirror)
			)
		)
		(sheetname "HDMI + Ethernet")
		(sheetfile "hdmi-ethernet.kicad_sch")
		(attr smd exclude_from_bom)
		(fp_rect
			(start -0.925 0.47)
			(end 0.925 -0.47)
			(stroke
				(width 0.05)
				(type default)
			)
			(fill no)
			(layer "B.CrtYd")
		)
		(fp_rect
			(start -0.5 0.25)
			(end 0.5 -0.25)
			(stroke
				(width 0.15)
				(type solid)
			)
			(fill no)
			(layer "B.Fab")
		)
		(pad "1" smd roundrect
			(at -0.48 0)
			(size 0.59 0.64)
			(layers "B.Cu" "B.Mask" "B.Paste")
			(roundrect_rratio 0.25)
			(net 945 "/HDMI + Ethernet/ETH_PHY_RXD1")
			(pintype "passive")
		)
		(pad "2" smd roundrect
			(at 0.48 0)
			(size 0.59 0.64)
			(layers "B.Cu" "B.Mask" "B.Paste")
			(roundrect_rratio 0.25)
			(net 1 "GND")
			(pintype "passive")
		)
	)
	(footprint "antmicro-footprints:C_0201"
		(layer "B.Cu")
		(at 203 130.45 180)
		(descr "Capacitor SMD 0201")
		(tags "capacitor SMD 0201")
		(property "Reference" "C45"
			(at -29 28.5 0)
			(layer "B.SilkS")
			(effects
				(font
					(size 0.7 0.7)
					(thickness 0.15)
				)
				(justify left bottom mirror)
			)
		)
		(property "Value" "C_4u7_0201"
			(at 0 -1.4 0)
			(layer "B.Fab")
			(effects
				(font
					(size 0.7 0.7)
					(thickness 0.15)
				)
				(justify left bottom mirror)
			)
		)
		(property "Description" "SMD Multilayer Ceramic Capacitor, 4.7 µF, 6.3 V, 0201 [0603 Metric], ± 20%, X5R, GRM Series"
			(at 0 0 180)
			(layer "F.Fab")
			(hide yes)
			(effects
				(font
					(size 1.27 1.27)
					(thickness 0.15)
				)
			)
		)
		(property "Author" "Antmicro"
			(at 406 260.9 0)
			(layer "B.Fab")
			(hide yes)
			(effects
				(font
					(size 1 1)
					(thickness 0.15)
				)
				(justify mirror)
			)
		)
		(property "Dielectric" ""
			(at 406 260.9 0)
			(layer "B.Fab")
			(hide yes)
			(effects
				(font
					(size 1 1)
					(thickness 0.15)
				)
				(justify mirror)
			)
		)
		(property "License" "Apache-2.0"
			(at 406 260.9 0)
			(layer "B.Fab")
			(hide yes)
			(effects
				(font
					(size 1 1)
					(thickness 0.15)
				)
				(justify mirror)
			)
		)
		(property "MPN" "GRM035R60J475ME15D"
			(at 406 260.9 0)
			(layer "B.Fab")
			(hide yes)
			(effects
				(font
					(size 1 1)
					(thickness 0.15)
				)
				(justify mirror)
			)
		)
		(property "Manufacturer" "Murata"
			(at 406 260.9 0)
			(layer "B.Fab")
			(hide yes)
			(effects
				(font
					(size 1 1)
					(thickness 0.15)
				)
				(justify mirror)
			)
		)
		(property "Val" "4u7"
			(at 406 260.9 0)
			(layer "B.Fab")
			(hide yes)
			(effects
				(font
					(size 1 1)
					(thickness 0.15)
				)
				(justify mirror)
			)
		)
		(property "Voltage" ""
			(at 406 260.9 0)
			(layer "B.Fab")
			(hide yes)
			(effects
				(font
					(size 1 1)
					(thickness 0.15)
				)
				(justify mirror)
			)
		)
		(sheetname "FPGA supply")
		(sheetfile "fpga-supply.kicad_sch")
		(attr smd)
		(fp_rect
			(start -0.7 0.35)
			(end 0.7 -0.35)
			(stroke
				(width 0.05)
				(type default)
			)
			(fill no)
			(layer "B.CrtYd")
		)
		(fp_rect
			(start 0.3 -0.15)
			(end -0.301 0.149)
			(stroke
				(width 0.15)
				(type solid)
			)
			(fill no)
			(layer "B.Fab")
		)
		(pad "" smd roundrect
			(at -0.349 0.002 180)
			(size 0.318 0.36)
			(layers "B.Paste")
			(roundrect_rratio 0.25)
		)
		(pad "" smd roundrect
			(at 0.341 0.002 180)
			(size 0.318 0.36)
			(layers "B.Paste")
			(roundrect_rratio 0.25)
		)
		(pad "1" smd roundrect
			(at -0.321 0.002 180)
			(size 0.46 0.4)
			(layers "B.Cu" "B.Mask")
			(roundrect_rratio 0.25)
			(net 1 "GND")
			(pintype "passive")
		)
		(pad "2" smd roundrect
			(at 0.32 0.002 180)
			(size 0.46 0.4)
			(layers "B.Cu" "B.Mask")
			(roundrect_rratio 0.25)
			(net 650 "+1V0")
			(pintype "passive")
		)
	)
	(footprint "antmicro-footprints:R_0402_1005Metric"
		(layer "B.Cu")
		(at 257.201 166.8 -90)
		(descr "Resistor SMD 0402")
		(tags "resistor SMD 0402")
		(property "Reference" "R247"
			(at -2.975 -3.199 225)
			(layer "B.SilkS")
			(effects
				(font
					(size 0.7 0.7)
					(thickness 0.15)
				)
				(justify left bottom mirror)
			)
		)
		(property "Value" "R_49R9_0402"
			(at 0 -1.4 90)
			(layer "B.Fab")
			(effects
				(font
					(size 0.7 0.7)
					(thickness 0.15)
				)
				(justify left bottom mirror)
			)
		)
		(property "Description" "SMD Chip Resistor, 49.9 ohm, ± 1%, 62.5 mW, 0402 [1005 Metric], Thick Film, General Purpose"
			(at 0 0 270)
			(layer "F.Fab")
			(hide yes)
			(effects
				(font
					(size 1.27 1.27)
					(thickness 0.15)
				)
			)
		)
		(property "Author" "Antmicro"
			(at 90.401 424.001 0)
			(layer "B.Fab")
			(hide yes)
			(effects
				(font
					(size 1 1)
					(thickness 0.15)
				)
				(justify mirror)
			)
		)
		(property "License" "Apache-2.0"
			(at 90.401 424.001 0)
			(layer "B.Fab")
			(hide yes)
			(effects
				(font
					(size 1 1)
					(thickness 0.15)
				)
				(justify mirror)
			)
		)
		(property "MPN" "CR0402-FX-49R9GLF"
			(at 90.401 424.001 0)
			(layer "B.Fab")
			(hide yes)
			(effects
				(font
					(size 1 1)
					(thickness 0.15)
				)
				(justify mirror)
			)
		)
		(property "Manufacturer" "Bourns"
			(at 90.401 424.001 0)
			(layer "B.Fab")
			(hide yes)
			(effects
				(font
					(size 1 1)
					(thickness 0.15)
				)
				(justify mirror)
			)
		)
		(property "Tolerance" "1%"
			(at 90.401 424.001 0)
			(layer "B.Fab")
			(hide yes)
			(effects
				(font
					(size 1 1)
					(thickness 0.15)
				)
				(justify mirror)
			)
		)
		(property "Val" "49R9"
			(at 90.401 424.001 0)
			(layer "B.Fab")
			(hide yes)
			(effects
				(font
					(size 1 1)
					(thickness 0.15)
				)
				(justify mirror)
			)
		)
		(sheetname "HDMI + Ethernet")
		(sheetfile "hdmi-ethernet.kicad_sch")
		(attr smd)
		(fp_rect
			(start -0.925 0.47)
			(end 0.925 -0.47)
			(stroke
				(width 0.05)
				(type default)
			)
			(fill no)
			(layer "B.CrtYd")
		)
		(fp_rect
			(start -0.5 0.25)
			(end 0.5 -0.25)
			(stroke
				(width 0.15)
				(type solid)
			)
			(fill no)
			(layer "B.Fab")
		)
		(pad "1" smd roundrect
			(at -0.48 0 270)
			(size 0.59 0.64)
			(layers "B.Cu" "B.Mask" "B.Paste")
			(roundrect_rratio 0.25)
			(net 725 "/HDMI + Ethernet/ETH1_N")
			(pintype "passive")
		)
		(pad "2" smd roundrect
			(at 0.48 0 270)
			(size 0.59 0.64)
			(layers "B.Cu" "B.Mask" "B.Paste")
			(roundrect_rratio 0.25)
			(net 721 "/HDMI + Ethernet/ETH_3V3")
			(pintype "passive")
		)
	)
	(footprint "antmicro-footprints:C_0402_1005Metric"
		(layer "B.Cu")
		(at 193.75 161.925 -90)
		(descr "Capacitor SMD 0402")
		(tags "capacitor SMD 0402")
		(property "Reference" "C347"
			(at -1.425 0.475 90)
			(layer "B.SilkS")
			(effects
				(font
					(size 0.7 0.7)
					(thickness 0.15)
				)
				(justify left bottom mirror)
			)
		)
		(property "Value" "C_100n_0402"
			(at 0 -1.4 90)
			(layer "B.Fab")
			(effects
				(font
					(size 0.7 0.7)
					(thickness 0.15)
				)
				(justify left bottom mirror)
			)
		)
		(property "Description" "SMD Multilayer Ceramic Capacitor, 0.1 µF, 50 V, 0402 [1005 Metric], ± 10%, X5R, GRM Series"
			(at 0 0 270)
			(layer "F.Fab")
			(hide yes)
			(effects
				(font
					(size 1.27 1.27)
					(thickness 0.15)
				)
			)
		)
		(property "Author" "Antmicro"
			(at 31.825 355.675 0)
			(layer "B.Fab")
			(hide yes)
			(effects
				(font
					(size 1 1)
					(thickness 0.15)
				)
				(justify mirror)
			)
		)
		(property "Dielectric" "X5R"
			(at 31.825 355.675 0)
			(layer "B.Fab")
			(hide yes)
			(effects
				(font
					(size 1 1)
					(thickness 0.15)
				)
				(justify mirror)
			)
		)
		(property "License" "Apache-2.0"
			(at 31.825 355.675 0)
			(layer "B.Fab")
			(hide yes)
			(effects
				(font
					(size 1 1)
					(thickness 0.15)
				)
				(justify mirror)
			)
		)
		(property "MPN" "GRM155R61H104KE14D"
			(at 31.825 355.675 0)
			(layer "B.Fab")
			(hide yes)
			(effects
				(font
					(size 1 1)
					(thickness 0.15)
				)
				(justify mirror)
			)
		)
		(property "Manufacturer" "Murata"
			(at 31.825 355.675 0)
			(layer "B.Fab")
			(hide yes)
			(effects
				(font
					(size 1 1)
					(thickness 0.15)
				)
				(justify mirror)
			)
		)
		(property "Val" "100n"
			(at 31.825 355.675 0)
			(layer "B.Fab")
			(hide yes)
			(effects
				(font
					(size 1 1)
					(thickness 0.15)
				)
				(justify mirror)
			)
		)
		(property "Voltage" "50V"
			(at 31.825 355.675 0)
			(layer "B.Fab")
			(hide yes)
			(effects
				(font
					(size 1 1)
					(thickness 0.15)
				)
				(justify mirror)
			)
		)
		(sheetname "DC-DC Converters")
		(sheetfile "dc-dc.kicad_sch")
		(attr smd)
		(fp_rect
			(start -0.925 0.47)
			(end 0.925 -0.47)
			(stroke
				(width 0.05)
				(type default)
			)
			(fill no)
			(layer "B.CrtYd")
		)
		(fp_line
			(start -0.494 0.25)
			(end 0.504 0.25)
			(stroke
				(width 0.15)
				(type solid)
			)
			(layer "B.Fab")
		)
		(fp_line
			(start 0.504 0.25)
			(end 0.504 -0.248)
			(stroke
				(width 0.15)
				(type solid)
			)
			(layer "B.Fab")
		)
		(fp_line
			(start -0.494 -0.248)
			(end -0.494 0.25)
			(stroke
				(width 0.15)
				(type solid)
			)
			(layer "B.Fab")
		)
		(fp_line
			(start 0.504 -0.248)
			(end -0.494 -0.248)
			(stroke
				(width 0.15)
				(type solid)
			)
			(layer "B.Fab")
		)
		(pad "1" smd roundrect
			(at -0.48 0 270)
			(size 0.59 0.64)
			(layers "B.Cu" "B.Mask" "B.Paste")
			(roundrect_rratio 0.25)
			(net 1 "GND")
			(pintype "passive")
		)
		(pad "2" smd roundrect
			(at 0.48 0 270)
			(size 0.59 0.64)
			(layers "B.Cu" "B.Mask" "B.Paste")
			(roundrect_rratio 0.25)
			(net 702 "VDC")
			(pintype "passive")
		)
	)
	(footprint "antmicro-footprints:C_0402_1005Metric"
		(layer "B.Cu")
		(at 209 127.5 180)
		(descr "Capacitor SMD 0402")
		(tags "capacitor SMD 0402")
		(property "Reference" "C43"
			(at -1.125 0.5 0)
			(layer "B.SilkS")
			(effects
				(font
					(size 0.7 0.7)
					(thickness 0.15)
				)
				(justify left bottom mirror)
			)
		)
		(property "Value" "C_100n_0402"
			(at 0 -1.169 0)
			(layer "B.Fab")
			(effects
				(font
					(size 0.7 0.7)
					(thickness 0.15)
				)
				(justify left bottom mirror)
			)
		)
		(property "Description" "SMD Multilayer Ceramic Capacitor, 0.1 µF, 50 V, 0402 [1005 Metric], ± 10%, X5R, GRM Series"
			(at 0 0 180)
			(layer "F.Fab")
			(hide yes)
			(effects
				(font
					(size 1.27 1.27)
					(thickness 0.15)
				)
			)
		)
		(property "Author" "Antmicro"
			(at 418 255 0)
			(layer "B.Fab")
			(hide yes)
			(effects
				(font
					(size 1 1)
					(thickness 0.15)
				)
				(justify mirror)
			)
		)
		(property "Dielectric" "X5R"
			(at 418 255 0)
			(layer "B.Fab")
			(hide yes)
			(effects
				(font
					(size 1 1)
					(thickness 0.15)
				)
				(justify mirror)
			)
		)
		(property "License" "Apache-2.0"
			(at 418 255 0)
			(layer "B.Fab")
			(hide yes)
			(effects
				(font
					(size 1 1)
					(thickness 0.15)
				)
				(justify mirror)
			)
		)
		(property "MPN" "GRM155R61H104KE14D"
			(at 418 255 0)
			(layer "B.Fab")
			(hide yes)
			(effects
				(font
					(size 1 1)
					(thickness 0.15)
				)
				(justify mirror)
			)
		)
		(property "Manufacturer" "Murata"
			(at 418 255 0)
			(layer "B.Fab")
			(hide yes)
			(effects
				(font
					(size 1 1)
					(thickness 0.15)
				)
				(justify mirror)
			)
		)
		(property "Val" "100n"
			(at 418 255 0)
			(layer "B.Fab")
			(hide yes)
			(effects
				(font
					(size 1 1)
					(thickness 0.15)
				)
				(justify mirror)
			)
		)
		(property "Voltage" "50V"
			(at 418 255 0)
			(layer "B.Fab")
			(hide yes)
			(effects
				(font
					(size 1 1)
					(thickness 0.15)
				)
				(justify mirror)
			)
		)
		(sheetname "FPGA Bank 14 & 15")
		(sheetfile "fpga-bank-14-15.kicad_sch")
		(attr smd)
		(fp_rect
			(start -0.925 0.47)
			(end 0.925 -0.47)
			(stroke
				(width 0.05)
				(type default)
			)
			(fill no)
			(layer "B.CrtYd")
		)
		(fp_line
			(start 0.504 0.25)
			(end 0.504 -0.248)
			(stroke
				(width 0.15)
				(type solid)
			)
			(layer "B.Fab")
		)
		(fp_line
			(start 0.504 -0.248)
			(end -0.494 -0.248)
			(stroke
				(width 0.15)
				(type solid)
			)
			(layer "B.Fab")
		)
		(fp_line
			(start -0.494 0.25)
			(end 0.504 0.25)
			(stroke
				(width 0.15)
				(type solid)
			)
			(layer "B.Fab")
		)
		(fp_line
			(start -0.494 -0.248)
			(end -0.494 0.25)
			(stroke
				(width 0.15)
				(type solid)
			)
			(layer "B.Fab")
		)
		(pad "1" smd roundrect
			(at -0.48 0 180)
			(size 0.59 0.64)
			(layers "B.Cu" "B.Mask" "B.Paste")
			(roundrect_rratio 0.25)
			(net 1 "GND")
			(pintype "passive")
		)
		(pad "2" smd roundrect
			(at 0.48 0 180)
			(size 0.59 0.64)
			(layers "B.Cu" "B.Mask" "B.Paste")
			(roundrect_rratio 0.25)
			(net 2 "VCC_USR_A")
			(pintype "passive")
		)
	)
	(footprint "antmicro-footprints:R_0402_1005Metric"
		(layer "B.Cu")
		(at 203.2 90.8 90)
		(descr "Resistor SMD 0402")
		(tags "resistor SMD 0402")
		(property "Reference" "R204"
			(at 1.95 2.4 270)
			(layer "B.SilkS")
			(effects
				(font
					(size 0.7 0.7)
					(thickness 0.15)
				)
				(justify left bottom mirror)
			)
		)
		(property "Value" "R_10k_0402"
			(at 0 -1.4 270)
			(layer "B.Fab")
			(effects
				(font
					(size 0.7 0.7)
					(thickness 0.15)
				)
				(justify left bottom mirror)
			)
		)
		(property "Description" "SMD Chip Resistor, 10 kohm, ± 1%, 62.5 mW, 0402 [1005 Metric], Thick Film, General Purpose"
			(at 0 0 90)
			(layer "F.Fab")
			(hide yes)
			(effects
				(font
					(size 1.27 1.27)
					(thickness 0.15)
				)
			)
		)
		(property "Author" "Antmicro"
			(at 294 -112.4 0)
			(layer "B.Fab")
			(hide yes)
			(effects
				(font
					(size 1 1)
					(thickness 0.15)
				)
				(justify mirror)
			)
		)
		(property "License" "Apache-2.0"
			(at 294 -112.4 0)
			(layer "B.Fab")
			(hide yes)
			(effects
				(font
					(size 1 1)
					(thickness 0.15)
				)
				(justify mirror)
			)
		)
		(property "MPN" "CR0402-FX-1002GLF"
			(at 294 -112.4 0)
			(layer "B.Fab")
			(hide yes)
			(effects
				(font
					(size 1 1)
					(thickness 0.15)
				)
				(justify mirror)
			)
		)
		(property "Manufacturer" "Bourns"
			(at 294 -112.4 0)
			(layer "B.Fab")
			(hide yes)
			(effects
				(font
					(size 1 1)
					(thickness 0.15)
				)
				(justify mirror)
			)
		)
		(property "Tolerance" "1%"
			(at 294 -112.4 0)
			(layer "B.Fab")
			(hide yes)
			(effects
				(font
					(size 1 1)
					(thickness 0.15)
				)
				(justify mirror)
			)
		)
		(property "Val" "10k"
			(at 294 -112.4 0)
			(layer "B.Fab")
			(hide yes)
			(effects
				(font
					(size 1 1)
					(thickness 0.15)
				)
				(justify mirror)
			)
		)
		(sheetname "HDMI + Ethernet")
		(sheetfile "hdmi-ethernet.kicad_sch")
		(attr smd)
		(fp_rect
			(start -0.925 0.47)
			(end 0.925 -0.47)
			(stroke
				(width 0.05)
				(type default)
			)
			(fill no)
			(layer "B.CrtYd")
		)
		(fp_rect
			(start -0.5 0.25)
			(end 0.5 -0.25)
			(stroke
				(width 0.15)
				(type solid)
			)
			(fill no)
			(layer "B.Fab")
		)
		(pad "1" smd roundrect
			(at -0.48 0 90)
			(size 0.59 0.64)
			(layers "B.Cu" "B.Mask" "B.Paste")
			(roundrect_rratio 0.25)
			(net 850 "/HDMI + Ethernet/GBE_LED_SPD-")
			(pintype "passive")
		)
		(pad "2" smd roundrect
			(at 0.48 0 90)
			(size 0.59 0.64)
			(layers "B.Cu" "B.Mask" "B.Paste")
			(roundrect_rratio 0.25)
			(net 24 "+3V3")
			(pintype "passive")
		)
	)
	(footprint "antmicro-footprints:R_0402_1005Metric"
		(layer "B.Cu")
		(at 242.699999 84.699999 -90)
		(descr "Resistor SMD 0402")
		(tags "resistor SMD 0402")
		(property "Reference" "R118"
			(at 0.725001 -0.400001 90)
			(layer "B.SilkS")
			(effects
				(font
					(size 0.7 0.7)
					(thickness 0.15)
				)
				(justify left bottom mirror)
			)
		)
		(property "Value" "R_100R_0402"
			(at 0 -1.4 90)
			(layer "B.Fab")
			(effects
				(font
					(size 0.7 0.7)
					(thickness 0.15)
				)
				(justify left bottom mirror)
			)
		)
		(property "Description" "SMD Chip Resistor, 100 ohm, ± 1%, 62.5 mW, 0402 [1005 Metric], Thick Film, General Purpose"
			(at 0 0 270)
			(layer "F.Fab")
			(hide yes)
			(effects
				(font
					(size 1.27 1.27)
					(thickness 0.15)
				)
			)
		)
		(property "Author" "Antmicro"
			(at 158 327.399998 0)
			(layer "B.Fab")
			(hide yes)
			(effects
				(font
					(size 1 1)
					(thickness 0.15)
				)
				(justify mirror)
			)
		)
		(property "License" "Apache-2.0"
			(at 158 327.399998 0)
			(layer "B.Fab")
			(hide yes)
			(effects
				(font
					(size 1 1)
					(thickness 0.15)
				)
				(justify mirror)
			)
		)
		(property "MPN" "CR0402-FX-1000GLF"
			(at 158 327.399998 0)
			(layer "B.Fab")
			(hide yes)
			(effects
				(font
					(size 1 1)
					(thickness 0.15)
				)
				(justify mirror)
			)
		)
		(property "Manufacturer" "Bourns"
			(at 158 327.399998 0)
			(layer "B.Fab")
			(hide yes)
			(effects
				(font
					(size 1 1)
					(thickness 0.15)
				)
				(justify mirror)
			)
		)
		(property "Tolerance" "1%"
			(at 158 327.399998 0)
			(layer "B.Fab")
			(hide yes)
			(effects
				(font
					(size 1 1)
					(thickness 0.15)
				)
				(justify mirror)
			)
		)
		(property "Val" "100R"
			(at 158 327.399998 0)
			(layer "B.Fab")
			(hide yes)
			(effects
				(font
					(size 1 1)
					(thickness 0.15)
				)
				(justify mirror)
			)
		)
		(sheetname "User GPIO + LED + button + DIP switch")
		(sheetfile "user-gpio.kicad_sch")
		(attr smd)
		(fp_rect
			(start -0.925 0.47)
			(end 0.925 -0.47)
			(stroke
				(width 0.05)
				(type default)
			)
			(fill no)
			(layer "B.CrtYd")
		)
		(fp_rect
			(start -0.5 0.25)
			(end 0.5 -0.25)
			(stroke
				(width 0.15)
				(type solid)
			)
			(fill no)
			(layer "B.Fab")
		)
		(pad "1" smd roundrect
			(at -0.48 0 270)
			(size 0.59 0.64)
			(layers "B.Cu" "B.Mask" "B.Paste")
			(roundrect_rratio 0.25)
			(net 812 "/User GPIO + LED + button + DIP switch/PMOD_B_9")
			(pintype "passive")
		)
		(pad "2" smd roundrect
			(at 0.48 0 270)
			(size 0.59 0.64)
			(layers "B.Cu" "B.Mask" "B.Paste")
			(roundrect_rratio 0.25)
			(net 452 "/FPGA Bank 12 & 13/PMOD_B.IO9")
			(pintype "passive")
		)
	)
	(footprint "antmicro-footprints:C_0201"
		(layer "B.Cu")
		(at 188.000001 122.500001 180)
		(descr "Capacitor SMD 0201")
		(tags "capacitor SMD 0201")
		(property "Reference" "C154"
			(at 2.250001 -0.399999 0)
			(layer "B.SilkS")
			(effects
				(font
					(size 0.7 0.7)
					(thickness 0.15)
				)
				(justify left bottom mirror)
			)
		)
		(property "Value" "C_100n_0201"
			(at 0 -1.4 0)
			(layer "B.Fab")
			(effects
				(font
					(size 0.7 0.7)
					(thickness 0.15)
				)
				(justify left bottom mirror)
			)
		)
		(property "Description" "SMD Multilayer Ceramic Capacitor, 0.1 µF, 6.3 V, 0201 [0603 Metric], ± 10%, X6S, CC Series"
			(at 0 0 180)
			(layer "F.Fab")
			(hide yes)
			(effects
				(font
					(size 1.27 1.27)
					(thickness 0.15)
				)
			)
		)
		(property "Author" "Antmicro"
			(at 376.000002 245.000002 0)
			(layer "B.Fab")
			(hide yes)
			(effects
				(font
					(size 1 1)
					(thickness 0.15)
				)
				(justify mirror)
			)
		)
		(property "Dielectric" ""
			(at 376.000002 245.000002 0)
			(layer "B.Fab")
			(hide yes)
			(effects
				(font
					(size 1 1)
					(thickness 0.15)
				)
				(justify mirror)
			)
		)
		(property "License" "Apache-2.0"
			(at 376.000002 245.000002 0)
			(layer "B.Fab")
			(hide yes)
			(effects
				(font
					(size 1 1)
					(thickness 0.15)
				)
				(justify mirror)
			)
		)
		(property "MPN" "CC0201KRX6S5BB104"
			(at 376.000002 245.000002 0)
			(layer "B.Fab")
			(hide yes)
			(effects
				(font
					(size 1 1)
					(thickness 0.15)
				)
				(justify mirror)
			)
		)
		(property "Manufacturer" "YAGEO"
			(at 376.000002 245.000002 0)
			(layer "B.Fab")
			(hide yes)
			(effects
				(font
					(size 1 1)
					(thickness 0.15)
				)
				(justify mirror)
			)
		)
		(property "Val" "100n"
			(at 376.000002 245.000002 0)
			(layer "B.Fab")
			(hide yes)
			(effects
				(font
					(size 1 1)
					(thickness 0.15)
				)
				(justify mirror)
			)
		)
		(property "Voltage" ""
			(at 376.000002 245.000002 0)
			(layer "B.Fab")
			(hide yes)
			(effects
				(font
					(size 1 1)
					(thickness 0.15)
				)
				(justify mirror)
			)
		)
		(sheetname "FPGA supply")
		(sheetfile "fpga-supply.kicad_sch")
		(attr smd)
		(fp_rect
			(start -0.7 0.35)
			(end 0.7 -0.35)
			(stroke
				(width 0.05)
				(type default)
			)
			(fill no)
			(layer "B.CrtYd")
		)
		(fp_rect
			(start 0.3 -0.15)
			(end -0.301 0.149)
			(stroke
				(width 0.15)
				(type solid)
			)
			(fill no)
			(layer "B.Fab")
		)
		(pad "" smd roundrect
			(at -0.349 0.002 180)
			(size 0.318 0.36)
			(layers "B.Paste")
			(roundrect_rratio 0.25)
		)
		(pad "" smd roundrect
			(at 0.341 0.002 180)
			(size 0.318 0.36)
			(layers "B.Paste")
			(roundrect_rratio 0.25)
		)
		(pad "1" smd roundrect
			(at -0.321 0.002 180)
			(size 0.46 0.4)
			(layers "B.Cu" "B.Mask")
			(roundrect_rratio 0.25)
			(net 1 "GND")
			(pintype "passive")
		)
		(pad "2" smd roundrect
			(at 0.32 0.002 180)
			(size 0.46 0.4)
			(layers "B.Cu" "B.Mask")
			(roundrect_rratio 0.25)
			(net 8 "+1V2_MGTAVTT")
			(pintype "passive")
		)
	)
	(footprint "antmicro-footprints:C_0402_1005Metric"
		(layer "B.Cu")
		(at 224.8 78.7)
		(descr "Capacitor SMD 0402")
		(tags "capacitor SMD 0402")
		(property "Reference" "C214"
			(at -1.35 -0.5 0)
			(layer "B.SilkS")
			(effects
				(font
					(size 0.7 0.7)
					(thickness 0.15)
				)
				(justify right bottom mirror)
			)
		)
		(property "Value" "C_1u_0402"
			(at 0 -1.4 0)
			(layer "B.Fab")
			(effects
				(font
					(size 0.7 0.7)
					(thickness 0.15)
				)
				(justify right bottom mirror)
			)
		)
		(property "Description" "SMD Multilayer Ceramic Capacitor, 1 µF, 10 V, 0402 [1005 Metric], ± 10%, X6S, C"
			(at 0 0 0)
			(layer "F.Fab")
			(hide yes)
			(effects
				(font
					(size 1.27 1.27)
					(thickness 0.15)
				)
			)
		)
		(property "Author" "Antmicro"
			(at 0 0 0)
			(layer "B.Fab")
			(hide yes)
			(effects
				(font
					(size 1 1)
					(thickness 0.15)
				)
				(justify mirror)
			)
		)
		(property "Dielectric" ""
			(at 0 0 0)
			(layer "B.Fab")
			(hide yes)
			(effects
				(font
					(size 1 1)
					(thickness 0.15)
				)
				(justify mirror)
			)
		)
		(property "License" "Apache-2.0"
			(at 0 0 0)
			(layer "B.Fab")
			(hide yes)
			(effects
				(font
					(size 1 1)
					(thickness 0.15)
				)
				(justify mirror)
			)
		)
		(property "MPN" "C1005X6S1A105K050BC"
			(at 0 0 0)
			(layer "B.Fab")
			(hide yes)
			(effects
				(font
					(size 1 1)
					(thickness 0.15)
				)
				(justify mirror)
			)
		)
		(property "Manufacturer" "TDK"
			(at 0 0 0)
			(layer "B.Fab")
			(hide yes)
			(effects
				(font
					(size 1 1)
					(thickness 0.15)
				)
				(justify mirror)
			)
		)
		(property "Val" "1u"
			(at 0 0 0)
			(layer "B.Fab")
			(hide yes)
			(effects
				(font
					(size 1 1)
					(thickness 0.15)
				)
				(justify mirror)
			)
		)
		(property "Voltage" ""
			(at 0 0 0)
			(layer "B.Fab")
			(hide yes)
			(effects
				(font
					(size 1 1)
					(thickness 0.15)
				)
				(justify mirror)
			)
		)
		(sheetname "User GPIO + LED + button + DIP switch")
		(sheetfile "user-gpio.kicad_sch")
		(attr smd)
		(fp_rect
			(start -0.925 0.47)
			(end 0.925 -0.47)
			(stroke
				(width 0.05)
				(type default)
			)
			(fill no)
			(layer "B.CrtYd")
		)
		(fp_line
			(start -0.494 -0.248)
			(end -0.494 0.25)
			(stroke
				(width 0.15)
				(type solid)
			)
			(layer "B.Fab")
		)
		(fp_line
			(start -0.494 0.25)
			(end 0.504 0.25)
			(stroke
				(width 0.15)
				(type solid)
			)
			(layer "B.Fab")
		)
		(fp_line
			(start 0.504 -0.248)
			(end -0.494 -0.248)
			(stroke
				(width 0.15)
				(type solid)
			)
			(layer "B.Fab")
		)
		(fp_line
			(start 0.504 0.25)
			(end 0.504 -0.248)
			(stroke
				(width 0.15)
				(type solid)
			)
			(layer "B.Fab")
		)
		(pad "1" smd roundrect
			(at -0.48 0)
			(size 0.59 0.64)
			(layers "B.Cu" "B.Mask" "B.Paste")
			(roundrect_rratio 0.25)
			(net 1 "GND")
			(pintype "passive")
		)
		(pad "2" smd roundrect
			(at 0.48 0)
			(size 0.59 0.64)
			(layers "B.Cu" "B.Mask" "B.Paste")
			(roundrect_rratio 0.25)
			(net 24 "+3V3")
			(pintype "passive")
		)
	)
	(footprint "antmicro-footprints:R_0402_1005Metric_EIA"
		(layer "B.Cu")
		(at 189 137.5)
		(descr "Resistor SMD 0402 (1005 Metric), square (rectangular) end terminal, IPC_7351 nominal, (Body size source: IPC-SM-782 page 76, https://www.pcb-3d.com/wordpress/wp-content/uploads/ipc-sm-782a_amendment_1_and_2.pdf)")
		(tags "resistor 0402")
		(property "Reference" "R339"
			(at -0.1 -1.45 180)
			(layer "B.SilkS")
			(effects
				(font
					(size 0.7 0.7)
					(thickness 0.15)
				)
				(justify left bottom mirror)
			)
		)
		(property "Value" "R_80R6_0402_EIA"
			(at 0 -1.169 180)
			(layer "B.Fab")
			(effects
				(font
					(size 0.7 0.7)
					(thickness 0.15)
				)
				(justify left bottom mirror)
			)
		)
		(property "Description" "SMD Chip Resistor, 80.6 ohm, ± 1%, 62.5 mW, 0402 [1005 Metric], Thick Film, General Purpose"
			(at 0 0 0)
			(layer "F.Fab")
			(hide yes)
			(effects
				(font
					(size 1.27 1.27)
					(thickness 0.15)
				)
			)
		)
		(property "Author" "Antmicro"
			(at 0 0 0)
			(layer "B.Fab")
			(hide yes)
			(effects
				(font
					(size 1 1)
					(thickness 0.15)
				)
				(justify mirror)
			)
		)
		(property "License" "Apache-2.0"
			(at 0 0 0)
			(layer "B.Fab")
			(hide yes)
			(effects
				(font
					(size 1 1)
					(thickness 0.15)
				)
				(justify mirror)
			)
		)
		(property "MPN" "MC00625W0402180R6"
			(at 0 0 0)
			(layer "B.Fab")
			(hide yes)
			(effects
				(font
					(size 1 1)
					(thickness 0.15)
				)
				(justify mirror)
			)
		)
		(property "Manufacturer" "Multicomp Pro"
			(at 0 0 0)
			(layer "B.Fab")
			(hide yes)
			(effects
				(font
					(size 1 1)
					(thickness 0.15)
				)
				(justify mirror)
			)
		)
		(property "Tolerance" "1%"
			(at 0 0 0)
			(layer "B.Fab")
			(hide yes)
			(effects
				(font
					(size 1 1)
					(thickness 0.15)
				)
				(justify mirror)
			)
		)
		(property "Val" "80R6"
			(at 0 0 0)
			(layer "B.Fab")
			(hide yes)
			(effects
				(font
					(size 1 1)
					(thickness 0.15)
				)
				(justify mirror)
			)
		)
		(sheetname "FPGA Bank 33 & 34")
		(sheetfile "fpga-bank-33-34.kicad_sch")
		(attr smd)
		(fp_rect
			(start -0.95 0.45)
			(end 0.95 -0.45)
			(stroke
				(width 0.05)
				(type default)
			)
			(fill no)
			(layer "B.CrtYd")
		)
		(fp_line
			(start -0.5 -0.249)
			(end -0.5 0.25)
			(stroke
				(width 0.15)
				(type solid)
			)
			(layer "B.Fab")
		)
		(fp_line
			(start -0.5 0.25)
			(end 0.499 0.25)
			(stroke
				(width 0.15)
				(type solid)
			)
			(layer "B.Fab")
		)
		(fp_line
			(start 0.499 -0.249)
			(end -0.5 -0.249)
			(stroke
				(width 0.15)
				(type solid)
			)
			(layer "B.Fab")
		)
		(fp_line
			(start 0.499 0.25)
			(end 0.499 -0.249)
			(stroke
				(width 0.15)
				(type solid)
			)
			(layer "B.Fab")
		)
		(pad "1" smd roundrect
			(at -0.5 0 270)
			(size 0.6 0.6)
			(layers "B.Cu" "B.Mask" "B.Paste")
			(roundrect_rratio 0.25)
			(net 1 "GND")
			(pintype "passive")
		)
		(pad "2" smd roundrect
			(at 0.499 0)
			(size 0.6 0.6)
			(layers "B.Cu" "B.Mask" "B.Paste")
			(roundrect_rratio 0.25)
			(net 567 "/FPGA Bank 33 & 34/DDR_VRN")
			(pintype "passive")
		)
	)
	(footprint "antmicro-footprints:R_0402_1005Metric"
		(layer "B.Cu")
		(at 212.899999 77.899999 90)
		(descr "Resistor SMD 0402")
		(tags "resistor SMD 0402")
		(property "Reference" "R112"
			(at 3.599999 0.350001 90)
			(layer "B.SilkS")
			(effects
				(font
					(size 0.7 0.7)
					(thickness 0.15)
				)
				(justify left bottom mirror)
			)
		)
		(property "Value" "R_100R_0402"
			(at 0 -1.4 270)
			(layer "B.Fab")
			(effects
				(font
					(size 0.7 0.7)
					(thickness 0.15)
				)
				(justify left bottom mirror)
			)
		)
		(property "Description" "SMD Chip Resistor, 100 ohm, ± 1%, 62.5 mW, 0402 [1005 Metric], Thick Film, General Purpose"
			(at 0 0 90)
			(layer "F.Fab")
			(hide yes)
			(effects
				(font
					(size 1.27 1.27)
					(thickness 0.15)
				)
			)
		)
		(property "Author" "Antmicro"
			(at 290.799998 -135 0)
			(layer "B.Fab")
			(hide yes)
			(effects
				(font
					(size 1 1)
					(thickness 0.15)
				)
				(justify mirror)
			)
		)
		(property "License" "Apache-2.0"
			(at 290.799998 -135 0)
			(layer "B.Fab")
			(hide yes)
			(effects
				(font
					(size 1 1)
					(thickness 0.15)
				)
				(justify mirror)
			)
		)
		(property "MPN" "CR0402-FX-1000GLF"
			(at 290.799998 -135 0)
			(layer "B.Fab")
			(hide yes)
			(effects
				(font
					(size 1 1)
					(thickness 0.15)
				)
				(justify mirror)
			)
		)
		(property "Manufacturer" "Bourns"
			(at 290.799998 -135 0)
			(layer "B.Fab")
			(hide yes)
			(effects
				(font
					(size 1 1)
					(thickness 0.15)
				)
				(justify mirror)
			)
		)
		(property "Tolerance" "1%"
			(at 290.799998 -135 0)
			(layer "B.Fab")
			(hide yes)
			(effects
				(font
					(size 1 1)
					(thickness 0.15)
				)
				(justify mirror)
			)
		)
		(property "Val" "100R"
			(at 290.799998 -135 0)
			(layer "B.Fab")
			(hide yes)
			(effects
				(font
					(size 1 1)
					(thickness 0.15)
				)
				(justify mirror)
			)
		)
		(sheetname "User GPIO + LED + button + DIP switch")
		(sheetfile "user-gpio.kicad_sch")
		(attr smd)
		(fp_rect
			(start -0.925 0.47)
			(end 0.925 -0.47)
			(stroke
				(width 0.05)
				(type default)
			)
			(fill no)
			(layer "B.CrtYd")
		)
		(fp_rect
			(start -0.5 0.25)
			(end 0.5 -0.25)
			(stroke
				(width 0.15)
				(type solid)
			)
			(fill no)
			(layer "B.Fab")
		)
		(pad "1" smd roundrect
			(at -0.48 0 90)
			(size 0.59 0.64)
			(layers "B.Cu" "B.Mask" "B.Paste")
			(roundrect_rratio 0.25)
			(net 808 "/User GPIO + LED + button + DIP switch/PMOD_A_7")
			(pintype "passive")
		)
		(pad "2" smd roundrect
			(at 0.48 0 90)
			(size 0.59 0.64)
			(layers "B.Cu" "B.Mask" "B.Paste")
			(roundrect_rratio 0.25)
			(net 433 "/FPGA Bank 12 & 13/PMOD_A.IO7")
			(pintype "passive")
		)
	)
	(footprint "antmicro-footprints:C_0201"
		(layer "B.Cu")
		(at 201.5 125.65)
		(descr "Capacitor SMD 0201")
		(tags "capacitor SMD 0201")
		(property "Reference" "C28"
			(at 24.775 -29.675 0)
			(layer "B.SilkS")
			(effects
				(font
					(size 0.7 0.7)
					(thickness 0.15)
				)
				(justify right bottom mirror)
			)
		)
		(property "Value" "C_4u7_0201"
			(at 0 -1.4 0)
			(layer "B.Fab")
			(effects
				(font
					(size 0.7 0.7)
					(thickness 0.15)
				)
				(justify right bottom mirror)
			)
		)
		(property "Description" "SMD Multilayer Ceramic Capacitor, 4.7 µF, 6.3 V, 0201 [0603 Metric], ± 20%, X5R, GRM Series"
			(at 0 0 0)
			(layer "F.Fab")
			(hide yes)
			(effects
				(font
					(size 1.27 1.27)
					(thickness 0.15)
				)
			)
		)
		(property "Author" "Antmicro"
			(at 0 0 0)
			(layer "B.Fab")
			(hide yes)
			(effects
				(font
					(size 1 1)
					(thickness 0.15)
				)
				(justify mirror)
			)
		)
		(property "Dielectric" ""
			(at 0 0 0)
			(layer "B.Fab")
			(hide yes)
			(effects
				(font
					(size 1 1)
					(thickness 0.15)
				)
				(justify mirror)
			)
		)
		(property "License" "Apache-2.0"
			(at 0 0 0)
			(layer "B.Fab")
			(hide yes)
			(effects
				(font
					(size 1 1)
					(thickness 0.15)
				)
				(justify mirror)
			)
		)
		(property "MPN" "GRM035R60J475ME15D"
			(at 0 0 0)
			(layer "B.Fab")
			(hide yes)
			(effects
				(font
					(size 1 1)
					(thickness 0.15)
				)
				(justify mirror)
			)
		)
		(property "Manufacturer" "Murata"
			(at 0 0 0)
			(layer "B.Fab")
			(hide yes)
			(effects
				(font
					(size 1 1)
					(thickness 0.15)
				)
				(justify mirror)
			)
		)
		(property "Val" "4u7"
			(at 0 0 0)
			(layer "B.Fab")
			(hide yes)
			(effects
				(font
					(size 1 1)
					(thickness 0.15)
				)
				(justify mirror)
			)
		)
		(property "Voltage" ""
			(at 0 0 0)
			(layer "B.Fab")
			(hide yes)
			(effects
				(font
					(size 1 1)
					(thickness 0.15)
				)
				(justify mirror)
			)
		)
		(sheetname "FPGA supply")
		(sheetfile "fpga-supply.kicad_sch")
		(attr smd)
		(fp_rect
			(start -0.7 0.35)
			(end 0.7 -0.35)
			(stroke
				(width 0.05)
				(type default)
			)
			(fill no)
			(layer "B.CrtYd")
		)
		(fp_rect
			(start 0.3 -0.15)
			(end -0.301 0.149)
			(stroke
				(width 0.15)
				(type solid)
			)
			(fill no)
			(layer "B.Fab")
		)
		(pad "" smd roundrect
			(at -0.349 0.002)
			(size 0.318 0.36)
			(layers "B.Paste")
			(roundrect_rratio 0.25)
		)
		(pad "" smd roundrect
			(at 0.341 0.002)
			(size 0.318 0.36)
			(layers "B.Paste")
			(roundrect_rratio 0.25)
		)
		(pad "1" smd roundrect
			(at -0.321 0.002)
			(size 0.46 0.4)
			(layers "B.Cu" "B.Mask")
			(roundrect_rratio 0.25)
			(net 1 "GND")
			(pintype "passive")
		)
		(pad "2" smd roundrect
			(at 0.32 0.002)
			(size 0.46 0.4)
			(layers "B.Cu" "B.Mask")
			(roundrect_rratio 0.25)
			(net 650 "+1V0")
			(pintype "passive")
		)
	)
	(footprint "antmicro-footprints:C_0402_1005Metric"
		(layer "B.Cu")
		(at 254.801 166.8 90)
		(descr "Capacitor SMD 0402")
		(tags "capacitor SMD 0402")
		(property "Reference" "C279"
			(at -1.9 -1.576 90)
			(layer "B.SilkS")
			(effects
				(font
					(size 0.7 0.7)
					(thickness 0.15)
				)
				(justify right bottom mirror)
			)
		)
		(property "Value" "C_10p_0402"
			(at 0 -1.4 90)
			(layer "B.Fab")
			(effects
				(font
					(size 0.7 0.7)
					(thickness 0.15)
				)
				(justify right bottom mirror)
			)
		)
		(property "Description" "SMD Multilayer Ceramic Capacitor, 10 pF, 50 V, 0402 [1005 Metric], ± 2%, C0G / NP0, GCM"
			(at 0 0 90)
			(layer "F.Fab")
			(hide yes)
			(effects
				(font
					(size 1.27 1.27)
					(thickness 0.15)
				)
			)
		)
		(property "Author" "Antmicro"
			(at 421.601 -88.001 0)
			(layer "B.Fab")
			(hide yes)
			(effects
				(font
					(size 1 1)
					(thickness 0.15)
				)
				(justify mirror)
			)
		)
		(property "Dielectric" "C0G"
			(at 421.601 -88.001 0)
			(layer "B.Fab")
			(hide yes)
			(effects
				(font
					(size 1 1)
					(thickness 0.15)
				)
				(justify mirror)
			)
		)
		(property "License" "Apache-2.0"
			(at 421.601 -88.001 0)
			(layer "B.Fab")
			(hide yes)
			(effects
				(font
					(size 1 1)
					(thickness 0.15)
				)
				(justify mirror)
			)
		)
		(property "MPN" "GCM1555C1H100GA16D"
			(at 421.601 -88.001 0)
			(layer "B.Fab")
			(hide yes)
			(effects
				(font
					(size 1 1)
					(thickness 0.15)
				)
				(justify mirror)
			)
		)
		(property "Manufacturer" "Murata"
			(at 421.601 -88.001 0)
			(layer "B.Fab")
			(hide yes)
			(effects
				(font
					(size 1 1)
					(thickness 0.15)
				)
				(justify mirror)
			)
		)
		(property "Val" "10p"
			(at 421.601 -88.001 0)
			(layer "B.Fab")
			(hide yes)
			(effects
				(font
					(size 1 1)
					(thickness 0.15)
				)
				(justify mirror)
			)
		)
		(property "Voltage" "50V"
			(at 421.601 -88.001 0)
			(layer "B.Fab")
			(hide yes)
			(effects
				(font
					(size 1 1)
					(thickness 0.15)
				)
				(justify mirror)
			)
		)
		(sheetname "HDMI + Ethernet")
		(sheetfile "hdmi-ethernet.kicad_sch")
		(attr smd)
		(fp_rect
			(start -0.925 0.47)
			(end 0.925 -0.47)
			(stroke
				(width 0.05)
				(type default)
			)
			(fill no)
			(layer "B.CrtYd")
		)
		(fp_line
			(start 0.504 -0.248)
			(end -0.494 -0.248)
			(stroke
				(width 0.15)
				(type solid)
			)
			(layer "B.Fab")
		)
		(fp_line
			(start -0.494 -0.248)
			(end -0.494 0.25)
			(stroke
				(width 0.15)
				(type solid)
			)
			(layer "B.Fab")
		)
		(fp_line
			(start 0.504 0.25)
			(end 0.504 -0.248)
			(stroke
				(width 0.15)
				(type solid)
			)
			(layer "B.Fab")
		)
		(fp_line
			(start -0.494 0.25)
			(end 0.504 0.25)
			(stroke
				(width 0.15)
				(type solid)
			)
			(layer "B.Fab")
		)
		(pad "1" smd roundrect
			(at -0.48 0 90)
			(size 0.59 0.64)
			(layers "B.Cu" "B.Mask" "B.Paste")
			(roundrect_rratio 0.25)
			(net 1 "GND")
			(pintype "passive")
		)
		(pad "2" smd roundrect
			(at 0.48 0 90)
			(size 0.59 0.64)
			(layers "B.Cu" "B.Mask" "B.Paste")
			(roundrect_rratio 0.25)
			(net 729 "/HDMI + Ethernet/ETH2_N")
			(pintype "passive")
		)
	)
	(footprint "antmicro-footprints:R_0402_1005Metric"
		(layer "B.Cu")
		(at 244.099999 84.699999 90)
		(descr "Resistor SMD 0402")
		(tags "resistor SMD 0402")
		(property "Reference" "R127"
			(at -0.725001 0.450001 270)
			(layer "B.SilkS")
			(effects
				(font
					(size 0.7 0.7)
					(thickness 0.15)
				)
				(justify left bottom mirror)
			)
		)
		(property "Value" "R_100R_0402"
			(at 0 -1.4 270)
			(layer "B.Fab")
			(effects
				(font
					(size 0.7 0.7)
					(thickness 0.15)
				)
				(justify left bottom mirror)
			)
		)
		(property "Description" "SMD Chip Resistor, 100 ohm, ± 1%, 62.5 mW, 0402 [1005 Metric], Thick Film, General Purpose"
			(at 0 0 90)
			(layer "F.Fab")
			(hide yes)
			(effects
				(font
					(size 1.27 1.27)
					(thickness 0.15)
				)
			)
		)
		(property "Author" "Antmicro"
			(at 328.799998 -159.4 0)
			(layer "B.Fab")
			(hide yes)
			(effects
				(font
					(size 1 1)
					(thickness 0.15)
				)
				(justify mirror)
			)
		)
		(property "License" "Apache-2.0"
			(at 328.799998 -159.4 0)
			(layer "B.Fab")
			(hide yes)
			(effects
				(font
					(size 1 1)
					(thickness 0.15)
				)
				(justify mirror)
			)
		)
		(property "MPN" "CR0402-FX-1000GLF"
			(at 328.799998 -159.4 0)
			(layer "B.Fab")
			(hide yes)
			(effects
				(font
					(size 1 1)
					(thickness 0.15)
				)
				(justify mirror)
			)
		)
		(property "Manufacturer" "Bourns"
			(at 328.799998 -159.4 0)
			(layer "B.Fab")
			(hide yes)
			(effects
				(font
					(size 1 1)
					(thickness 0.15)
				)
				(justify mirror)
			)
		)
		(property "Tolerance" "1%"
			(at 328.799998 -159.4 0)
			(layer "B.Fab")
			(hide yes)
			(effects
				(font
					(size 1 1)
					(thickness 0.15)
				)
				(justify mirror)
			)
		)
		(property "Val" "100R"
			(at 328.799998 -159.4 0)
			(layer "B.Fab")
			(hide yes)
			(effects
				(font
					(size 1 1)
					(thickness 0.15)
				)
				(justify mirror)
			)
		)
		(sheetname "User GPIO + LED + button + DIP switch")
		(sheetfile "user-gpio.kicad_sch")
		(attr smd)
		(fp_rect
			(start -0.925 0.47)
			(end 0.925 -0.47)
			(stroke
				(width 0.05)
				(type default)
			)
			(fill no)
			(layer "B.CrtYd")
		)
		(fp_rect
			(start -0.5 0.25)
			(end 0.5 -0.25)
			(stroke
				(width 0.15)
				(type solid)
			)
			(fill no)
			(layer "B.Fab")
		)
		(pad "1" smd roundrect
			(at -0.48 0 90)
			(size 0.59 0.64)
			(layers "B.Cu" "B.Mask" "B.Paste")
			(roundrect_rratio 0.25)
			(net 472 "/FPGA Bank 12 & 13/PMOD_B.IO4")
			(pintype "passive")
		)
		(pad "2" smd roundrect
			(at 0.48 0 90)
			(size 0.59 0.64)
			(layers "B.Cu" "B.Mask" "B.Paste")
			(roundrect_rratio 0.25)
			(net 811 "/User GPIO + LED + button + DIP switch/PMOD_B_4")
			(pintype "passive")
		)
	)
	(footprint "antmicro-footprints:C_0402_1005Metric"
		(layer "B.Cu")
		(at 158.6 144.5 -90)
		(descr "Capacitor SMD 0402")
		(tags "capacitor SMD 0402")
		(property "Reference" "C173"
			(at -1.9 3.475 90)
			(layer "B.SilkS")
			(effects
				(font
					(size 0.7 0.7)
					(thickness 0.15)
				)
				(justify left bottom mirror)
			)
		)
		(property "Value" "C_100n_0402"
			(at 0 -1.169 90)
			(layer "B.Fab")
			(effects
				(font
					(size 0.7 0.7)
					(thickness 0.15)
				)
				(justify left bottom mirror)
			)
		)
		(property "Description" "SMD Multilayer Ceramic Capacitor, 0.1 µF, 50 V, 0402 [1005 Metric], ± 10%, X5R, GRM Series"
			(at 0 0 270)
			(layer "F.Fab")
			(hide yes)
			(effects
				(font
					(size 1.27 1.27)
					(thickness 0.15)
				)
			)
		)
		(property "Author" "Antmicro"
			(at 14.1 303.1 0)
			(layer "B.Fab")
			(hide yes)
			(effects
				(font
					(size 1 1)
					(thickness 0.15)
				)
				(justify mirror)
			)
		)
		(property "Dielectric" "X5R"
			(at 14.1 303.1 0)
			(layer "B.Fab")
			(hide yes)
			(effects
				(font
					(size 1 1)
					(thickness 0.15)
				)
				(justify mirror)
			)
		)
		(property "License" "Apache-2.0"
			(at 14.1 303.1 0)
			(layer "B.Fab")
			(hide yes)
			(effects
				(font
					(size 1 1)
					(thickness 0.15)
				)
				(justify mirror)
			)
		)
		(property "MPN" "GRM155R61H104KE14D"
			(at 14.1 303.1 0)
			(layer "B.Fab")
			(hide yes)
			(effects
				(font
					(size 1 1)
					(thickness 0.15)
				)
				(justify mirror)
			)
		)
		(property "Manufacturer" "Murata"
			(at 14.1 303.1 0)
			(layer "B.Fab")
			(hide yes)
			(effects
				(font
					(size 1 1)
					(thickness 0.15)
				)
				(justify mirror)
			)
		)
		(property "Val" "100n"
			(at 14.1 303.1 0)
			(layer "B.Fab")
			(hide yes)
			(effects
				(font
					(size 1 1)
					(thickness 0.15)
				)
				(justify mirror)
			)
		)
		(property "Voltage" "50V"
			(at 14.1 303.1 0)
			(layer "B.Fab")
			(hide yes)
			(effects
				(font
					(size 1 1)
					(thickness 0.15)
				)
				(justify mirror)
			)
		)
		(sheetname "DRAM + SRAM")
		(sheetfile "ram.kicad_sch")
		(attr smd)
		(fp_rect
			(start -0.925 0.47)
			(end 0.925 -0.47)
			(stroke
				(width 0.05)
				(type default)
			)
			(fill no)
			(layer "B.CrtYd")
		)
		(fp_line
			(start -0.494 0.25)
			(end 0.504 0.25)
			(stroke
				(width 0.15)
				(type solid)
			)
			(layer "B.Fab")
		)
		(fp_line
			(start 0.504 0.25)
			(end 0.504 -0.248)
			(stroke
				(width 0.15)
				(type solid)
			)
			(layer "B.Fab")
		)
		(fp_line
			(start -0.494 -0.248)
			(end -0.494 0.25)
			(stroke
				(width 0.15)
				(type solid)
			)
			(layer "B.Fab")
		)
		(fp_line
			(start 0.504 -0.248)
			(end -0.494 -0.248)
			(stroke
				(width 0.15)
				(type solid)
			)
			(layer "B.Fab")
		)
		(pad "1" smd roundrect
			(at -0.48 0 270)
			(size 0.59 0.64)
			(layers "B.Cu" "B.Mask" "B.Paste")
			(roundrect_rratio 0.25)
			(net 1 "GND")
			(pintype "passive")
		)
		(pad "2" smd roundrect
			(at 0.48 0 270)
			(size 0.59 0.64)
			(layers "B.Cu" "B.Mask" "B.Paste")
			(roundrect_rratio 0.25)
			(net 7 "+0V675_VTT")
			(pintype "passive")
		)
	)
	(footprint "antmicro-footprints:R_0402_1005Metric"
		(layer "B.Cu")
		(at 214.199999 77.899999 -90)
		(descr "Resistor SMD 0402")
		(tags "resistor SMD 0402")
		(property "Reference" "R120"
			(at -3.599999 -0.375001 90)
			(layer "B.SilkS")
			(effects
				(font
					(size 0.7 0.7)
					(thickness 0.15)
				)
				(justify left bottom mirror)
			)
		)
		(property "Value" "R_100R_0402"
			(at 0 -1.4 90)
			(layer "B.Fab")
			(effects
				(font
					(size 0.7 0.7)
					(thickness 0.15)
				)
				(justify left bottom mirror)
			)
		)
		(property "Description" "SMD Chip Resistor, 100 ohm, ± 1%, 62.5 mW, 0402 [1005 Metric], Thick Film, General Purpose"
			(at 0 0 270)
			(layer "F.Fab")
			(hide yes)
			(effects
				(font
					(size 1.27 1.27)
					(thickness 0.15)
				)
			)
		)
		(property "Author" "Antmicro"
			(at 136.3 292.099998 0)
			(layer "B.Fab")
			(hide yes)
			(effects
				(font
					(size 1 1)
					(thickness 0.15)
				)
				(justify mirror)
			)
		)
		(property "License" "Apache-2.0"
			(at 136.3 292.099998 0)
			(layer "B.Fab")
			(hide yes)
			(effects
				(font
					(size 1 1)
					(thickness 0.15)
				)
				(justify mirror)
			)
		)
		(property "MPN" "CR0402-FX-1000GLF"
			(at 136.3 292.099998 0)
			(layer "B.Fab")
			(hide yes)
			(effects
				(font
					(size 1 1)
					(thickness 0.15)
				)
				(justify mirror)
			)
		)
		(property "Manufacturer" "Bourns"
			(at 136.3 292.099998 0)
			(layer "B.Fab")
			(hide yes)
			(effects
				(font
					(size 1 1)
					(thickness 0.15)
				)
				(justify mirror)
			)
		)
		(property "Tolerance" "1%"
			(at 136.3 292.099998 0)
			(layer "B.Fab")
			(hide yes)
			(effects
				(font
					(size 1 1)
					(thickness 0.15)
				)
				(justify mirror)
			)
		)
		(property "Val" "100R"
			(at 136.3 292.099998 0)
			(layer "B.Fab")
			(hide yes)
			(effects
				(font
					(size 1 1)
					(thickness 0.15)
				)
				(justify mirror)
			)
		)
		(sheetname "User GPIO + LED + button + DIP switch")
		(sheetfile "user-gpio.kicad_sch")
		(attr smd)
		(fp_rect
			(start -0.925 0.47)
			(end 0.925 -0.47)
			(stroke
				(width 0.05)
				(type default)
			)
			(fill no)
			(layer "B.CrtYd")
		)
		(fp_rect
			(start -0.5 0.25)
			(end 0.5 -0.25)
			(stroke
				(width 0.15)
				(type solid)
			)
			(fill no)
			(layer "B.Fab")
		)
		(pad "1" smd roundrect
			(at -0.48 0 270)
			(size 0.59 0.64)
			(layers "B.Cu" "B.Mask" "B.Paste")
			(roundrect_rratio 0.25)
			(net 456 "/FPGA Bank 12 & 13/PMOD_A.IO1")
			(pintype "passive")
		)
		(pad "2" smd roundrect
			(at 0.48 0 270)
			(size 0.59 0.64)
			(layers "B.Cu" "B.Mask" "B.Paste")
			(roundrect_rratio 0.25)
			(net 809 "/User GPIO + LED + button + DIP switch/PMOD_A_1")
			(pintype "passive")
		)
	)
	(footprint "antmicro-footprints:C_0402_1005Metric"
		(layer "B.Cu")
		(at 196 137.5)
		(descr "Capacitor SMD 0402")
		(tags "capacitor SMD 0402")
		(property "Reference" "C78"
			(at 1.275 1.225 180)
			(layer "B.SilkS")
			(effects
				(font
					(size 0.7 0.7)
					(thickness 0.15)
				)
				(justify left bottom mirror)
			)
		)
		(property "Value" "C_100n_0402"
			(at 0 -1.169 180)
			(layer "B.Fab")
			(effects
				(font
					(size 0.7 0.7)
					(thickness 0.15)
				)
				(justify left bottom mirror)
			)
		)
		(property "Description" "SMD Multilayer Ceramic Capacitor, 0.1 µF, 50 V, 0402 [1005 Metric], ± 10%, X5R, GRM Series"
			(at 0 0 0)
			(layer "F.Fab")
			(hide yes)
			(effects
				(font
					(size 1.27 1.27)
					(thickness 0.15)
				)
			)
		)
		(property "Author" "Antmicro"
			(at 0 0 0)
			(layer "B.Fab")
			(hide yes)
			(effects
				(font
					(size 1 1)
					(thickness 0.15)
				)
				(justify mirror)
			)
		)
		(property "Dielectric" "X5R"
			(at 0 0 0)
			(layer "B.Fab")
			(hide yes)
			(effects
				(font
					(size 1 1)
					(thickness 0.15)
				)
				(justify mirror)
			)
		)
		(property "License" "Apache-2.0"
			(at 0 0 0)
			(layer "B.Fab")
			(hide yes)
			(effects
				(font
					(size 1 1)
					(thickness 0.15)
				)
				(justify mirror)
			)
		)
		(property "MPN" "GRM155R61H104KE14D"
			(at 0 0 0)
			(layer "B.Fab")
			(hide yes)
			(effects
				(font
					(size 1 1)
					(thickness 0.15)
				)
				(justify mirror)
			)
		)
		(property "Manufacturer" "Murata"
			(at 0 0 0)
			(layer "B.Fab")
			(hide yes)
			(effects
				(font
					(size 1 1)
					(thickness 0.15)
				)
				(justify mirror)
			)
		)
		(property "Val" "100n"
			(at 0 0 0)
			(layer "B.Fab")
			(hide yes)
			(effects
				(font
					(size 1 1)
					(thickness 0.15)
				)
				(justify mirror)
			)
		)
		(property "Voltage" "50V"
			(at 0 0 0)
			(layer "B.Fab")
			(hide yes)
			(effects
				(font
					(size 1 1)
					(thickness 0.15)
				)
				(justify mirror)
			)
		)
		(sheetname "FPGA Bank 33 & 34")
		(sheetfile "fpga-bank-33-34.kicad_sch")
		(attr smd)
		(fp_rect
			(start -0.925 0.47)
			(end 0.925 -0.47)
			(stroke
				(width 0.05)
				(type default)
			)
			(fill no)
			(layer "B.CrtYd")
		)
		(fp_line
			(start -0.494 -0.248)
			(end -0.494 0.25)
			(stroke
				(width 0.15)
				(type solid)
			)
			(layer "B.Fab")
		)
		(fp_line
			(start -0.494 0.25)
			(end 0.504 0.25)
			(stroke
				(width 0.15)
				(type solid)
			)
			(layer "B.Fab")
		)
		(fp_line
			(start 0.504 -0.248)
			(end -0.494 -0.248)
			(stroke
				(width 0.15)
				(type solid)
			)
			(layer "B.Fab")
		)
		(fp_line
			(start 0.504 0.25)
			(end 0.504 -0.248)
			(stroke
				(width 0.15)
				(type solid)
			)
			(layer "B.Fab")
		)
		(pad "1" smd roundrect
			(at -0.48 0)
			(size 0.59 0.64)
			(layers "B.Cu" "B.Mask" "B.Paste")
			(roundrect_rratio 0.25)
			(net 1 "GND")
			(pintype "passive")
		)
		(pad "2" smd roundrect
			(at 0.48 0)
			(size 0.59 0.64)
			(layers "B.Cu" "B.Mask" "B.Paste")
			(roundrect_rratio 0.25)
			(net 26 "+1V8")
			(pintype "passive")
		)
	)
	(footprint "antmicro-footprints:C_0603_1608Metric"
		(layer "B.Cu")
		(at 200 141.8 90)
		(descr "Capacitor SMD 0603")
		(tags "capacitor 0603")
		(property "Reference" "C380"
			(at -1.375 -0.525 90)
			(layer "B.SilkS")
			(effects
				(font
					(size 0.7 0.7)
					(thickness 0.15)
				)
				(justify right bottom mirror)
			)
		)
		(property "Value" "C_47u_0603"
			(at 0 -1.6 90)
			(layer "B.Fab")
			(effects
				(font
					(size 0.7 0.7)
					(thickness 0.15)
				)
				(justify right bottom mirror)
			)
		)
		(property "Description" "SMD Multilayer Ceramic Capacitor, 47 µF, 6.3 V, 0603 [1608 Metric], ± 20%, X5R, GRM Series"
			(at 0 0 90)
			(layer "F.Fab")
			(hide yes)
			(effects
				(font
					(size 1.27 1.27)
					(thickness 0.15)
				)
			)
		)
		(property "Author" "Antmicro"
			(at 341.8 -58.2 0)
			(layer "B.Fab")
			(hide yes)
			(effects
				(font
					(size 1 1)
					(thickness 0.15)
				)
				(justify mirror)
			)
		)
		(property "Dielectric" ""
			(at 341.8 -58.2 0)
			(layer "B.Fab")
			(hide yes)
			(effects
				(font
					(size 1 1)
					(thickness 0.15)
				)
				(justify mirror)
			)
		)
		(property "License" "Apache-2.0"
			(at 341.8 -58.2 0)
			(layer "B.Fab")
			(hide yes)
			(effects
				(font
					(size 1 1)
					(thickness 0.15)
				)
				(justify mirror)
			)
		)
		(property "MPN" "GRM188R60J476ME15D"
			(at 341.8 -58.2 0)
			(layer "B.Fab")
			(hide yes)
			(effects
				(font
					(size 1 1)
					(thickness 0.15)
				)
				(justify mirror)
			)
		)
		(property "Manufacturer" "Murata"
			(at 341.8 -58.2 0)
			(layer "B.Fab")
			(hide yes)
			(effects
				(font
					(size 1 1)
					(thickness 0.15)
				)
				(justify mirror)
			)
		)
		(property "Val" "47u"
			(at 341.8 -58.2 0)
			(layer "B.Fab")
			(hide yes)
			(effects
				(font
					(size 1 1)
					(thickness 0.15)
				)
				(justify mirror)
			)
		)
		(property "Voltage" ""
			(at 341.8 -58.2 0)
			(layer "B.Fab")
			(hide yes)
			(effects
				(font
					(size 1 1)
					(thickness 0.15)
				)
				(justify mirror)
			)
		)
		(sheetname "FPGA supply")
		(sheetfile "fpga-supply.kicad_sch")
		(attr smd)
		(fp_line
			(start -0.15 -0.4)
			(end 0.15 -0.4)
			(stroke
				(width 0.15)
				(type solid)
			)
			(layer "B.SilkS")
		)
		(fp_line
			(start -0.15 0.4)
			(end 0.15 0.4)
			(stroke
				(width 0.15)
				(type solid)
			)
			(layer "B.SilkS")
		)
		(fp_rect
			(start -1.25 0.65)
			(end 1.25 -0.65)
			(stroke
				(width 0.05)
				(type solid)
			)
			(fill no)
			(layer "B.CrtYd")
		)
		(fp_rect
			(start -0.8 0.4)
			(end 0.8 -0.4)
			(stroke
				(width 0.15)
				(type solid)
			)
			(fill no)
			(layer "B.Fab")
		)
		(pad "1" smd roundrect
			(at -0.7 0 90)
			(size 0.8 1)
			(layers "B.Cu" "B.Mask" "B.Paste")
			(roundrect_rratio 0.2)
			(net 1 "GND")
			(pintype "passive")
		)
		(pad "2" smd roundrect
			(at 0.7 0 90)
			(size 0.8 1)
			(layers "B.Cu" "B.Mask" "B.Paste")
			(roundrect_rratio 0.2)
			(net 650 "+1V0")
			(pintype "passive")
		)
	)
	(footprint "antmicro-footprints:C_0402_1005Metric"
		(layer "B.Cu")
		(at 213 128.52 180)
		(descr "Capacitor SMD 0402")
		(tags "capacitor SMD 0402")
		(property "Reference" "C13"
			(at -1.075 0.45 0)
			(layer "B.SilkS")
			(effects
				(font
					(size 0.7 0.7)
					(thickness 0.15)
				)
				(justify left bottom mirror)
			)
		)
		(property "Value" "C_100n_0402"
			(at 0 -1.169 0)
			(layer "B.Fab")
			(effects
				(font
					(size 0.7 0.7)
					(thickness 0.15)
				)
				(justify left bottom mirror)
			)
		)
		(property "Description" "SMD Multilayer Ceramic Capacitor, 0.1 µF, 50 V, 0402 [1005 Metric], ± 10%, X5R, GRM Series"
			(at 0 0 180)
			(layer "F.Fab")
			(hide yes)
			(effects
				(font
					(size 1.27 1.27)
					(thickness 0.15)
				)
			)
		)
		(property "Author" "Antmicro"
			(at 426 257.04 0)
			(layer "B.Fab")
			(hide yes)
			(effects
				(font
					(size 1 1)
					(thickness 0.15)
				)
				(justify mirror)
			)
		)
		(property "Dielectric" "X5R"
			(at 426 257.04 0)
			(layer "B.Fab")
			(hide yes)
			(effects
				(font
					(size 1 1)
					(thickness 0.15)
				)
				(justify mirror)
			)
		)
		(property "License" "Apache-2.0"
			(at 426 257.04 0)
			(layer "B.Fab")
			(hide yes)
			(effects
				(font
					(size 1 1)
					(thickness 0.15)
				)
				(justify mirror)
			)
		)
		(property "MPN" "GRM155R61H104KE14D"
			(at 426 257.04 0)
			(layer "B.Fab")
			(hide yes)
			(effects
				(font
					(size 1 1)
					(thickness 0.15)
				)
				(justify mirror)
			)
		)
		(property "Manufacturer" "Murata"
			(at 426 257.04 0)
			(layer "B.Fab")
			(hide yes)
			(effects
				(font
					(size 1 1)
					(thickness 0.15)
				)
				(justify mirror)
			)
		)
		(property "Val" "100n"
			(at 426 257.04 0)
			(layer "B.Fab")
			(hide yes)
			(effects
				(font
					(size 1 1)
					(thickness 0.15)
				)
				(justify mirror)
			)
		)
		(property "Voltage" "50V"
			(at 426 257.04 0)
			(layer "B.Fab")
			(hide yes)
			(effects
				(font
					(size 1 1)
					(thickness 0.15)
				)
				(justify mirror)
			)
		)
		(sheetname "FPGA Bank 14 & 15")
		(sheetfile "fpga-bank-14-15.kicad_sch")
		(attr smd)
		(fp_rect
			(start -0.925 0.47)
			(end 0.925 -0.47)
			(stroke
				(width 0.05)
				(type default)
			)
			(fill no)
			(layer "B.CrtYd")
		)
		(fp_line
			(start 0.504 0.25)
			(end 0.504 -0.248)
			(stroke
				(width 0.15)
				(type solid)
			)
			(layer "B.Fab")
		)
		(fp_line
			(start 0.504 -0.248)
			(end -0.494 -0.248)
			(stroke
				(width 0.15)
				(type solid)
			)
			(layer "B.Fab")
		)
		(fp_line
			(start -0.494 0.25)
			(end 0.504 0.25)
			(stroke
				(width 0.15)
				(type solid)
			)
			(layer "B.Fab")
		)
		(fp_line
			(start -0.494 -0.248)
			(end -0.494 0.25)
			(stroke
				(width 0.15)
				(type solid)
			)
			(layer "B.Fab")
		)
		(pad "1" smd roundrect
			(at -0.48 0 180)
			(size 0.59 0.64)
			(layers "B.Cu" "B.Mask" "B.Paste")
			(roundrect_rratio 0.25)
			(net 1 "GND")
			(pintype "passive")
		)
		(pad "2" smd roundrect
			(at 0.48 0 180)
			(size 0.59 0.64)
			(layers "B.Cu" "B.Mask" "B.Paste")
			(roundrect_rratio 0.25)
			(net 24 "+3V3")
			(pintype "passive")
		)
	)
	(footprint "antmicro-footprints:R_0402_1005Metric"
		(layer "B.Cu")
		(at 198.491252 91.55)
		(descr "Resistor SMD 0402")
		(tags "resistor SMD 0402")
		(property "Reference" "R209"
			(at 1.483748 -4.6 180)
			(layer "B.SilkS")
			(effects
				(font
					(size 0.7 0.7)
					(thickness 0.15)
				)
				(justify left bottom mirror)
			)
		)
		(property "Value" "R_2k2_0402"
			(at 0 -1.4 180)
			(layer "B.Fab")
			(effects
				(font
					(size 0.7 0.7)
					(thickness 0.15)
				)
				(justify left bottom mirror)
			)
		)
		(property "Description" "SMD Chip Resistor, 2.2 kohm, ± 1%, 62.5 mW, 0402 [1005 Metric], Thick Film, General Purpose"
			(at 0 0 0)
			(layer "F.Fab")
			(hide yes)
			(effects
				(font
					(size 1.27 1.27)
					(thickness 0.15)
				)
			)
		)
		(property "Author" "Antmicro"
			(at 0 0 0)
			(layer "B.Fab")
			(hide yes)
			(effects
				(font
					(size 1 1)
					(thickness 0.15)
				)
				(justify mirror)
			)
		)
		(property "DNP" "DNP"
			(at 0 0 0)
			(layer "B.Fab")
			(hide yes)
			(effects
				(font
					(size 1 1)
					(thickness 0.15)
				)
				(justify mirror)
			)
		)
		(property "License" "Apache-2.0"
			(at 0 0 0)
			(layer "B.Fab")
			(hide yes)
			(effects
				(font
					(size 1 1)
					(thickness 0.15)
				)
				(justify mirror)
			)
		)
		(property "MPN" "CR0402-FX-2201GLF"
			(at 0 0 0)
			(layer "B.Fab")
			(hide yes)
			(effects
				(font
					(size 1 1)
					(thickness 0.15)
				)
				(justify mirror)
			)
		)
		(property "Manufacturer" "Bourns"
			(at 0 0 0)
			(layer "B.Fab")
			(hide yes)
			(effects
				(font
					(size 1 1)
					(thickness 0.15)
				)
				(justify mirror)
			)
		)
		(property "Tolerance" "1%"
			(at 0 0 0)
			(layer "B.Fab")
			(hide yes)
			(effects
				(font
					(size 1 1)
					(thickness 0.15)
				)
				(justify mirror)
			)
		)
		(property "Val" "2k2"
			(at 0 0 0)
			(layer "B.Fab")
			(hide yes)
			(effects
				(font
					(size 1 1)
					(thickness 0.15)
				)
				(justify mirror)
			)
		)
		(property "dnp" ""
			(at 0 0 0)
			(layer "B.Fab")
			(hide yes)
			(effects
				(font
					(size 1 1)
					(thickness 0.15)
				)
				(justify mirror)
			)
		)
		(property "exclude_from_bom" ""
			(at 0 0 0)
			(layer "B.Fab")
			(hide yes)
			(effects
				(font
					(size 1 1)
					(thickness 0.15)
				)
				(justify mirror)
			)
		)
		(sheetname "HDMI + Ethernet")
		(sheetfile "hdmi-ethernet.kicad_sch")
		(attr smd exclude_from_bom)
		(fp_rect
			(start -0.925 0.47)
			(end 0.925 -0.47)
			(stroke
				(width 0.05)
				(type default)
			)
			(fill no)
			(layer "B.CrtYd")
		)
		(fp_rect
			(start -0.5 0.25)
			(end 0.5 -0.25)
			(stroke
				(width 0.15)
				(type solid)
			)
			(fill no)
			(layer "B.Fab")
		)
		(pad "1" smd roundrect
			(at -0.48 0)
			(size 0.59 0.64)
			(layers "B.Cu" "B.Mask" "B.Paste")
			(roundrect_rratio 0.25)
			(net 503 "/FPGA Bank 16 & 17/GBE_RGMII.RXD3")
			(pintype "passive")
		)
		(pad "2" smd roundrect
			(at 0.48 0)
			(size 0.59 0.64)
			(layers "B.Cu" "B.Mask" "B.Paste")
			(roundrect_rratio 0.25)
			(net 1 "GND")
			(pintype "passive")
		)
	)
	(footprint "antmicro-footprints:C_0201"
		(layer "B.Cu")
		(at 189.8 125.5 180)
		(descr "Capacitor SMD 0201")
		(tags "capacitor SMD 0201")
		(property "Reference" "C153"
			(at 0.5 -0.4 0)
			(layer "B.SilkS")
			(effects
				(font
					(size 0.7 0.7)
					(thickness 0.15)
				)
				(justify left bottom mirror)
			)
		)
		(property "Value" "C_100n_0201"
			(at 0 -1.4 0)
			(layer "B.Fab")
			(effects
				(font
					(size 0.7 0.7)
					(thickness 0.15)
				)
				(justify left bottom mirror)
			)
		)
		(property "Description" "SMD Multilayer Ceramic Capacitor, 0.1 µF, 6.3 V, 0201 [0603 Metric], ± 10%, X6S, CC Series"
			(at 0 0 180)
			(layer "F.Fab")
			(hide yes)
			(effects
				(font
					(size 1.27 1.27)
					(thickness 0.15)
				)
			)
		)
		(property "Author" "Antmicro"
			(at 379.6 251 0)
			(layer "B.Fab")
			(hide yes)
			(effects
				(font
					(size 1 1)
					(thickness 0.15)
				)
				(justify mirror)
			)
		)
		(property "Dielectric" ""
			(at 379.6 251 0)
			(layer "B.Fab")
			(hide yes)
			(effects
				(font
					(size 1 1)
					(thickness 0.15)
				)
				(justify mirror)
			)
		)
		(property "License" "Apache-2.0"
			(at 379.6 251 0)
			(layer "B.Fab")
			(hide yes)
			(effects
				(font
					(size 1 1)
					(thickness 0.15)
				)
				(justify mirror)
			)
		)
		(property "MPN" "CC0201KRX6S5BB104"
			(at 379.6 251 0)
			(layer "B.Fab")
			(hide yes)
			(effects
				(font
					(size 1 1)
					(thickness 0.15)
				)
				(justify mirror)
			)
		)
		(property "Manufacturer" "YAGEO"
			(at 379.6 251 0)
			(layer "B.Fab")
			(hide yes)
			(effects
				(font
					(size 1 1)
					(thickness 0.15)
				)
				(justify mirror)
			)
		)
		(property "Val" "100n"
			(at 379.6 251 0)
			(layer "B.Fab")
			(hide yes)
			(effects
				(font
					(size 1 1)
					(thickness 0.15)
				)
				(justify mirror)
			)
		)
		(property "Voltage" ""
			(at 379.6 251 0)
			(layer "B.Fab")
			(hide yes)
			(effects
				(font
					(size 1 1)
					(thickness 0.15)
				)
				(justify mirror)
			)
		)
		(sheetname "FPGA supply")
		(sheetfile "fpga-supply.kicad_sch")
		(attr smd)
		(fp_rect
			(start -0.7 0.35)
			(end 0.7 -0.35)
			(stroke
				(width 0.05)
				(type default)
			)
			(fill no)
			(layer "B.CrtYd")
		)
		(fp_rect
			(start 0.3 -0.15)
			(end -0.301 0.149)
			(stroke
				(width 0.15)
				(type solid)
			)
			(fill no)
			(layer "B.Fab")
		)
		(pad "" smd roundrect
			(at -0.349 0.002 180)
			(size 0.318 0.36)
			(layers "B.Paste")
			(roundrect_rratio 0.25)
		)
		(pad "" smd roundrect
			(at 0.341 0.002 180)
			(size 0.318 0.36)
			(layers "B.Paste")
			(roundrect_rratio 0.25)
		)
		(pad "1" smd roundrect
			(at -0.321 0.002 180)
			(size 0.46 0.4)
			(layers "B.Cu" "B.Mask")
			(roundrect_rratio 0.25)
			(net 1 "GND")
			(pintype "passive")
		)
		(pad "2" smd roundrect
			(at 0.32 0.002 180)
			(size 0.46 0.4)
			(layers "B.Cu" "B.Mask")
			(roundrect_rratio 0.25)
			(net 8 "+1V2_MGTAVTT")
			(pintype "passive")
		)
	)
	(footprint "antmicro-footprints:C_0402_1005Metric"
		(layer "B.Cu")
		(at 205 120.5)
		(descr "Capacitor SMD 0402")
		(tags "capacitor SMD 0402")
		(property "Reference" "C98"
			(at 29.35 -29.575 180)
			(layer "B.SilkS")
			(effects
				(font
					(size 0.7 0.7)
					(thickness 0.15)
				)
				(justify left bottom mirror)
			)
		)
		(property "Value" "C_100n_0402"
			(at 0 -1.169 180)
			(layer "B.Fab")
			(effects
				(font
					(size 0.7 0.7)
					(thickness 0.15)
				)
				(justify left bottom mirror)
			)
		)
		(property "Description" "SMD Multilayer Ceramic Capacitor, 0.1 µF, 50 V, 0402 [1005 Metric], ± 10%, X5R, GRM Series"
			(at 0 0 0)
			(layer "F.Fab")
			(hide yes)
			(effects
				(font
					(size 1.27 1.27)
					(thickness 0.15)
				)
			)
		)
		(property "Author" "Antmicro"
			(at 0 0 0)
			(layer "B.Fab")
			(hide yes)
			(effects
				(font
					(size 1 1)
					(thickness 0.15)
				)
				(justify mirror)
			)
		)
		(property "Dielectric" "X5R"
			(at 0 0 0)
			(layer "B.Fab")
			(hide yes)
			(effects
				(font
					(size 1 1)
					(thickness 0.15)
				)
				(justify mirror)
			)
		)
		(property "License" "Apache-2.0"
			(at 0 0 0)
			(layer "B.Fab")
			(hide yes)
			(effects
				(font
					(size 1 1)
					(thickness 0.15)
				)
				(justify mirror)
			)
		)
		(property "MPN" "GRM155R61H104KE14D"
			(at 0 0 0)
			(layer "B.Fab")
			(hide yes)
			(effects
				(font
					(size 1 1)
					(thickness 0.15)
				)
				(justify mirror)
			)
		)
		(property "Manufacturer" "Murata"
			(at 0 0 0)
			(layer "B.Fab")
			(hide yes)
			(effects
				(font
					(size 1 1)
					(thickness 0.15)
				)
				(justify mirror)
			)
		)
		(property "Val" "100n"
			(at 0 0 0)
			(layer "B.Fab")
			(hide yes)
			(effects
				(font
					(size 1 1)
					(thickness 0.15)
				)
				(justify mirror)
			)
		)
		(property "Voltage" "50V"
			(at 0 0 0)
			(layer "B.Fab")
			(hide yes)
			(effects
				(font
					(size 1 1)
					(thickness 0.15)
				)
				(justify mirror)
			)
		)
		(sheetname "FPGA Bank 16 & 17")
		(sheetfile "fpga-bank-16-17.kicad_sch")
		(attr smd)
		(fp_rect
			(start -0.925 0.47)
			(end 0.925 -0.47)
			(stroke
				(width 0.05)
				(type default)
			)
			(fill no)
			(layer "B.CrtYd")
		)
		(fp_line
			(start -0.494 -0.248)
			(end -0.494 0.25)
			(stroke
				(width 0.15)
				(type solid)
			)
			(layer "B.Fab")
		)
		(fp_line
			(start -0.494 0.25)
			(end 0.504 0.25)
			(stroke
				(width 0.15)
				(type solid)
			)
			(layer "B.Fab")
		)
		(fp_line
			(start 0.504 -0.248)
			(end -0.494 -0.248)
			(stroke
				(width 0.15)
				(type solid)
			)
			(layer "B.Fab")
		)
		(fp_line
			(start 0.504 0.25)
			(end 0.504 -0.248)
			(stroke
				(width 0.15)
				(type solid)
			)
			(layer "B.Fab")
		)
		(pad "1" smd roundrect
			(at -0.48 0)
			(size 0.59 0.64)
			(layers "B.Cu" "B.Mask" "B.Paste")
			(roundrect_rratio 0.25)
			(net 1 "GND")
			(pintype "passive")
		)
		(pad "2" smd roundrect
			(at 0.48 0)
			(size 0.59 0.64)
			(layers "B.Cu" "B.Mask" "B.Paste")
			(roundrect_rratio 0.25)
			(net 24 "+3V3")
			(pintype "passive")
		)
	)
	(footprint "antmicro-footprints:R_0402_1005Metric"
		(layer "B.Cu")
		(at 242.301 114.3 90)
		(descr "Resistor SMD 0402")
		(tags "resistor SMD 0402")
		(property "Reference" "R168"
			(at 1.375 1.274 270)
			(layer "B.SilkS")
			(effects
				(font
					(size 0.7 0.7)
					(thickness 0.15)
				)
				(justify left bottom mirror)
			)
		)
		(property "Value" "R_100k_0402"
			(at 0 -1.4 270)
			(layer "B.Fab")
			(effects
				(font
					(size 0.7 0.7)
					(thickness 0.15)
				)
				(justify left bottom mirror)
			)
		)
		(property "Description" "SMD Chip Resistor, 100 kohm, ± 1%, 62.5 mW, 0402 [1005 Metric], Thick Film, General Purpose"
			(at 0 0 90)
			(layer "F.Fab")
			(hide yes)
			(effects
				(font
					(size 1.27 1.27)
					(thickness 0.15)
				)
			)
		)
		(property "Author" "Antmicro"
			(at 356.601 -128.001 0)
			(layer "B.Fab")
			(hide yes)
			(effects
				(font
					(size 1 1)
					(thickness 0.15)
				)
				(justify mirror)
			)
		)
		(property "License" "Apache-2.0"
			(at 356.601 -128.001 0)
			(layer "B.Fab")
			(hide yes)
			(effects
				(font
					(size 1 1)
					(thickness 0.15)
				)
				(justify mirror)
			)
		)
		(property "MPN" "CR0402-FX-1003GLF"
			(at 356.601 -128.001 0)
			(layer "B.Fab")
			(hide yes)
			(effects
				(font
					(size 1 1)
					(thickness 0.15)
				)
				(justify mirror)
			)
		)
		(property "Manufacturer" "Bourns"
			(at 356.601 -128.001 0)
			(layer "B.Fab")
			(hide yes)
			(effects
				(font
					(size 1 1)
					(thickness 0.15)
				)
				(justify mirror)
			)
		)
		(property "Tolerance" "1%"
			(at 356.601 -128.001 0)
			(layer "B.Fab")
			(hide yes)
			(effects
				(font
					(size 1 1)
					(thickness 0.15)
				)
				(justify mirror)
			)
		)
		(property "Val" "100k"
			(at 356.601 -128.001 0)
			(layer "B.Fab")
			(hide yes)
			(effects
				(font
					(size 1 1)
					(thickness 0.15)
				)
				(justify mirror)
			)
		)
		(sheetname "User GPIO + LED + button + DIP switch")
		(sheetfile "user-gpio.kicad_sch")
		(attr smd)
		(fp_rect
			(start -0.925 0.47)
			(end 0.925 -0.47)
			(stroke
				(width 0.05)
				(type default)
			)
			(fill no)
			(layer "B.CrtYd")
		)
		(fp_rect
			(start -0.5 0.25)
			(end 0.5 -0.25)
			(stroke
				(width 0.15)
				(type solid)
			)
			(fill no)
			(layer "B.Fab")
		)
		(pad "1" smd roundrect
			(at -0.48 0 90)
			(size 0.59 0.64)
			(layers "B.Cu" "B.Mask" "B.Paste")
			(roundrect_rratio 0.25)
			(net 29 "Net-(J4-Pin_4)")
			(pintype "passive")
		)
		(pad "2" smd roundrect
			(at 0.48 0 90)
			(size 0.59 0.64)
			(layers "B.Cu" "B.Mask" "B.Paste")
			(roundrect_rratio 0.25)
			(net 703 "+5V")
			(pintype "passive")
		)
	)
	(footprint "antmicro-footprints:C_0402_1005Metric"
		(layer "B.Cu")
		(at 159.55 146.5 -90)
		(descr "Capacitor SMD 0402")
		(tags "capacitor SMD 0402")
		(property "Reference" "C174"
			(at -1.025 3.475 90)
			(layer "B.SilkS")
			(effects
				(font
					(size 0.7 0.7)
					(thickness 0.15)
				)
				(justify left bottom mirror)
			)
		)
		(property "Value" "C_100n_0402"
			(at 0 -1.169 90)
			(layer "B.Fab")
			(effects
				(font
					(size 0.7 0.7)
					(thickness 0.15)
				)
				(justify left bottom mirror)
			)
		)
		(property "Description" "SMD Multilayer Ceramic Capacitor, 0.1 µF, 50 V, 0402 [1005 Metric], ± 10%, X5R, GRM Series"
			(at 0 0 270)
			(layer "F.Fab")
			(hide yes)
			(effects
				(font
					(size 1.27 1.27)
					(thickness 0.15)
				)
			)
		)
		(property "Author" "Antmicro"
			(at 13.05 306.05 0)
			(layer "B.Fab")
			(hide yes)
			(effects
				(font
					(size 1 1)
					(thickness 0.15)
				)
				(justify mirror)
			)
		)
		(property "Dielectric" "X5R"
			(at 13.05 306.05 0)
			(layer "B.Fab")
			(hide yes)
			(effects
				(font
					(size 1 1)
					(thickness 0.15)
				)
				(justify mirror)
			)
		)
		(property "License" "Apache-2.0"
			(at 13.05 306.05 0)
			(layer "B.Fab")
			(hide yes)
			(effects
				(font
					(size 1 1)
					(thickness 0.15)
				)
				(justify mirror)
			)
		)
		(property "MPN" "GRM155R61H104KE14D"
			(at 13.05 306.05 0)
			(layer "B.Fab")
			(hide yes)
			(effects
				(font
					(size 1 1)
					(thickness 0.15)
				)
				(justify mirror)
			)
		)
		(property "Manufacturer" "Murata"
			(at 13.05 306.05 0)
			(layer "B.Fab")
			(hide yes)
			(effects
				(font
					(size 1 1)
					(thickness 0.15)
				)
				(justify mirror)
			)
		)
		(property "Val" "100n"
			(at 13.05 306.05 0)
			(layer "B.Fab")
			(hide yes)
			(effects
				(font
					(size 1 1)
					(thickness 0.15)
				)
				(justify mirror)
			)
		)
		(property "Voltage" "50V"
			(at 13.05 306.05 0)
			(layer "B.Fab")
			(hide yes)
			(effects
				(font
					(size 1 1)
					(thickness 0.15)
				)
				(justify mirror)
			)
		)
		(sheetname "DRAM + SRAM")
		(sheetfile "ram.kicad_sch")
		(attr smd)
		(fp_rect
			(start -0.925 0.47)
			(end 0.925 -0.47)
			(stroke
				(width 0.05)
				(type default)
			)
			(fill no)
			(layer "B.CrtYd")
		)
		(fp_line
			(start -0.494 0.25)
			(end 0.504 0.25)
			(stroke
				(width 0.15)
				(type solid)
			)
			(layer "B.Fab")
		)
		(fp_line
			(start 0.504 0.25)
			(end 0.504 -0.248)
			(stroke
				(width 0.15)
				(type solid)
			)
			(layer "B.Fab")
		)
		(fp_line
			(start -0.494 -0.248)
			(end -0.494 0.25)
			(stroke
				(width 0.15)
				(type solid)
			)
			(layer "B.Fab")
		)
		(fp_line
			(start 0.504 -0.248)
			(end -0.494 -0.248)
			(stroke
				(width 0.15)
				(type solid)
			)
			(layer "B.Fab")
		)
		(pad "1" smd roundrect
			(at -0.48 0 270)
			(size 0.59 0.64)
			(layers "B.Cu" "B.Mask" "B.Paste")
			(roundrect_rratio 0.25)
			(net 7 "+0V675_VTT")
			(pintype "passive")
		)
		(pad "2" smd roundrect
			(at 0.48 0 270)
			(size 0.59 0.64)
			(layers "B.Cu" "B.Mask" "B.Paste")
			(roundrect_rratio 0.25)
			(net 25 "+1V35")
			(pintype "passive")
		)
	)
	(footprint "antmicro-footprints:R_0402_1005Metric"
		(layer "B.Cu")
		(at 258.4 88.6 -90)
		(descr "Resistor SMD 0402")
		(tags "resistor SMD 0402")
		(property "Reference" "R355"
			(at -1.35 -1.25 90)
			(layer "B.SilkS")
			(effects
				(font
					(size 0.7 0.7)
					(thickness 0.15)
				)
				(justify left bottom mirror)
			)
		)
		(property "Value" "R_100k_0402"
			(at 0 -1.4 90)
			(layer "B.Fab")
			(effects
				(font
					(size 0.7 0.7)
					(thickness 0.15)
				)
				(justify left bottom mirror)
			)
		)
		(property "Description" "SMD Chip Resistor, 100 kohm, ± 1%, 62.5 mW, 0402 [1005 Metric], Thick Film, General Purpose"
			(at 0 0 270)
			(layer "F.Fab")
			(hide yes)
			(effects
				(font
					(size 1.27 1.27)
					(thickness 0.15)
				)
			)
		)
		(property "Author" "Antmicro"
			(at 169.8 347 0)
			(layer "B.Fab")
			(hide yes)
			(effects
				(font
					(size 1 1)
					(thickness 0.15)
				)
				(justify mirror)
			)
		)
		(property "License" "Apache-2.0"
			(at 169.8 347 0)
			(layer "B.Fab")
			(hide yes)
			(effects
				(font
					(size 1 1)
					(thickness 0.15)
				)
				(justify mirror)
			)
		)
		(property "MPN" "CR0402-FX-1003GLF"
			(at 169.8 347 0)
			(layer "B.Fab")
			(hide yes)
			(effects
				(font
					(size 1 1)
					(thickness 0.15)
				)
				(justify mirror)
			)
		)
		(property "Manufacturer" "Bourns"
			(at 169.8 347 0)
			(layer "B.Fab")
			(hide yes)
			(effects
				(font
					(size 1 1)
					(thickness 0.15)
				)
				(justify mirror)
			)
		)
		(property "Tolerance" "1%"
			(at 169.8 347 0)
			(layer "B.Fab")
			(hide yes)
			(effects
				(font
					(size 1 1)
					(thickness 0.15)
				)
				(justify mirror)
			)
		)
		(property "Val" "100k"
			(at 169.8 347 0)
			(layer "B.Fab")
			(hide yes)
			(effects
				(font
					(size 1 1)
					(thickness 0.15)
				)
				(justify mirror)
			)
		)
		(sheetname "User GPIO + LED + button + DIP switch")
		(sheetfile "user-gpio.kicad_sch")
		(attr smd)
		(fp_rect
			(start -0.925 0.47)
			(end 0.925 -0.47)
			(stroke
				(width 0.05)
				(type default)
			)
			(fill no)
			(layer "B.CrtYd")
		)
		(fp_rect
			(start -0.5 0.25)
			(end 0.5 -0.25)
			(stroke
				(width 0.15)
				(type solid)
			)
			(fill no)
			(layer "B.Fab")
		)
		(pad "1" smd roundrect
			(at -0.48 0 270)
			(size 0.59 0.64)
			(layers "B.Cu" "B.Mask" "B.Paste")
			(roundrect_rratio 0.25)
			(net 1301 "/USER_IO.LED_GREEN2")
			(pintype "passive")
		)
		(pad "2" smd roundrect
			(at 0.48 0 270)
			(size 0.59 0.64)
			(layers "B.Cu" "B.Mask" "B.Paste")
			(roundrect_rratio 0.25)
			(net 1 "GND")
			(pintype "passive")
		)
	)
	(footprint "antmicro-footprints:R_0603_1608Metric"
		(layer "B.Cu")
		(at 248.601 176.7 90)
		(descr "Resistor SMD 0603")
		(tags "resistor SMD 0603")
		(property "Reference" "R52"
			(at 1.075 -0.626 270)
			(layer "B.SilkS")
			(effects
				(font
					(size 0.7 0.7)
					(thickness 0.15)
				)
				(justify left bottom mirror)
			)
		)
		(property "Value" "R_63R4_0603"
			(at 0 -1.6 270)
			(layer "B.Fab")
			(effects
				(font
					(size 0.7 0.7)
					(thickness 0.15)
				)
				(justify left bottom mirror)
			)
		)
		(property "Description" "SMD Chip Resistor"
			(at 0 0 90)
			(layer "F.Fab")
			(hide yes)
			(effects
				(font
					(size 1.27 1.27)
					(thickness 0.15)
				)
			)
		)
		(property "Author" "Antmicro"
			(at 425.301 -71.901 0)
			(layer "B.Fab")
			(hide yes)
			(effects
				(font
					(size 1 1)
					(thickness 0.15)
				)
				(justify mirror)
			)
		)
		(property "License" "Apache-2.0"
			(at 425.301 -71.901 0)
			(layer "B.Fab")
			(hide yes)
			(effects
				(font
					(size 1 1)
					(thickness 0.15)
				)
				(justify mirror)
			)
		)
		(property "MPN" "CR0603-FX-63R4ELF"
			(at 425.301 -71.901 0)
			(layer "B.Fab")
			(hide yes)
			(effects
				(font
					(size 1 1)
					(thickness 0.15)
				)
				(justify mirror)
			)
		)
		(property "Manufacturer" "Bourns"
			(at 425.301 -71.901 0)
			(layer "B.Fab")
			(hide yes)
			(effects
				(font
					(size 1 1)
					(thickness 0.15)
				)
				(justify mirror)
			)
		)
		(property "Tolerance" "1%"
			(at 425.301 -71.901 0)
			(layer "B.Fab")
			(hide yes)
			(effects
				(font
					(size 1 1)
					(thickness 0.15)
				)
				(justify mirror)
			)
		)
		(property "Val" "63R4"
			(at 425.301 -71.901 0)
			(layer "B.Fab")
			(hide yes)
			(effects
				(font
					(size 1 1)
					(thickness 0.15)
				)
				(justify mirror)
			)
		)
		(sheetname "Power supply")
		(sheetfile "power-supply.kicad_sch")
		(attr smd)
		(fp_line
			(start -0.15 -0.4)
			(end 0.15 -0.4)
			(stroke
				(width 0.15)
				(type solid)
			)
			(layer "B.SilkS")
		)
		(fp_line
			(start -0.15 0.4)
			(end 0.15 0.4)
			(stroke
				(width 0.15)
				(type solid)
			)
			(layer "B.SilkS")
		)
		(fp_rect
			(start -1.25 0.65)
			(end 1.25 -0.65)
			(stroke
				(width 0.05)
				(type solid)
			)
			(fill no)
			(layer "B.CrtYd")
		)
		(fp_rect
			(start -0.8 0.4)
			(end 0.8 -0.4)
			(stroke
				(width 0.15)
				(type solid)
			)
			(fill no)
			(layer "B.Fab")
		)
		(pad "1" smd roundrect
			(at -0.7 0 90)
			(size 0.8 1)
			(layers "B.Cu" "B.Mask" "B.Paste")
			(roundrect_rratio 0.2)
			(net 697 "/Power supply/VSS")
			(pintype "passive")
		)
		(pad "2" smd roundrect
			(at 0.7 0 90)
			(size 0.8 1)
			(layers "B.Cu" "B.Mask" "B.Paste")
			(roundrect_rratio 0.2)
			(net 885 "/Power supply/CLSA")
			(pintype "passive")
		)
	)
	(footprint "antmicro-footprints:C_0603_1608Metric"
		(layer "B.Cu")
		(at 201.5 147 90)
		(descr "Capacitor SMD 0603")
		(tags "capacitor 0603")
		(property "Reference" "C381"
			(at -1.5 1.375 90)
			(layer "B.SilkS")
			(effects
				(font
					(size 0.7 0.7)
					(thickness 0.15)
				)
				(justify right bottom mirror)
			)
		)
		(property "Value" "C_47u_0603"
			(at 0 -1.6 90)
			(layer "B.Fab")
			(effects
				(font
					(size 0.7 0.7)
					(thickness 0.15)
				)
				(justify right bottom mirror)
			)
		)
		(property "Description" "SMD Multilayer Ceramic Capacitor, 47 µF, 6.3 V, 0603 [1608 Metric], ± 20%, X5R, GRM Series"
			(at 0 0 90)
			(layer "F.Fab")
			(hide yes)
			(effects
				(font
					(size 1.27 1.27)
					(thickness 0.15)
				)
			)
		)
		(property "Author" "Antmicro"
			(at 348.5 -54.5 0)
			(layer "B.Fab")
			(hide yes)
			(effects
				(font
					(size 1 1)
					(thickness 0.15)
				)
				(justify mirror)
			)
		)
		(property "Dielectric" ""
			(at 348.5 -54.5 0)
			(layer "B.Fab")
			(hide yes)
			(effects
				(font
					(size 1 1)
					(thickness 0.15)
				)
				(justify mirror)
			)
		)
		(property "License" "Apache-2.0"
			(at 348.5 -54.5 0)
			(layer "B.Fab")
			(hide yes)
			(effects
				(font
					(size 1 1)
					(thickness 0.15)
				)
				(justify mirror)
			)
		)
		(property "MPN" "GRM188R60J476ME15D"
			(at 348.5 -54.5 0)
			(layer "B.Fab")
			(hide yes)
			(effects
				(font
					(size 1 1)
					(thickness 0.15)
				)
				(justify mirror)
			)
		)
		(property "Manufacturer" "Murata"
			(at 348.5 -54.5 0)
			(layer "B.Fab")
			(hide yes)
			(effects
				(font
					(size 1 1)
					(thickness 0.15)
				)
				(justify mirror)
			)
		)
		(property "Val" "47u"
			(at 348.5 -54.5 0)
			(layer "B.Fab")
			(hide yes)
			(effects
				(font
					(size 1 1)
					(thickness 0.15)
				)
				(justify mirror)
			)
		)
		(property "Voltage" ""
			(at 348.5 -54.5 0)
			(layer "B.Fab")
			(hide yes)
			(effects
				(font
					(size 1 1)
					(thickness 0.15)
				)
				(justify mirror)
			)
		)
		(sheetname "FPGA supply")
		(sheetfile "fpga-supply.kicad_sch")
		(attr smd)
		(fp_line
			(start -0.15 -0.4)
			(end 0.15 -0.4)
			(stroke
				(width 0.15)
				(type solid)
			)
			(layer "B.SilkS")
		)
		(fp_line
			(start -0.15 0.4)
			(end 0.15 0.4)
			(stroke
				(width 0.15)
				(type solid)
			)
			(layer "B.SilkS")
		)
		(fp_rect
			(start -1.25 0.65)
			(end 1.25 -0.65)
			(stroke
				(width 0.05)
				(type solid)
			)
			(fill no)
			(layer "B.CrtYd")
		)
		(fp_rect
			(start -0.8 0.4)
			(end 0.8 -0.4)
			(stroke
				(width 0.15)
				(type solid)
			)
			(fill no)
			(layer "B.Fab")
		)
		(pad "1" smd roundrect
			(at -0.7 0 90)
			(size 0.8 1)
			(layers "B.Cu" "B.Mask" "B.Paste")
			(roundrect_rratio 0.2)
			(net 1 "GND")
			(pintype "passive")
		)
		(pad "2" smd roundrect
			(at 0.7 0 90)
			(size 0.8 1)
			(layers "B.Cu" "B.Mask" "B.Paste")
			(roundrect_rratio 0.2)
			(net 650 "+1V0")
			(pintype "passive")
		)
	)
	(footprint "antmicro-footprints:R_0402_1005Metric"
		(layer "B.Cu")
		(at 153.2125 169.2 90)
		(descr "Resistor SMD 0402")
		(tags "resistor SMD 0402")
		(property "Reference" "R304"
			(at -0.725 0.3875 270)
			(layer "B.SilkS")
			(effects
				(font
					(size 0.7 0.7)
					(thickness 0.15)
				)
				(justify left bottom mirror)
			)
		)
		(property "Value" "R_0R_0402"
			(at 0 -1.4 270)
			(layer "B.Fab")
			(effects
				(font
					(size 0.7 0.7)
					(thickness 0.15)
				)
				(justify left bottom mirror)
			)
		)
		(property "Description" "SMD Chip Resistor, Jumper, 0 ohm, 100 mW, 0402 [1005 Metric], Thick Film, General Purpose"
			(at 0 0 90)
			(layer "F.Fab")
			(hide yes)
			(effects
				(font
					(size 1.27 1.27)
					(thickness 0.15)
				)
			)
		)
		(property "Author" "Antmicro"
			(at 322.4125 15.9875 0)
			(layer "B.Fab")
			(hide yes)
			(effects
				(font
					(size 1 1)
					(thickness 0.15)
				)
				(justify mirror)
			)
		)
		(property "Current" "1A"
			(at 322.4125 15.9875 0)
			(layer "B.Fab")
			(hide yes)
			(effects
				(font
					(size 1 1)
					(thickness 0.15)
				)
				(justify mirror)
			)
		)
		(property "DNP" "DNP"
			(at 322.4125 15.9875 0)
			(layer "B.Fab")
			(hide yes)
			(effects
				(font
					(size 1 1)
					(thickness 0.15)
				)
				(justify mirror)
			)
		)
		(property "License" "Apache-2.0"
			(at 322.4125 15.9875 0)
			(layer "B.Fab")
			(hide yes)
			(effects
				(font
					(size 1 1)
					(thickness 0.15)
				)
				(justify mirror)
			)
		)
		(property "MPN" "ERJ2GE0R00X"
			(at 322.4125 15.9875 0)
			(layer "B.Fab")
			(hide yes)
			(effects
				(font
					(size 1 1)
					(thickness 0.15)
				)
				(justify mirror)
			)
		)
		(property "Manufacturer" "Panasonic"
			(at 322.4125 15.9875 0)
			(layer "B.Fab")
			(hide yes)
			(effects
				(font
					(size 1 1)
					(thickness 0.15)
				)
				(justify mirror)
			)
		)
		(property "Tolerance" ""
			(at 322.4125 15.9875 0)
			(layer "B.Fab")
			(hide yes)
			(effects
				(font
					(size 1 1)
					(thickness 0.15)
				)
				(justify mirror)
			)
		)
		(property "Val" "0R"
			(at 322.4125 15.9875 0)
			(layer "B.Fab")
			(hide yes)
			(effects
				(font
					(size 1 1)
					(thickness 0.15)
				)
				(justify mirror)
			)
		)
		(property "dnp" ""
			(at 322.4125 15.9875 0)
			(layer "B.Fab")
			(hide yes)
			(effects
				(font
					(size 1 1)
					(thickness 0.15)
				)
				(justify mirror)
			)
		)
		(property "exclude_from_bom" ""
			(at 322.4125 15.9875 0)
			(layer "B.Fab")
			(hide yes)
			(effects
				(font
					(size 1 1)
					(thickness 0.15)
				)
				(justify mirror)
			)
		)
		(sheetname "DC-DC Converters")
		(sheetfile "dc-dc.kicad_sch")
		(attr smd exclude_from_bom)
		(fp_rect
			(start -0.925 0.47)
			(end 0.925 -0.47)
			(stroke
				(width 0.05)
				(type default)
			)
			(fill no)
			(layer "B.CrtYd")
		)
		(fp_rect
			(start -0.5 0.25)
			(end 0.5 -0.25)
			(stroke
				(width 0.15)
				(type solid)
			)
			(fill no)
			(layer "B.Fab")
		)
		(pad "1" smd roundrect
			(at -0.48 0 90)
			(size 0.59 0.64)
			(layers "B.Cu" "B.Mask" "B.Paste")
			(roundrect_rratio 0.25)
			(net 959 "/DC-DC Converters/FB1")
			(pintype "passive")
		)
		(pad "2" smd roundrect
			(at 0.48 0 90)
			(size 0.59 0.64)
			(layers "B.Cu" "B.Mask" "B.Paste")
			(roundrect_rratio 0.25)
			(net 1221 "/DC-DC Converters/SENSE_1V0_P")
			(pintype "passive")
		)
	)
	(footprint "antmicro-footprints:C_0402_1005Metric"
		(layer "B.Cu")
		(at 219.875 130.65 180)
		(descr "Capacitor SMD 0402")
		(tags "capacitor SMD 0402")
		(property "Reference" "C178"
			(at -1.475 0.45 0)
			(layer "B.SilkS")
			(effects
				(font
					(size 0.7 0.7)
					(thickness 0.15)
				)
				(justify left bottom mirror)
			)
		)
		(property "Value" "C_100n_0402"
			(at 0 -1.169 0)
			(layer "B.Fab")
			(effects
				(font
					(size 0.7 0.7)
					(thickness 0.15)
				)
				(justify left bottom mirror)
			)
		)
		(property "Description" "SMD Multilayer Ceramic Capacitor, 0.1 µF, 50 V, 0402 [1005 Metric], ± 10%, X5R, GRM Series"
			(at 0 0 180)
			(layer "F.Fab")
			(hide yes)
			(effects
				(font
					(size 1.27 1.27)
					(thickness 0.15)
				)
			)
		)
		(property "Author" "Antmicro"
			(at 439.75 261.3 0)
			(layer "B.Fab")
			(hide yes)
			(effects
				(font
					(size 1 1)
					(thickness 0.15)
				)
				(justify mirror)
			)
		)
		(property "Dielectric" "X5R"
			(at 439.75 261.3 0)
			(layer "B.Fab")
			(hide yes)
			(effects
				(font
					(size 1 1)
					(thickness 0.15)
				)
				(justify mirror)
			)
		)
		(property "License" "Apache-2.0"
			(at 439.75 261.3 0)
			(layer "B.Fab")
			(hide yes)
			(effects
				(font
					(size 1 1)
					(thickness 0.15)
				)
				(justify mirror)
			)
		)
		(property "MPN" "GRM155R61H104KE14D"
			(at 439.75 261.3 0)
			(layer "B.Fab")
			(hide yes)
			(effects
				(font
					(size 1 1)
					(thickness 0.15)
				)
				(justify mirror)
			)
		)
		(property "Manufacturer" "Murata"
			(at 439.75 261.3 0)
			(layer "B.Fab")
			(hide yes)
			(effects
				(font
					(size 1 1)
					(thickness 0.15)
				)
				(justify mirror)
			)
		)
		(property "Val" "100n"
			(at 439.75 261.3 0)
			(layer "B.Fab")
			(hide yes)
			(effects
				(font
					(size 1 1)
					(thickness 0.15)
				)
				(justify mirror)
			)
		)
		(property "Voltage" "50V"
			(at 439.75 261.3 0)
			(layer "B.Fab")
			(hide yes)
			(effects
				(font
					(size 1 1)
					(thickness 0.15)
				)
				(justify mirror)
			)
		)
		(sheetname "DRAM + SRAM")
		(sheetfile "ram.kicad_sch")
		(attr smd)
		(fp_rect
			(start -0.925 0.47)
			(end 0.925 -0.47)
			(stroke
				(width 0.05)
				(type default)
			)
			(fill no)
			(layer "B.CrtYd")
		)
		(fp_line
			(start 0.504 0.25)
			(end 0.504 -0.248)
			(stroke
				(width 0.15)
				(type solid)
			)
			(layer "B.Fab")
		)
		(fp_line
			(start 0.504 -0.248)
			(end -0.494 -0.248)
			(stroke
				(width 0.15)
				(type solid)
			)
			(layer "B.Fab")
		)
		(fp_line
			(start -0.494 0.25)
			(end 0.504 0.25)
			(stroke
				(width 0.15)
				(type solid)
			)
			(layer "B.Fab")
		)
		(fp_line
			(start -0.494 -0.248)
			(end -0.494 0.25)
			(stroke
				(width 0.15)
				(type solid)
			)
			(layer "B.Fab")
		)
		(pad "1" smd roundrect
			(at -0.48 0 180)
			(size 0.59 0.64)
			(layers "B.Cu" "B.Mask" "B.Paste")
			(roundrect_rratio 0.25)
			(net 1 "GND")
			(pintype "passive")
		)
		(pad "2" smd roundrect
			(at 0.48 0 180)
			(size 0.59 0.64)
			(layers "B.Cu" "B.Mask" "B.Paste")
			(roundrect_rratio 0.25)
			(net 24 "+3V3")
			(pintype "passive")
		)
	)
	(footprint "antmicro-footprints:R_0402_1005Metric"
		(layer "B.Cu")
		(at 189.36 84.8 90)
		(descr "Resistor SMD 0402")
		(tags "resistor SMD 0402")
		(property "Reference" "R136"
			(at -0.725 0.4 270)
			(layer "B.SilkS")
			(effects
				(font
					(size 0.7 0.7)
					(thickness 0.15)
				)
				(justify left bottom mirror)
			)
		)
		(property "Value" "R_100R_0402"
			(at 0 -1.4 270)
			(layer "B.Fab")
			(effects
				(font
					(size 0.7 0.7)
					(thickness 0.15)
				)
				(justify left bottom mirror)
			)
		)
		(property "Description" "SMD Chip Resistor, 100 ohm, ± 1%, 62.5 mW, 0402 [1005 Metric], Thick Film, General Purpose"
			(at 0 0 90)
			(layer "F.Fab")
			(hide yes)
			(effects
				(font
					(size 1.27 1.27)
					(thickness 0.15)
				)
			)
		)
		(property "Author" "Antmicro"
			(at 274.16 -104.56 0)
			(layer "B.Fab")
			(hide yes)
			(effects
				(font
					(size 1 1)
					(thickness 0.15)
				)
				(justify mirror)
			)
		)
		(property "License" "Apache-2.0"
			(at 274.16 -104.56 0)
			(layer "B.Fab")
			(hide yes)
			(effects
				(font
					(size 1 1)
					(thickness 0.15)
				)
				(justify mirror)
			)
		)
		(property "MPN" "CR0402-FX-1000GLF"
			(at 274.16 -104.56 0)
			(layer "B.Fab")
			(hide yes)
			(effects
				(font
					(size 1 1)
					(thickness 0.15)
				)
				(justify mirror)
			)
		)
		(property "Manufacturer" "Bourns"
			(at 274.16 -104.56 0)
			(layer "B.Fab")
			(hide yes)
			(effects
				(font
					(size 1 1)
					(thickness 0.15)
				)
				(justify mirror)
			)
		)
		(property "Tolerance" "1%"
			(at 274.16 -104.56 0)
			(layer "B.Fab")
			(hide yes)
			(effects
				(font
					(size 1 1)
					(thickness 0.15)
				)
				(justify mirror)
			)
		)
		(property "Val" "100R"
			(at 274.16 -104.56 0)
			(layer "B.Fab")
			(hide yes)
			(effects
				(font
					(size 1 1)
					(thickness 0.15)
				)
				(justify mirror)
			)
		)
		(sheetname "User GPIO + LED + button + DIP switch")
		(sheetfile "user-gpio.kicad_sch")
		(attr smd)
		(fp_rect
			(start -0.925 0.47)
			(end 0.925 -0.47)
			(stroke
				(width 0.05)
				(type default)
			)
			(fill no)
			(layer "B.CrtYd")
		)
		(fp_rect
			(start -0.5 0.25)
			(end 0.5 -0.25)
			(stroke
				(width 0.15)
				(type solid)
			)
			(fill no)
			(layer "B.Fab")
		)
		(pad "1" smd roundrect
			(at -0.48 0 90)
			(size 0.59 0.64)
			(layers "B.Cu" "B.Mask" "B.Paste")
			(roundrect_rratio 0.25)
			(net 826 "/User GPIO + LED + button + DIP switch/CW_20PIN_MOSI")
			(pintype "passive")
		)
		(pad "2" smd roundrect
			(at 0.48 0 90)
			(size 0.59 0.64)
			(layers "B.Cu" "B.Mask" "B.Paste")
			(roundrect_rratio 0.25)
			(net 476 "/FPGA Bank 12 & 13/CW_HEADER.MOSI")
			(pintype "passive")
		)
	)
	(footprint "antmicro-footprints:C_0402_1005Metric"
		(layer "B.Cu")
		(at 194.775 128.775 180)
		(descr "Capacitor SMD 0402")
		(tags "capacitor SMD 0402")
		(property "Reference" "C136"
			(at -24.475 28.75 0)
			(layer "B.SilkS")
			(effects
				(font
					(size 0.7 0.7)
					(thickness 0.15)
				)
				(justify left bottom mirror)
			)
		)
		(property "Value" "C_100n_0402"
			(at 0 -1.169 0)
			(layer "B.Fab")
			(effects
				(font
					(size 0.7 0.7)
					(thickness 0.15)
				)
				(justify left bottom mirror)
			)
		)
		(property "Description" "SMD Multilayer Ceramic Capacitor, 0.1 µF, 50 V, 0402 [1005 Metric], ± 10%, X5R, GRM Series"
			(at 0 0 180)
			(layer "F.Fab")
			(hide yes)
			(effects
				(font
					(size 1.27 1.27)
					(thickness 0.15)
				)
			)
		)
		(property "Author" "Antmicro"
			(at 389.55 257.55 0)
			(layer "B.Fab")
			(hide yes)
			(effects
				(font
					(size 1 1)
					(thickness 0.15)
				)
				(justify mirror)
			)
		)
		(property "Dielectric" "X5R"
			(at 389.55 257.55 0)
			(layer "B.Fab")
			(hide yes)
			(effects
				(font
					(size 1 1)
					(thickness 0.15)
				)
				(justify mirror)
			)
		)
		(property "License" "Apache-2.0"
			(at 389.55 257.55 0)
			(layer "B.Fab")
			(hide yes)
			(effects
				(font
					(size 1 1)
					(thickness 0.15)
				)
				(justify mirror)
			)
		)
		(property "MPN" "GRM155R61H104KE14D"
			(at 389.55 257.55 0)
			(layer "B.Fab")
			(hide yes)
			(effects
				(font
					(size 1 1)
					(thickness 0.15)
				)
				(justify mirror)
			)
		)
		(property "Manufacturer" "Murata"
			(at 389.55 257.55 0)
			(layer "B.Fab")
			(hide yes)
			(effects
				(font
					(size 1 1)
					(thickness 0.15)
				)
				(justify mirror)
			)
		)
		(property "Val" "100n"
			(at 389.55 257.55 0)
			(layer "B.Fab")
			(hide yes)
			(effects
				(font
					(size 1 1)
					(thickness 0.15)
				)
				(justify mirror)
			)
		)
		(property "Voltage" "50V"
			(at 389.55 257.55 0)
			(layer "B.Fab")
			(hide yes)
			(effects
				(font
					(size 1 1)
					(thickness 0.15)
				)
				(justify mirror)
			)
		)
		(sheetname "FPGA supply")
		(sheetfile "fpga-supply.kicad_sch")
		(attr smd)
		(fp_rect
			(start -0.925 0.47)
			(end 0.925 -0.47)
			(stroke
				(width 0.05)
				(type default)
			)
			(fill no)
			(layer "B.CrtYd")
		)
		(fp_line
			(start 0.504 0.25)
			(end 0.504 -0.248)
			(stroke
				(width 0.15)
				(type solid)
			)
			(layer "B.Fab")
		)
		(fp_line
			(start 0.504 -0.248)
			(end -0.494 -0.248)
			(stroke
				(width 0.15)
				(type solid)
			)
			(layer "B.Fab")
		)
		(fp_line
			(start -0.494 0.25)
			(end 0.504 0.25)
			(stroke
				(width 0.15)
				(type solid)
			)
			(layer "B.Fab")
		)
		(fp_line
			(start -0.494 -0.248)
			(end -0.494 0.25)
			(stroke
				(width 0.15)
				(type solid)
			)
			(layer "B.Fab")
		)
		(pad "1" smd roundrect
			(at -0.48 0 180)
			(size 0.59 0.64)
			(layers "B.Cu" "B.Mask" "B.Paste")
			(roundrect_rratio 0.25)
			(net 1 "GND")
			(pintype "passive")
		)
		(pad "2" smd roundrect
			(at 0.48 0 180)
			(size 0.59 0.64)
			(layers "B.Cu" "B.Mask" "B.Paste")
			(roundrect_rratio 0.25)
			(net 650 "+1V0")
			(pintype "passive")
		)
	)
	(footprint "antmicro-footprints:R_0402_1005Metric"
		(layer "B.Cu")
		(at 244.701 166 180)
		(descr "Resistor SMD 0402")
		(tags "resistor SMD 0402")
		(property "Reference" "R243"
			(at -1.349 -2.25 180)
			(layer "B.SilkS")
			(effects
				(font
					(size 0.7 0.7)
					(thickness 0.15)
				)
				(justify left bottom mirror)
			)
		)
		(property "Value" "R_0R_0402"
			(at 0 -1.4 0)
			(layer "B.Fab")
			(effects
				(font
					(size 0.7 0.7)
					(thickness 0.15)
				)
				(justify left bottom mirror)
			)
		)
		(property "Description" "SMD Chip Resistor, Jumper, 0 ohm, 100 mW, 0402 [1005 Metric], Thick Film, General Purpose"
			(at 0 0 180)
			(layer "F.Fab")
			(hide yes)
			(effects
				(font
					(size 1.27 1.27)
					(thickness 0.15)
				)
			)
		)
		(property "Author" "Antmicro"
			(at 489.402 332 0)
			(layer "B.Fab")
			(hide yes)
			(effects
				(font
					(size 1 1)
					(thickness 0.15)
				)
				(justify mirror)
			)
		)
		(property "Current" "1A"
			(at 489.402 332 0)
			(layer "B.Fab")
			(hide yes)
			(effects
				(font
					(size 1 1)
					(thickness 0.15)
				)
				(justify mirror)
			)
		)
		(property "License" "Apache-2.0"
			(at 489.402 332 0)
			(layer "B.Fab")
			(hide yes)
			(effects
				(font
					(size 1 1)
					(thickness 0.15)
				)
				(justify mirror)
			)
		)
		(property "MPN" "ERJ2GE0R00X"
			(at 489.402 332 0)
			(layer "B.Fab")
			(hide yes)
			(effects
				(font
					(size 1 1)
					(thickness 0.15)
				)
				(justify mirror)
			)
		)
		(property "Manufacturer" "Panasonic"
			(at 489.402 332 0)
			(layer "B.Fab")
			(hide yes)
			(effects
				(font
					(size 1 1)
					(thickness 0.15)
				)
				(justify mirror)
			)
		)
		(property "Tolerance" ""
			(at 489.402 332 0)
			(layer "B.Fab")
			(hide yes)
			(effects
				(font
					(size 1 1)
					(thickness 0.15)
				)
				(justify mirror)
			)
		)
		(property "Val" "0R"
			(at 489.402 332 0)
			(layer "B.Fab")
			(hide yes)
			(effects
				(font
					(size 1 1)
					(thickness 0.15)
				)
				(justify mirror)
			)
		)
		(sheetname "HDMI + Ethernet")
		(sheetfile "hdmi-ethernet.kicad_sch")
		(attr smd)
		(fp_rect
			(start -0.925 0.47)
			(end 0.925 -0.47)
			(stroke
				(width 0.05)
				(type default)
			)
			(fill no)
			(layer "B.CrtYd")
		)
		(fp_rect
			(start -0.5 0.25)
			(end 0.5 -0.25)
			(stroke
				(width 0.15)
				(type solid)
			)
			(fill no)
			(layer "B.Fab")
		)
		(pad "1" smd roundrect
			(at -0.48 0 180)
			(size 0.59 0.64)
			(layers "B.Cu" "B.Mask" "B.Paste")
			(roundrect_rratio 0.25)
			(net 12 "Net-(J15A-TRDCT1{slash}2{slash}3{slash}4_1)")
			(pintype "passive")
		)
		(pad "2" smd roundrect
			(at 0.48 0 180)
			(size 0.59 0.64)
			(layers "B.Cu" "B.Mask" "B.Paste")
			(roundrect_rratio 0.25)
			(net 721 "/HDMI + Ethernet/ETH_3V3")
			(pintype "passive")
		)
	)
	(footprint "antmicro-footprints:C_0402_1005Metric"
		(layer "B.Cu")
		(at 159.55 144.5 -90)
		(descr "Capacitor SMD 0402")
		(tags "capacitor SMD 0402")
		(property "Reference" "C171"
			(at -1.9 3.475 90)
			(layer "B.SilkS")
			(effects
				(font
					(size 0.7 0.7)
					(thickness 0.15)
				)
				(justify left bottom mirror)
			)
		)
		(property "Value" "C_100n_0402"
			(at 0 -1.169 90)
			(layer "B.Fab")
			(effects
				(font
					(size 0.7 0.7)
					(thickness 0.15)
				)
				(justify left bottom mirror)
			)
		)
		(property "Description" "SMD Multilayer Ceramic Capacitor, 0.1 µF, 50 V, 0402 [1005 Metric], ± 10%, X5R, GRM Series"
			(at 0 0 270)
			(layer "F.Fab")
			(hide yes)
			(effects
				(font
					(size 1.27 1.27)
					(thickness 0.15)
				)
			)
		)
		(property "Author" "Antmicro"
			(at 15.05 304.05 0)
			(layer "B.Fab")
			(hide yes)
			(effects
				(font
					(size 1 1)
					(thickness 0.15)
				)
				(justify mirror)
			)
		)
		(property "Dielectric" "X5R"
			(at 15.05 304.05 0)
			(layer "B.Fab")
			(hide yes)
			(effects
				(font
					(size 1 1)
					(thickness 0.15)
				)
				(justify mirror)
			)
		)
		(property "License" "Apache-2.0"
			(at 15.05 304.05 0)
			(layer "B.Fab")
			(hide yes)
			(effects
				(font
					(size 1 1)
					(thickness 0.15)
				)
				(justify mirror)
			)
		)
		(property "MPN" "GRM155R61H104KE14D"
			(at 15.05 304.05 0)
			(layer "B.Fab")
			(hide yes)
			(effects
				(font
					(size 1 1)
					(thickness 0.15)
				)
				(justify mirror)
			)
		)
		(property "Manufacturer" "Murata"
			(at 15.05 304.05 0)
			(layer "B.Fab")
			(hide yes)
			(effects
				(font
					(size 1 1)
					(thickness 0.15)
				)
				(justify mirror)
			)
		)
		(property "Val" "100n"
			(at 15.05 304.05 0)
			(layer "B.Fab")
			(hide yes)
			(effects
				(font
					(size 1 1)
					(thickness 0.15)
				)
				(justify mirror)
			)
		)
		(property "Voltage" "50V"
			(at 15.05 304.05 0)
			(layer "B.Fab")
			(hide yes)
			(effects
				(font
					(size 1 1)
					(thickness 0.15)
				)
				(justify mirror)
			)
		)
		(sheetname "DRAM + SRAM")
		(sheetfile "ram.kicad_sch")
		(attr smd)
		(fp_rect
			(start -0.925 0.47)
			(end 0.925 -0.47)
			(stroke
				(width 0.05)
				(type default)
			)
			(fill no)
			(layer "B.CrtYd")
		)
		(fp_line
			(start -0.494 0.25)
			(end 0.504 0.25)
			(stroke
				(width 0.15)
				(type solid)
			)
			(layer "B.Fab")
		)
		(fp_line
			(start 0.504 0.25)
			(end 0.504 -0.248)
			(stroke
				(width 0.15)
				(type solid)
			)
			(layer "B.Fab")
		)
		(fp_line
			(start -0.494 -0.248)
			(end -0.494 0.25)
			(stroke
				(width 0.15)
				(type solid)
			)
			(layer "B.Fab")
		)
		(fp_line
			(start 0.504 -0.248)
			(end -0.494 -0.248)
			(stroke
				(width 0.15)
				(type solid)
			)
			(layer "B.Fab")
		)
		(pad "1" smd roundrect
			(at -0.48 0 270)
			(size 0.59 0.64)
			(layers "B.Cu" "B.Mask" "B.Paste")
			(roundrect_rratio 0.25)
			(net 1 "GND")
			(pintype "passive")
		)
		(pad "2" smd roundrect
			(at 0.48 0 270)
			(size 0.59 0.64)
			(layers "B.Cu" "B.Mask" "B.Paste")
			(roundrect_rratio 0.25)
			(net 7 "+0V675_VTT")
			(pintype "passive")
		)
	)
	(footprint "antmicro-footprints:C_0402_1005Metric"
		(layer "B.Cu")
		(at 167.145001 82.635001 180)
		(descr "Capacitor SMD 0402")
		(tags "capacitor SMD 0402")
		(property "Reference" "C298"
			(at 0.820001 -0.389999 0)
			(layer "B.SilkS")
			(effects
				(font
					(size 0.7 0.7)
					(thickness 0.15)
				)
				(justify left bottom mirror)
			)
		)
		(property "Value" "C_100n_0402"
			(at 0 -1.4 0)
			(layer "B.Fab")
			(effects
				(font
					(size 0.7 0.7)
					(thickness 0.15)
				)
				(justify left bottom mirror)
			)
		)
		(property "Description" "SMD Multilayer Ceramic Capacitor, 0.1 µF, 50 V, 0402 [1005 Metric], ± 10%, X5R, GRM Series"
			(at 0 0 180)
			(layer "F.Fab")
			(hide yes)
			(effects
				(font
					(size 1.27 1.27)
					(thickness 0.15)
				)
			)
		)
		(property "Author" "Antmicro"
			(at 334.290002 165.270002 0)
			(layer "B.Fab")
			(hide yes)
			(effects
				(font
					(size 1 1)
					(thickness 0.15)
				)
				(justify mirror)
			)
		)
		(property "Dielectric" "X5R"
			(at 334.290002 165.270002 0)
			(layer "B.Fab")
			(hide yes)
			(effects
				(font
					(size 1 1)
					(thickness 0.15)
				)
				(justify mirror)
			)
		)
		(property "License" "Apache-2.0"
			(at 334.290002 165.270002 0)
			(layer "B.Fab")
			(hide yes)
			(effects
				(font
					(size 1 1)
					(thickness 0.15)
				)
				(justify mirror)
			)
		)
		(property "MPN" "GRM155R61H104KE14D"
			(at 334.290002 165.270002 0)
			(layer "B.Fab")
			(hide yes)
			(effects
				(font
					(size 1 1)
					(thickness 0.15)
				)
				(justify mirror)
			)
		)
		(property "Manufacturer" "Murata"
			(at 334.290002 165.270002 0)
			(layer "B.Fab")
			(hide yes)
			(effects
				(font
					(size 1 1)
					(thickness 0.15)
				)
				(justify mirror)
			)
		)
		(property "Val" "100n"
			(at 334.290002 165.270002 0)
			(layer "B.Fab")
			(hide yes)
			(effects
				(font
					(size 1 1)
					(thickness 0.15)
				)
				(justify mirror)
			)
		)
		(property "Voltage" "50V"
			(at 334.290002 165.270002 0)
			(layer "B.Fab")
			(hide yes)
			(effects
				(font
					(size 1 1)
					(thickness 0.15)
				)
				(justify mirror)
			)
		)
		(sheetname "FMC+ HSPC")
		(sheetfile "fmc-hspc.kicad_sch")
		(attr smd)
		(fp_rect
			(start -0.925 0.47)
			(end 0.925 -0.47)
			(stroke
				(width 0.05)
				(type default)
			)
			(fill no)
			(layer "B.CrtYd")
		)
		(fp_line
			(start 0.504 0.25)
			(end 0.504 -0.248)
			(stroke
				(width 0.15)
				(type solid)
			)
			(layer "B.Fab")
		)
		(fp_line
			(start 0.504 -0.248)
			(end -0.494 -0.248)
			(stroke
				(width 0.15)
				(type solid)
			)
			(layer "B.Fab")
		)
		(fp_line
			(start -0.494 0.25)
			(end 0.504 0.25)
			(stroke
				(width 0.15)
				(type solid)
			)
			(layer "B.Fab")
		)
		(fp_line
			(start -0.494 -0.248)
			(end -0.494 0.25)
			(stroke
				(width 0.15)
				(type solid)
			)
			(layer "B.Fab")
		)
		(pad "1" smd roundrect
			(at -0.48 0 180)
			(size 0.59 0.64)
			(layers "B.Cu" "B.Mask" "B.Paste")
			(roundrect_rratio 0.25)
			(net 61 "/FMC+ HSPC/GTX116.TX3_P")
			(pintype "passive")
		)
		(pad "2" smd roundrect
			(at 0.48 0 180)
			(size 0.59 0.64)
			(layers "B.Cu" "B.Mask" "B.Paste")
			(roundrect_rratio 0.25)
			(net 60 "/FMC+ HSPC/GTX_TX0_C_P")
			(pintype "passive")
		)
	)
	(footprint "antmicro-footprints:NetTie-2_SMD_Pad0.127mm"
		(layer "B.Cu")
		(at 249.301 148.4 90)
		(descr "Net tie, 2 pin, 0.127mm  SMD pads")
		(tags "net tie")
		(property "Reference" "NT6"
			(at -0.128 1.345 270)
			(layer "B.SilkS")
			(hide yes)
			(effects
				(font
					(size 0.7 0.7)
					(thickness 0.15)
				)
				(justify left bottom mirror)
			)
		)
		(property "Value" "Net-Tie_2"
			(at 0 -1.199 270)
			(layer "B.Fab")
			(effects
				(font
					(size 0.7 0.7)
					(thickness 0.15)
				)
				(justify left bottom mirror)
			)
		)
		(property "Description" "Net tie, 2 pins"
			(at 0 0 90)
			(layer "F.Fab")
			(hide yes)
			(effects
				(font
					(size 1.27 1.27)
					(thickness 0.15)
				)
			)
		)
		(property "Author" "Antmicro"
			(at 397.701 -100.901 0)
			(layer "B.Fab")
			(hide yes)
			(effects
				(font
					(size 1 1)
					(thickness 0.15)
				)
				(justify mirror)
			)
		)
		(property "License" "Apache-2.0"
			(at 397.701 -100.901 0)
			(layer "B.Fab")
			(hide yes)
			(effects
				(font
					(size 1 1)
					(thickness 0.15)
				)
				(justify mirror)
			)
		)
		(property "MPN" ""
			(at 397.701 -100.901 0)
			(layer "B.Fab")
			(hide yes)
			(effects
				(font
					(size 1 1)
					(thickness 0.15)
				)
				(justify mirror)
			)
		)
		(property "Manufacturer" ""
			(at 397.701 -100.901 0)
			(layer "B.Fab")
			(hide yes)
			(effects
				(font
					(size 1 1)
					(thickness 0.15)
				)
				(justify mirror)
			)
		)
		(sheetname "FPGA Config")
		(sheetfile "fpga-config.kicad_sch")
		(attr exclude_from_pos_files)
		(net_tie_pad_groups "1, 2")
		(fp_poly
			(pts
				(xy -0.0635 0.0635) (xy 0.0625 0.0635) (xy 0.0625 -0.0635) (xy -0.0635 -0.0635)
			)
			(stroke
				(width 0)
				(type solid)
			)
			(fill yes)
			(layer "B.Cu")
		)
		(pad "1" smd roundrect
			(at -0.127 0 270)
			(size 0.127 0.127)
			(layers "B.Cu")
			(roundrect_rratio 0.5)
			(chamfer_ratio 0)
			(chamfer top_left bottom_left)
			(net 1315 "/SUP_MCU.DONE")
			(pinfunction "1")
			(pintype "passive")
		)
		(pad "2" smd roundrect
			(at 0.126 0 90)
			(size 0.127 0.127)
			(layers "B.Cu")
			(roundrect_rratio 0.5)
			(chamfer_ratio 0)
			(chamfer top_left bottom_left)
			(net 246 "/FPGA Config/DONE")
			(pinfunction "2")
			(pintype "passive")
		)
	)
	(footprint "antmicro-footprints:R_0402_1005Metric"
		(layer "B.Cu")
		(at 195.691252 93.85 180)
		(descr "Resistor SMD 0402")
		(tags "resistor SMD 0402")
		(property "Reference" "R201"
			(at 0.716252 -0.425 0)
			(layer "B.SilkS")
			(effects
				(font
					(size 0.7 0.7)
					(thickness 0.15)
				)
				(justify left bottom mirror)
			)
		)
		(property "Value" "R_10k_0402"
			(at 0 -1.4 0)
			(layer "B.Fab")
			(effects
				(font
					(size 0.7 0.7)
					(thickness 0.15)
				)
				(justify left bottom mirror)
			)
		)
		(property "Description" "SMD Chip Resistor, 10 kohm, ± 1%, 62.5 mW, 0402 [1005 Metric], Thick Film, General Purpose"
			(at 0 0 180)
			(layer "F.Fab")
			(hide yes)
			(effects
				(font
					(size 1.27 1.27)
					(thickness 0.15)
				)
			)
		)
		(property "Author" "Antmicro"
			(at 391.382504 187.7 0)
			(layer "B.Fab")
			(hide yes)
			(effects
				(font
					(size 1 1)
					(thickness 0.15)
				)
				(justify mirror)
			)
		)
		(property "DNP" "DNP"
			(at 391.382504 187.7 0)
			(layer "B.Fab")
			(hide yes)
			(effects
				(font
					(size 1 1)
					(thickness 0.15)
				)
				(justify mirror)
			)
		)
		(property "License" "Apache-2.0"
			(at 391.382504 187.7 0)
			(layer "B.Fab")
			(hide yes)
			(effects
				(font
					(size 1 1)
					(thickness 0.15)
				)
				(justify mirror)
			)
		)
		(property "MPN" "CR0402-FX-1002GLF"
			(at 391.382504 187.7 0)
			(layer "B.Fab")
			(hide yes)
			(effects
				(font
					(size 1 1)
					(thickness 0.15)
				)
				(justify mirror)
			)
		)
		(property "Manufacturer" "Bourns"
			(at 391.382504 187.7 0)
			(layer "B.Fab")
			(hide yes)
			(effects
				(font
					(size 1 1)
					(thickness 0.15)
				)
				(justify mirror)
			)
		)
		(property "Tolerance" "1%"
			(at 391.382504 187.7 0)
			(layer "B.Fab")
			(hide yes)
			(effects
				(font
					(size 1 1)
					(thickness 0.15)
				)
				(justify mirror)
			)
		)
		(property "Val" "10k"
			(at 391.382504 187.7 0)
			(layer "B.Fab")
			(hide yes)
			(effects
				(font
					(size 1 1)
					(thickness 0.15)
				)
				(justify mirror)
			)
		)
		(property "dnp" ""
			(at 391.382504 187.7 0)
			(layer "B.Fab")
			(hide yes)
			(effects
				(font
					(size 1 1)
					(thickness 0.15)
				)
				(justify mirror)
			)
		)
		(property "exclude_from_bom" ""
			(at 391.382504 187.7 0)
			(layer "B.Fab")
			(hide yes)
			(effects
				(font
					(size 1 1)
					(thickness 0.15)
				)
				(justify mirror)
			)
		)
		(sheetname "HDMI + Ethernet")
		(sheetfile "hdmi-ethernet.kicad_sch")
		(attr smd exclude_from_bom)
		(fp_rect
			(start -0.925 0.47)
			(end 0.925 -0.47)
			(stroke
				(width 0.05)
				(type default)
			)
			(fill no)
			(layer "B.CrtYd")
		)
		(fp_rect
			(start -0.5 0.25)
			(end 0.5 -0.25)
			(stroke
				(width 0.15)
				(type solid)
			)
			(fill no)
			(layer "B.Fab")
		)
		(pad "1" smd roundrect
			(at -0.48 0 180)
			(size 0.59 0.64)
			(layers "B.Cu" "B.Mask" "B.Paste")
			(roundrect_rratio 0.25)
			(net 505 "/FPGA Bank 16 & 17/GBE_RGMII.RXD1")
			(pintype "passive")
		)
		(pad "2" smd roundrect
			(at 0.48 0 180)
			(size 0.59 0.64)
			(layers "B.Cu" "B.Mask" "B.Paste")
			(roundrect_rratio 0.25)
			(net 24 "+3V3")
			(pintype "passive")
		)
	)
	(footprint "antmicro-footprints:R_0402_1005Metric"
		(layer "B.Cu")
		(at 164.75 183.7 -90)
		(descr "Resistor SMD 0402")
		(tags "resistor SMD 0402")
		(property "Reference" "R284"
			(at -3.625 -0.325 90)
			(layer "B.SilkS")
			(effects
				(font
					(size 0.7 0.7)
					(thickness 0.15)
				)
				(justify left bottom mirror)
			)
		)
		(property "Value" "R_47k_0402"
			(at 0 -1.4 90)
			(layer "B.Fab")
			(effects
				(font
					(size 0.7 0.7)
					(thickness 0.15)
				)
				(justify left bottom mirror)
			)
		)
		(property "Description" "SMD Chip Resistor, 47 kohm, ± 1%, 62.5 mW, 0402 [1005 Metric], Thick Film, General Purpose"
			(at 0 0 270)
			(layer "F.Fab")
			(hide yes)
			(effects
				(font
					(size 1.27 1.27)
					(thickness 0.15)
				)
			)
		)
		(property "Author" "Antmicro"
			(at -18.95 348.45 0)
			(layer "B.Fab")
			(hide yes)
			(effects
				(font
					(size 1 1)
					(thickness 0.15)
				)
				(justify mirror)
			)
		)
		(property "License" "Apache-2.0"
			(at -18.95 348.45 0)
			(layer "B.Fab")
			(hide yes)
			(effects
				(font
					(size 1 1)
					(thickness 0.15)
				)
				(justify mirror)
			)
		)
		(property "MPN" "CR0402-FX-4702GLF"
			(at -18.95 348.45 0)
			(layer "B.Fab")
			(hide yes)
			(effects
				(font
					(size 1 1)
					(thickness 0.15)
				)
				(justify mirror)
			)
		)
		(property "Manufacturer" "Bourns"
			(at -18.95 348.45 0)
			(layer "B.Fab")
			(hide yes)
			(effects
				(font
					(size 1 1)
					(thickness 0.15)
				)
				(justify mirror)
			)
		)
		(property "Tolerance" "1%"
			(at -18.95 348.45 0)
			(layer "B.Fab")
			(hide yes)
			(effects
				(font
					(size 1 1)
					(thickness 0.15)
				)
				(justify mirror)
			)
		)
		(property "Val" "47k"
			(at -18.95 348.45 0)
			(layer "B.Fab")
			(hide yes)
			(effects
				(font
					(size 1 1)
					(thickness 0.15)
				)
				(justify mirror)
			)
		)
		(sheetname "DC-DC Converters")
		(sheetfile "dc-dc.kicad_sch")
		(attr smd)
		(fp_rect
			(start -0.925 0.47)
			(end 0.925 -0.47)
			(stroke
				(width 0.05)
				(type default)
			)
			(fill no)
			(layer "B.CrtYd")
		)
		(fp_rect
			(start -0.5 0.25)
			(end 0.5 -0.25)
			(stroke
				(width 0.15)
				(type solid)
			)
			(fill no)
			(layer "B.Fab")
		)
		(pad "1" smd roundrect
			(at -0.48 0 270)
			(size 0.59 0.64)
			(layers "B.Cu" "B.Mask" "B.Paste")
			(roundrect_rratio 0.25)
			(net 1 "GND")
			(pintype "passive")
		)
		(pad "2" smd roundrect
			(at 0.48 0 270)
			(size 0.59 0.64)
			(layers "B.Cu" "B.Mask" "B.Paste")
			(roundrect_rratio 0.25)
			(net 797 "/DC-DC Converters/PB_CTRL_OE")
			(pintype "passive")
		)
	)
	(footprint "antmicro-footprints:C_0402_1005Metric"
		(layer "B.Cu")
		(at 197 140.5)
		(descr "Capacitor SMD 0402")
		(tags "capacitor SMD 0402")
		(property "Reference" "C100"
			(at 1.4 1.2 180)
			(layer "B.SilkS")
			(effects
				(font
					(size 0.7 0.7)
					(thickness 0.15)
				)
				(justify left bottom mirror)
			)
		)
		(property "Value" "C_100n_0402"
			(at 0 -1.169 180)
			(layer "B.Fab")
			(effects
				(font
					(size 0.7 0.7)
					(thickness 0.15)
				)
				(justify left bottom mirror)
			)
		)
		(property "Description" "SMD Multilayer Ceramic Capacitor, 0.1 µF, 50 V, 0402 [1005 Metric], ± 10%, X5R, GRM Series"
			(at 0 0 0)
			(layer "F.Fab")
			(hide yes)
			(effects
				(font
					(size 1.27 1.27)
					(thickness 0.15)
				)
			)
		)
		(property "Author" "Antmicro"
			(at 0 0 0)
			(layer "B.Fab")
			(hide yes)
			(effects
				(font
					(size 1 1)
					(thickness 0.15)
				)
				(justify mirror)
			)
		)
		(property "Dielectric" "X5R"
			(at 0 0 0)
			(layer "B.Fab")
			(hide yes)
			(effects
				(font
					(size 1 1)
					(thickness 0.15)
				)
				(justify mirror)
			)
		)
		(property "License" "Apache-2.0"
			(at 0 0 0)
			(layer "B.Fab")
			(hide yes)
			(effects
				(font
					(size 1 1)
					(thickness 0.15)
				)
				(justify mirror)
			)
		)
		(property "MPN" "GRM155R61H104KE14D"
			(at 0 0 0)
			(layer "B.Fab")
			(hide yes)
			(effects
				(font
					(size 1 1)
					(thickness 0.15)
				)
				(justify mirror)
			)
		)
		(property "Manufacturer" "Murata"
			(at 0 0 0)
			(layer "B.Fab")
			(hide yes)
			(effects
				(font
					(size 1 1)
					(thickness 0.15)
				)
				(justify mirror)
			)
		)
		(property "Val" "100n"
			(at 0 0 0)
			(layer "B.Fab")
			(hide yes)
			(effects
				(font
					(size 1 1)
					(thickness 0.15)
				)
				(justify mirror)
			)
		)
		(property "Voltage" "50V"
			(at 0 0 0)
			(layer "B.Fab")
			(hide yes)
			(effects
				(font
					(size 1 1)
					(thickness 0.15)
				)
				(justify mirror)
			)
		)
		(sheetname "FPGA Bank 18 & 32")
		(sheetfile "fpga-bank-18-32.kicad_sch")
		(attr smd)
		(fp_rect
			(start -0.925 0.47)
			(end 0.925 -0.47)
			(stroke
				(width 0.05)
				(type default)
			)
			(fill no)
			(layer "B.CrtYd")
		)
		(fp_line
			(start -0.494 -0.248)
			(end -0.494 0.25)
			(stroke
				(width 0.15)
				(type solid)
			)
			(layer "B.Fab")
		)
		(fp_line
			(start -0.494 0.25)
			(end 0.504 0.25)
			(stroke
				(width 0.15)
				(type solid)
			)
			(layer "B.Fab")
		)
		(fp_line
			(start 0.504 -0.248)
			(end -0.494 -0.248)
			(stroke
				(width 0.15)
				(type solid)
			)
			(layer "B.Fab")
		)
		(fp_line
			(start 0.504 0.25)
			(end 0.504 -0.248)
			(stroke
				(width 0.15)
				(type solid)
			)
			(layer "B.Fab")
		)
		(pad "1" smd roundrect
			(at -0.48 0)
			(size 0.59 0.64)
			(layers "B.Cu" "B.Mask" "B.Paste")
			(roundrect_rratio 0.25)
			(net 1 "GND")
			(pintype "passive")
		)
		(pad "2" smd roundrect
			(at 0.48 0)
			(size 0.59 0.64)
			(layers "B.Cu" "B.Mask" "B.Paste")
			(roundrect_rratio 0.25)
			(net 26 "+1V8")
			(pintype "passive")
		)
	)
	(footprint "antmicro-footprints:QFN-2L_1.6x1x0.55mm"
		(layer "B.Cu")
		(at 264.75 79.4 90)
		(property "Reference" "D35"
			(at -1.9 -0.75 90)
			(layer "B.SilkS")
			(effects
				(font
					(size 0.7 0.7)
					(thickness 0.15)
				)
				(justify right bottom mirror)
			)
		)
		(property "Value" "ESDA25P35-1U1M"
			(at 0 -1.7 90)
			(layer "B.Fab")
			(effects
				(font
					(size 0.7 0.7)
					(thickness 0.15)
				)
				(justify right bottom mirror)
			)
		)
		(property "Description" "Unidirectional TVS, 30 kV, QFN-2L, 22 V, 195 pF"
			(at 0 0 90)
			(layer "F.Fab")
			(hide yes)
			(effects
				(font
					(size 1.27 1.27)
					(thickness 0.15)
				)
			)
		)
		(property "Author" "Antmicro"
			(at 344.15 -185.35 0)
			(layer "B.Fab")
			(hide yes)
			(effects
				(font
					(size 1 1)
					(thickness 0.15)
				)
				(justify mirror)
			)
		)
		(property "License" "Apache-2.0"
			(at 344.15 -185.35 0)
			(layer "B.Fab")
			(hide yes)
			(effects
				(font
					(size 1 1)
					(thickness 0.15)
				)
				(justify mirror)
			)
		)
		(property "MPN" "ESDA25P35-1U1M"
			(at 344.15 -185.35 0)
			(layer "B.Fab")
			(hide yes)
			(effects
				(font
					(size 1 1)
					(thickness 0.15)
				)
				(justify mirror)
			)
		)
		(property "Manufacturer" "STMicroelectronics"
			(at 344.15 -185.35 0)
			(layer "B.Fab")
			(hide yes)
			(effects
				(font
					(size 1 1)
					(thickness 0.15)
				)
				(justify mirror)
			)
		)
		(property "Public" "False"
			(at 344.15 -185.35 0)
			(layer "B.Fab")
			(hide yes)
			(effects
				(font
					(size 1 1)
					(thickness 0.15)
				)
				(justify mirror)
			)
		)
		(sheetname "User GPIO + LED + button + DIP switch")
		(sheetfile "user-gpio.kicad_sch")
		(attr smd)
		(fp_line
			(start 0.27 -0.3)
			(end -0.27 -0.3)
			(stroke
				(width 0.15)
				(type solid)
			)
			(layer "B.SilkS")
		)
		(fp_line
			(start 0.27 0.3)
			(end -0.27 0.3)
			(stroke
				(width 0.15)
				(type solid)
			)
			(layer "B.SilkS")
		)
		(fp_line
			(start -1.2 0.4)
			(end -1.2 -0.4)
			(stroke
				(width 0.15)
				(type solid)
			)
			(layer "B.SilkS")
		)
		(fp_rect
			(start 1.25 -0.65)
			(end -1.25 0.65)
			(stroke
				(width 0.05)
				(type solid)
			)
			(fill no)
			(layer "B.CrtYd")
		)
		(fp_line
			(start 0.201 -0.2)
			(end 0.201 0)
			(stroke
				(width 0.15)
				(type solid)
			)
			(layer "B.Fab")
		)
		(fp_line
			(start -0.199 -0.2)
			(end -0.199 -0.1)
			(stroke
				(width 0.15)
				(type solid)
			)
			(layer "B.Fab")
		)
		(fp_line
			(start 0.599 0)
			(end 0.201 0)
			(stroke
				(width 0.15)
				(type solid)
			)
			(layer "B.Fab")
		)
		(fp_line
			(start 0.201 0)
			(end 0.201 0.202)
			(stroke
				(width 0.15)
				(type solid)
			)
			(layer "B.Fab")
		)
		(fp_line
			(start -0.101 0)
			(end 0.201 -0.2)
			(stroke
				(width 0.15)
				(type solid)
			)
			(layer "B.Fab")
		)
		(fp_line
			(start -0.199 0)
			(end -0.597 0)
			(stroke
				(width 0.15)
				(type solid)
			)
			(layer "B.Fab")
		)
		(fp_line
			(start 0.201 0.202)
			(end -0.101 0)
			(stroke
				(width 0.15)
				(type solid)
			)
			(layer "B.Fab")
		)
		(fp_line
			(start -0.199 0.202)
			(end -0.199 -0.1)
			(stroke
				(width 0.15)
				(type solid)
			)
			(layer "B.Fab")
		)
		(fp_rect
			(start 0.848 -0.4)
			(end -0.85 0.402)
			(stroke
				(width 0.15)
				(type solid)
			)
			(fill no)
			(layer "B.Fab")
		)
		(pad "1" smd roundrect
			(at -0.7 0 270)
			(size 0.8 1)
			(layers "B.Cu" "B.Mask" "B.Paste")
			(roundrect_rratio 0.2)
			(net 1228 "/USER_IO.BUTTON0")
			(pinfunction "C")
			(pintype "passive")
		)
		(pad "2" smd roundrect
			(at 0.7 0 270)
			(size 0.8 1)
			(layers "B.Cu" "B.Mask" "B.Paste")
			(roundrect_rratio 0.2)
			(net 1 "GND")
			(pinfunction "A")
			(pintype "passive")
		)
	)
	(footprint "antmicro-footprints:C_0402_1005Metric"
		(layer "B.Cu")
		(at 210.5 117 90)
		(descr "Capacitor SMD 0402")
		(tags "capacitor SMD 0402")
		(property "Reference" "C27"
			(at 1.125 1.25 270)
			(layer "B.SilkS")
			(effects
				(font
					(size 0.7 0.7)
					(thickness 0.15)
				)
				(justify left bottom mirror)
			)
		)
		(property "Value" "C_100n_0402"
			(at 0 -1.169 270)
			(layer "B.Fab")
			(effects
				(font
					(size 0.7 0.7)
					(thickness 0.15)
				)
				(justify left bottom mirror)
			)
		)
		(property "Description" "SMD Multilayer Ceramic Capacitor, 0.1 µF, 50 V, 0402 [1005 Metric], ± 10%, X5R, GRM Series"
			(at 0 0 90)
			(layer "F.Fab")
			(hide yes)
			(effects
				(font
					(size 1.27 1.27)
					(thickness 0.15)
				)
			)
		)
		(property "Author" "Antmicro"
			(at 327.5 -93.5 0)
			(layer "B.Fab")
			(hide yes)
			(effects
				(font
					(size 1 1)
					(thickness 0.15)
				)
				(justify mirror)
			)
		)
		(property "Dielectric" "X5R"
			(at 327.5 -93.5 0)
			(layer "B.Fab")
			(hide yes)
			(effects
				(font
					(size 1 1)
					(thickness 0.15)
				)
				(justify mirror)
			)
		)
		(property "License" "Apache-2.0"
			(at 327.5 -93.5 0)
			(layer "B.Fab")
			(hide yes)
			(effects
				(font
					(size 1 1)
					(thickness 0.15)
				)
				(justify mirror)
			)
		)
		(property "MPN" "GRM155R61H104KE14D"
			(at 327.5 -93.5 0)
			(layer "B.Fab")
			(hide yes)
			(effects
				(font
					(size 1 1)
					(thickness 0.15)
				)
				(justify mirror)
			)
		)
		(property "Manufacturer" "Murata"
			(at 327.5 -93.5 0)
			(layer "B.Fab")
			(hide yes)
			(effects
				(font
					(size 1 1)
					(thickness 0.15)
				)
				(justify mirror)
			)
		)
		(property "Val" "100n"
			(at 327.5 -93.5 0)
			(layer "B.Fab")
			(hide yes)
			(effects
				(font
					(size 1 1)
					(thickness 0.15)
				)
				(justify mirror)
			)
		)
		(property "Voltage" "50V"
			(at 327.5 -93.5 0)
			(layer "B.Fab")
			(hide yes)
			(effects
				(font
					(size 1 1)
					(thickness 0.15)
				)
				(justify mirror)
			)
		)
		(sheetname "FPGA Bank 16 & 17")
		(sheetfile "fpga-bank-16-17.kicad_sch")
		(attr smd)
		(fp_rect
			(start -0.925 0.47)
			(end 0.925 -0.47)
			(stroke
				(width 0.05)
				(type default)
			)
			(fill no)
			(layer "B.CrtYd")
		)
		(fp_line
			(start 0.504 -0.248)
			(end -0.494 -0.248)
			(stroke
				(width 0.15)
				(type solid)
			)
			(layer "B.Fab")
		)
		(fp_line
			(start -0.494 -0.248)
			(end -0.494 0.25)
			(stroke
				(width 0.15)
				(type solid)
			)
			(layer "B.Fab")
		)
		(fp_line
			(start 0.504 0.25)
			(end 0.504 -0.248)
			(stroke
				(width 0.15)
				(type solid)
			)
			(layer "B.Fab")
		)
		(fp_line
			(start -0.494 0.25)
			(end 0.504 0.25)
			(stroke
				(width 0.15)
				(type solid)
			)
			(layer "B.Fab")
		)
		(pad "1" smd roundrect
			(at -0.48 0 90)
			(size 0.59 0.64)
			(layers "B.Cu" "B.Mask" "B.Paste")
			(roundrect_rratio 0.25)
			(net 1 "GND")
			(pintype "passive")
		)
		(pad "2" smd roundrect
			(at 0.48 0 90)
			(size 0.59 0.64)
			(layers "B.Cu" "B.Mask" "B.Paste")
			(roundrect_rratio 0.25)
			(net 3 "VCC_USR_B")
			(pintype "passive")
		)
	)
	(footprint "antmicro-footprints:C_0402_1005Metric"
		(layer "B.Cu")
		(at 196.85 131.25)
		(descr "Capacitor SMD 0402")
		(tags "capacitor SMD 0402")
		(property "Reference" "C63"
			(at 25 -28.025 180)
			(layer "B.SilkS")
			(effects
				(font
					(size 0.7 0.7)
					(thickness 0.15)
				)
				(justify left bottom mirror)
			)
		)
		(property "Value" "C_100n_0402"
			(at 0 -1.169 180)
			(layer "B.Fab")
			(effects
				(font
					(size 0.7 0.7)
					(thickness 0.15)
				)
				(justify left bottom mirror)
			)
		)
		(property "Description" "SMD Multilayer Ceramic Capacitor, 0.1 µF, 50 V, 0402 [1005 Metric], ± 10%, X5R, GRM Series"
			(at 0 0 0)
			(layer "F.Fab")
			(hide yes)
			(effects
				(font
					(size 1.27 1.27)
					(thickness 0.15)
				)
			)
		)
		(property "Author" "Antmicro"
			(at 0 0 0)
			(layer "B.Fab")
			(hide yes)
			(effects
				(font
					(size 1 1)
					(thickness 0.15)
				)
				(justify mirror)
			)
		)
		(property "Dielectric" "X5R"
			(at 0 0 0)
			(layer "B.Fab")
			(hide yes)
			(effects
				(font
					(size 1 1)
					(thickness 0.15)
				)
				(justify mirror)
			)
		)
		(property "License" "Apache-2.0"
			(at 0 0 0)
			(layer "B.Fab")
			(hide yes)
			(effects
				(font
					(size 1 1)
					(thickness 0.15)
				)
				(justify mirror)
			)
		)
		(property "MPN" "GRM155R61H104KE14D"
			(at 0 0 0)
			(layer "B.Fab")
			(hide yes)
			(effects
				(font
					(size 1 1)
					(thickness 0.15)
				)
				(justify mirror)
			)
		)
		(property "Manufacturer" "Murata"
			(at 0 0 0)
			(layer "B.Fab")
			(hide yes)
			(effects
				(font
					(size 1 1)
					(thickness 0.15)
				)
				(justify mirror)
			)
		)
		(property "Val" "100n"
			(at 0 0 0)
			(layer "B.Fab")
			(hide yes)
			(effects
				(font
					(size 1 1)
					(thickness 0.15)
				)
				(justify mirror)
			)
		)
		(property "Voltage" "50V"
			(at 0 0 0)
			(layer "B.Fab")
			(hide yes)
			(effects
				(font
					(size 1 1)
					(thickness 0.15)
				)
				(justify mirror)
			)
		)
		(sheetname "FPGA supply")
		(sheetfile "fpga-supply.kicad_sch")
		(attr smd)
		(fp_rect
			(start -0.925 0.47)
			(end 0.925 -0.47)
			(stroke
				(width 0.05)
				(type default)
			)
			(fill no)
			(layer "B.CrtYd")
		)
		(fp_line
			(start -0.494 -0.248)
			(end -0.494 0.25)
			(stroke
				(width 0.15)
				(type solid)
			)
			(layer "B.Fab")
		)
		(fp_line
			(start -0.494 0.25)
			(end 0.504 0.25)
			(stroke
				(width 0.15)
				(type solid)
			)
			(layer "B.Fab")
		)
		(fp_line
			(start 0.504 -0.248)
			(end -0.494 -0.248)
			(stroke
				(width 0.15)
				(type solid)
			)
			(layer "B.Fab")
		)
		(fp_line
			(start 0.504 0.25)
			(end 0.504 -0.248)
			(stroke
				(width 0.15)
				(type solid)
			)
			(layer "B.Fab")
		)
		(pad "1" smd roundrect
			(at -0.48 0)
			(size 0.59 0.64)
			(layers "B.Cu" "B.Mask" "B.Paste")
			(roundrect_rratio 0.25)
			(net 1 "GND")
			(pintype "passive")
		)
		(pad "2" smd roundrect
			(at 0.48 0)
			(size 0.59 0.64)
			(layers "B.Cu" "B.Mask" "B.Paste")
			(roundrect_rratio 0.25)
			(net 26 "+1V8")
			(pintype "passive")
		)
	)
	(footprint "antmicro-footprints:R_0402_1005Metric"
		(layer "B.Cu")
		(at 265.401 173)
		(descr "Resistor SMD 0402")
		(tags "resistor SMD 0402")
		(property "Reference" "R246"
			(at 3.649 0.35 180)
			(layer "B.SilkS")
			(effects
				(font
					(size 0.7 0.7)
					(thickness 0.15)
				)
				(justify left bottom mirror)
			)
		)
		(property "Value" "R_10R_0402"
			(at 0 -1.4 180)
			(layer "B.Fab")
			(effects
				(font
					(size 0.7 0.7)
					(thickness 0.15)
				)
				(justify left bottom mirror)
			)
		)
		(property "Description" "SMD Chip Resistor, 10 ohm, ± 1%, 62.5 mW, 0402 [1005 Metric], Thick Film, General Purpose"
			(at 0 0 0)
			(layer "F.Fab")
			(hide yes)
			(effects
				(font
					(size 1.27 1.27)
					(thickness 0.15)
				)
			)
		)
		(property "Author" "Antmicro"
			(at 0 0 0)
			(layer "B.Fab")
			(hide yes)
			(effects
				(font
					(size 1 1)
					(thickness 0.15)
				)
				(justify mirror)
			)
		)
		(property "License" "Apache-2.0"
			(at 0 0 0)
			(layer "B.Fab")
			(hide yes)
			(effects
				(font
					(size 1 1)
					(thickness 0.15)
				)
				(justify mirror)
			)
		)
		(property "MPN" "CR0402-FX-10R0GLF"
			(at 0 0 0)
			(layer "B.Fab")
			(hide yes)
			(effects
				(font
					(size 1 1)
					(thickness 0.15)
				)
				(justify mirror)
			)
		)
		(property "Manufacturer" "Bourns"
			(at 0 0 0)
			(layer "B.Fab")
			(hide yes)
			(effects
				(font
					(size 1 1)
					(thickness 0.15)
				)
				(justify mirror)
			)
		)
		(property "Tolerance" "1%"
			(at 0 0 0)
			(layer "B.Fab")
			(hide yes)
			(effects
				(font
					(size 1 1)
					(thickness 0.15)
				)
				(justify mirror)
			)
		)
		(property "Val" "10R"
			(at 0 0 0)
			(layer "B.Fab")
			(hide yes)
			(effects
				(font
					(size 1 1)
					(thickness 0.15)
				)
				(justify mirror)
			)
		)
		(sheetname "HDMI + Ethernet")
		(sheetfile "hdmi-ethernet.kicad_sch")
		(attr smd)
		(fp_rect
			(start -0.925 0.47)
			(end 0.925 -0.47)
			(stroke
				(width 0.05)
				(type default)
			)
			(fill no)
			(layer "B.CrtYd")
		)
		(fp_rect
			(start -0.5 0.25)
			(end 0.5 -0.25)
			(stroke
				(width 0.15)
				(type solid)
			)
			(fill no)
			(layer "B.Fab")
		)
		(pad "1" smd roundrect
			(at -0.48 0)
			(size 0.59 0.64)
			(layers "B.Cu" "B.Mask" "B.Paste")
			(roundrect_rratio 0.25)
			(net 1 "GND")
			(pintype "passive")
		)
		(pad "2" smd roundrect
			(at 0.48 0)
			(size 0.59 0.64)
			(layers "B.Cu" "B.Mask" "B.Paste")
			(roundrect_rratio 0.25)
			(net 723 "/HDMI + Ethernet/ETH_CONN_SH")
			(pintype "passive")
		)
	)
	(footprint "antmicro-footprints:R_0402_1005Metric"
		(layer "B.Cu")
		(at 250.301 141.25 -90)
		(descr "Resistor SMD 0402")
		(tags "resistor SMD 0402")
		(property "Reference" "R87"
			(at 0.75 -0.399 90)
			(layer "B.SilkS")
			(effects
				(font
					(size 0.7 0.7)
					(thickness 0.15)
				)
				(justify left bottom mirror)
			)
		)
		(property "Value" "R_10k_0402"
			(at 0 -1.4 90)
			(layer "B.Fab")
			(effects
				(font
					(size 0.7 0.7)
					(thickness 0.15)
				)
				(justify left bottom mirror)
			)
		)
		(property "Description" "SMD Chip Resistor, 10 kohm, ± 1%, 62.5 mW, 0402 [1005 Metric], Thick Film, General Purpose"
			(at 0 0 270)
			(layer "F.Fab")
			(hide yes)
			(effects
				(font
					(size 1.27 1.27)
					(thickness 0.15)
				)
			)
		)
		(property "Author" "Antmicro"
			(at 109.051 391.551 0)
			(layer "B.Fab")
			(hide yes)
			(effects
				(font
					(size 1 1)
					(thickness 0.15)
				)
				(justify mirror)
			)
		)
		(property "License" "Apache-2.0"
			(at 109.051 391.551 0)
			(layer "B.Fab")
			(hide yes)
			(effects
				(font
					(size 1 1)
					(thickness 0.15)
				)
				(justify mirror)
			)
		)
		(property "MPN" "CR0402-FX-1002GLF"
			(at 109.051 391.551 0)
			(layer "B.Fab")
			(hide yes)
			(effects
				(font
					(size 1 1)
					(thickness 0.15)
				)
				(justify mirror)
			)
		)
		(property "Manufacturer" "Bourns"
			(at 109.051 391.551 0)
			(layer "B.Fab")
			(hide yes)
			(effects
				(font
					(size 1 1)
					(thickness 0.15)
				)
				(justify mirror)
			)
		)
		(property "Tolerance" "1%"
			(at 109.051 391.551 0)
			(layer "B.Fab")
			(hide yes)
			(effects
				(font
					(size 1 1)
					(thickness 0.15)
				)
				(justify mirror)
			)
		)
		(property "Val" "10k"
			(at 109.051 391.551 0)
			(layer "B.Fab")
			(hide yes)
			(effects
				(font
					(size 1 1)
					(thickness 0.15)
				)
				(justify mirror)
			)
		)
		(sheetname "SPI Flash + SD Card")
		(sheetfile "spi-flash.kicad_sch")
		(attr smd)
		(fp_rect
			(start -0.925 0.47)
			(end 0.925 -0.47)
			(stroke
				(width 0.05)
				(type default)
			)
			(fill no)
			(layer "B.CrtYd")
		)
		(fp_rect
			(start -0.5 0.25)
			(end 0.5 -0.25)
			(stroke
				(width 0.15)
				(type solid)
			)
			(fill no)
			(layer "B.Fab")
		)
		(pad "1" smd roundrect
			(at -0.48 0 270)
			(size 0.59 0.64)
			(layers "B.Cu" "B.Mask" "B.Paste")
			(roundrect_rratio 0.25)
			(net 391 "/FPGA Bank 33 & 34/SD_CARD.DAT3")
			(pintype "passive")
		)
		(pad "2" smd roundrect
			(at 0.48 0 270)
			(size 0.59 0.64)
			(layers "B.Cu" "B.Mask" "B.Paste")
			(roundrect_rratio 0.25)
			(net 24 "+3V3")
			(pintype "passive")
		)
	)
	(footprint "antmicro-footprints:C_0402_1005Metric"
		(layer "B.Cu")
		(at 198.325 126.825 180)
		(descr "Capacitor SMD 0402")
		(tags "capacitor SMD 0402")
		(property "Reference" "C131"
			(at -26.3 29.375 0)
			(layer "B.SilkS")
			(effects
				(font
					(size 0.7 0.7)
					(thickness 0.15)
				)
				(justify left bottom mirror)
			)
		)
		(property "Value" "C_100n_0402"
			(at 0 -1.169 0)
			(layer "B.Fab")
			(effects
				(font
					(size 0.7 0.7)
					(thickness 0.15)
				)
				(justify left bottom mirror)
			)
		)
		(property "Description" "SMD Multilayer Ceramic Capacitor, 0.1 µF, 50 V, 0402 [1005 Metric], ± 10%, X5R, GRM Series"
			(at 0 0 180)
			(layer "F.Fab")
			(hide yes)
			(effects
				(font
					(size 1.27 1.27)
					(thickness 0.15)
				)
			)
		)
		(property "Author" "Antmicro"
			(at 396.65 253.65 0)
			(layer "B.Fab")
			(hide yes)
			(effects
				(font
					(size 1 1)
					(thickness 0.15)
				)
				(justify mirror)
			)
		)
		(property "Dielectric" "X5R"
			(at 396.65 253.65 0)
			(layer "B.Fab")
			(hide yes)
			(effects
				(font
					(size 1 1)
					(thickness 0.15)
				)
				(justify mirror)
			)
		)
		(property "License" "Apache-2.0"
			(at 396.65 253.65 0)
			(layer "B.Fab")
			(hide yes)
			(effects
				(font
					(size 1 1)
					(thickness 0.15)
				)
				(justify mirror)
			)
		)
		(property "MPN" "GRM155R61H104KE14D"
			(at 396.65 253.65 0)
			(layer "B.Fab")
			(hide yes)
			(effects
				(font
					(size 1 1)
					(thickness 0.15)
				)
				(justify mirror)
			)
		)
		(property "Manufacturer" "Murata"
			(at 396.65 253.65 0)
			(layer "B.Fab")
			(hide yes)
			(effects
				(font
					(size 1 1)
					(thickness 0.15)
				)
				(justify mirror)
			)
		)
		(property "Val" "100n"
			(at 396.65 253.65 0)
			(layer "B.Fab")
			(hide yes)
			(effects
				(font
					(size 1 1)
					(thickness 0.15)
				)
				(justify mirror)
			)
		)
		(property "Voltage" "50V"
			(at 396.65 253.65 0)
			(layer "B.Fab")
			(hide yes)
			(effects
				(font
					(size 1 1)
					(thickness 0.15)
				)
				(justify mirror)
			)
		)
		(sheetname "FPGA supply")
		(sheetfile "fpga-supply.kicad_sch")
		(attr smd)
		(fp_rect
			(start -0.925 0.47)
			(end 0.925 -0.47)
			(stroke
				(width 0.05)
				(type default)
			)
			(fill no)
			(layer "B.CrtYd")
		)
		(fp_line
			(start 0.504 0.25)
			(end 0.504 -0.248)
			(stroke
				(width 0.15)
				(type solid)
			)
			(layer "B.Fab")
		)
		(fp_line
			(start 0.504 -0.248)
			(end -0.494 -0.248)
			(stroke
				(width 0.15)
				(type solid)
			)
			(layer "B.Fab")
		)
		(fp_line
			(start -0.494 0.25)
			(end 0.504 0.25)
			(stroke
				(width 0.15)
				(type solid)
			)
			(layer "B.Fab")
		)
		(fp_line
			(start -0.494 -0.248)
			(end -0.494 0.25)
			(stroke
				(width 0.15)
				(type solid)
			)
			(layer "B.Fab")
		)
		(pad "1" smd roundrect
			(at -0.48 0 180)
			(size 0.59 0.64)
			(layers "B.Cu" "B.Mask" "B.Paste")
			(roundrect_rratio 0.25)
			(net 1 "GND")
			(pintype "passive")
		)
		(pad "2" smd roundrect
			(at 0.48 0 180)
			(size 0.59 0.64)
			(layers "B.Cu" "B.Mask" "B.Paste")
			(roundrect_rratio 0.25)
			(net 650 "+1V0")
			(pintype "passive")
		)
	)
	(footprint "antmicro-footprints:C_0402_1005Metric"
		(layer "B.Cu")
		(at 187.25 137.25 -90)
		(descr "Capacitor SMD 0402")
		(tags "capacitor SMD 0402")
		(property "Reference" "C62"
			(at -1.1 0.5 90)
			(layer "B.SilkS")
			(effects
				(font
					(size 0.7 0.7)
					(thickness 0.15)
				)
				(justify left bottom mirror)
			)
		)
		(property "Value" "C_100n_0402"
			(at 0 -1.169 90)
			(layer "B.Fab")
			(effects
				(font
					(size 0.7 0.7)
					(thickness 0.15)
				)
				(justify left bottom mirror)
			)
		)
		(property "Description" "SMD Multilayer Ceramic Capacitor, 0.1 µF, 50 V, 0402 [1005 Metric], ± 10%, X5R, GRM Series"
			(at 0 0 270)
			(layer "F.Fab")
			(hide yes)
			(effects
				(font
					(size 1.27 1.27)
					(thickness 0.15)
				)
			)
		)
		(property "Author" "Antmicro"
			(at 50 324.5 0)
			(layer "B.Fab")
			(hide yes)
			(effects
				(font
					(size 1 1)
					(thickness 0.15)
				)
				(justify mirror)
			)
		)
		(property "Dielectric" "X5R"
			(at 50 324.5 0)
			(layer "B.Fab")
			(hide yes)
			(effects
				(font
					(size 1 1)
					(thickness 0.15)
				)
				(justify mirror)
			)
		)
		(property "License" "Apache-2.0"
			(at 50 324.5 0)
			(layer "B.Fab")
			(hide yes)
			(effects
				(font
					(size 1 1)
					(thickness 0.15)
				)
				(justify mirror)
			)
		)
		(property "MPN" "GRM155R61H104KE14D"
			(at 50 324.5 0)
			(layer "B.Fab")
			(hide yes)
			(effects
				(font
					(size 1 1)
					(thickness 0.15)
				)
				(justify mirror)
			)
		)
		(property "Manufacturer" "Murata"
			(at 50 324.5 0)
			(layer "B.Fab")
			(hide yes)
			(effects
				(font
					(size 1 1)
					(thickness 0.15)
				)
				(justify mirror)
			)
		)
		(property "Val" "100n"
			(at 50 324.5 0)
			(layer "B.Fab")
			(hide yes)
			(effects
				(font
					(size 1 1)
					(thickness 0.15)
				)
				(justify mirror)
			)
		)
		(property "Voltage" "50V"
			(at 50 324.5 0)
			(layer "B.Fab")
			(hide yes)
			(effects
				(font
					(size 1 1)
					(thickness 0.15)
				)
				(justify mirror)
			)
		)
		(sheetname "FPGA Bank 33 & 34")
		(sheetfile "fpga-bank-33-34.kicad_sch")
		(attr smd)
		(fp_rect
			(start -0.925 0.47)
			(end 0.925 -0.47)
			(stroke
				(width 0.05)
				(type default)
			)
			(fill no)
			(layer "B.CrtYd")
		)
		(fp_line
			(start -0.494 0.25)
			(end 0.504 0.25)
			(stroke
				(width 0.15)
				(type solid)
			)
			(layer "B.Fab")
		)
		(fp_line
			(start 0.504 0.25)
			(end 0.504 -0.248)
			(stroke
				(width 0.15)
				(type solid)
			)
			(layer "B.Fab")
		)
		(fp_line
			(start -0.494 -0.248)
			(end -0.494 0.25)
			(stroke
				(width 0.15)
				(type solid)
			)
			(layer "B.Fab")
		)
		(fp_line
			(start 0.504 -0.248)
			(end -0.494 -0.248)
			(stroke
				(width 0.15)
				(type solid)
			)
			(layer "B.Fab")
		)
		(pad "1" smd roundrect
			(at -0.48 0 270)
			(size 0.59 0.64)
			(layers "B.Cu" "B.Mask" "B.Paste")
			(roundrect_rratio 0.25)
			(net 1 "GND")
			(pintype "passive")
		)
		(pad "2" smd roundrect
			(at 0.48 0 270)
			(size 0.59 0.64)
			(layers "B.Cu" "B.Mask" "B.Paste")
			(roundrect_rratio 0.25)
			(net 25 "+1V35")
			(pintype "passive")
		)
	)
	(footprint "antmicro-footprints:C_0402_1005Metric"
		(layer "B.Cu")
		(at 191.75 126.275)
		(descr "Capacitor SMD 0402")
		(tags "capacitor SMD 0402")
		(property "Reference" "C103"
			(at 22.975 -29.3 180)
			(layer "B.SilkS")
			(effects
				(font
					(size 0.7 0.7)
					(thickness 0.15)
				)
				(justify left bottom mirror)
			)
		)
		(property "Value" "C_100n_0402"
			(at 0 -1.169 180)
			(layer "B.Fab")
			(effects
				(font
					(size 0.7 0.7)
					(thickness 0.15)
				)
				(justify left bottom mirror)
			)
		)
		(property "Description" "SMD Multilayer Ceramic Capacitor, 0.1 µF, 50 V, 0402 [1005 Metric], ± 10%, X5R, GRM Series"
			(at 0 0 0)
			(layer "F.Fab")
			(hide yes)
			(effects
				(font
					(size 1.27 1.27)
					(thickness 0.15)
				)
			)
		)
		(property "Author" "Antmicro"
			(at 0 0 0)
			(layer "B.Fab")
			(hide yes)
			(effects
				(font
					(size 1 1)
					(thickness 0.15)
				)
				(justify mirror)
			)
		)
		(property "Dielectric" "X5R"
			(at 0 0 0)
			(layer "B.Fab")
			(hide yes)
			(effects
				(font
					(size 1 1)
					(thickness 0.15)
				)
				(justify mirror)
			)
		)
		(property "License" "Apache-2.0"
			(at 0 0 0)
			(layer "B.Fab")
			(hide yes)
			(effects
				(font
					(size 1 1)
					(thickness 0.15)
				)
				(justify mirror)
			)
		)
		(property "MPN" "GRM155R61H104KE14D"
			(at 0 0 0)
			(layer "B.Fab")
			(hide yes)
			(effects
				(font
					(size 1 1)
					(thickness 0.15)
				)
				(justify mirror)
			)
		)
		(property "Manufacturer" "Murata"
			(at 0 0 0)
			(layer "B.Fab")
			(hide yes)
			(effects
				(font
					(size 1 1)
					(thickness 0.15)
				)
				(justify mirror)
			)
		)
		(property "Val" "100n"
			(at 0 0 0)
			(layer "B.Fab")
			(hide yes)
			(effects
				(font
					(size 1 1)
					(thickness 0.15)
				)
				(justify mirror)
			)
		)
		(property "Voltage" "50V"
			(at 0 0 0)
			(layer "B.Fab")
			(hide yes)
			(effects
				(font
					(size 1 1)
					(thickness 0.15)
				)
				(justify mirror)
			)
		)
		(sheetname "FPGA supply")
		(sheetfile "fpga-supply.kicad_sch")
		(attr smd)
		(fp_rect
			(start -0.925 0.47)
			(end 0.925 -0.47)
			(stroke
				(width 0.05)
				(type default)
			)
			(fill no)
			(layer "B.CrtYd")
		)
		(fp_line
			(start -0.494 -0.248)
			(end -0.494 0.25)
			(stroke
				(width 0.15)
				(type solid)
			)
			(layer "B.Fab")
		)
		(fp_line
			(start -0.494 0.25)
			(end 0.504 0.25)
			(stroke
				(width 0.15)
				(type solid)
			)
			(layer "B.Fab")
		)
		(fp_line
			(start 0.504 -0.248)
			(end -0.494 -0.248)
			(stroke
				(width 0.15)
				(type solid)
			)
			(layer "B.Fab")
		)
		(fp_line
			(start 0.504 0.25)
			(end 0.504 -0.248)
			(stroke
				(width 0.15)
				(type solid)
			)
			(layer "B.Fab")
		)
		(pad "1" smd roundrect
			(at -0.48 0)
			(size 0.59 0.64)
			(layers "B.Cu" "B.Mask" "B.Paste")
			(roundrect_rratio 0.25)
			(net 6 "+1V0_MGTAVCC")
			(pintype "passive")
		)
		(pad "2" smd roundrect
			(at 0.48 0)
			(size 0.59 0.64)
			(layers "B.Cu" "B.Mask" "B.Paste")
			(roundrect_rratio 0.25)
			(net 1 "GND")
			(pintype "passive")
		)
	)
	(footprint "antmicro-footprints:R_0603_1608Metric"
		(layer "B.Cu")
		(at 262.401 170.3 180)
		(descr "Resistor SMD 0603")
		(tags "resistor SMD 0603")
		(property "Reference" "R251"
			(at 1.051 -0.375 0)
			(layer "B.SilkS")
			(effects
				(font
					(size 0.7 0.7)
					(thickness 0.15)
				)
				(justify left bottom mirror)
			)
		)
		(property "Value" "R_220R_0603"
			(at 0 -1.6 0)
			(layer "B.Fab")
			(effects
				(font
					(size 0.7 0.7)
					(thickness 0.15)
				)
				(justify left bottom mirror)
			)
		)
		(property "Description" "SMD Chip Resistor, 220 ohm, ± 1%, 100 mW, 0603 [1608 Metric], Thick Film, General Purpose"
			(at 0 0 180)
			(layer "F.Fab")
			(hide yes)
			(effects
				(font
					(size 1.27 1.27)
					(thickness 0.15)
				)
			)
		)
		(property "Author" "Antmicro"
			(at 524.802 340.6 0)
			(layer "B.Fab")
			(hide yes)
			(effects
				(font
					(size 1 1)
					(thickness 0.15)
				)
				(justify mirror)
			)
		)
		(property "License" "Apache-2.0"
			(at 524.802 340.6 0)
			(layer "B.Fab")
			(hide yes)
			(effects
				(font
					(size 1 1)
					(thickness 0.15)
				)
				(justify mirror)
			)
		)
		(property "MPN" "CR0603-FX-2200ELF"
			(at 524.802 340.6 0)
			(layer "B.Fab")
			(hide yes)
			(effects
				(font
					(size 1 1)
					(thickness 0.15)
				)
				(justify mirror)
			)
		)
		(property "Manufacturer" "Bourns"
			(at 524.802 340.6 0)
			(layer "B.Fab")
			(hide yes)
			(effects
				(font
					(size 1 1)
					(thickness 0.15)
				)
				(justify mirror)
			)
		)
		(property "Tolerance" "1%"
			(at 524.802 340.6 0)
			(layer "B.Fab")
			(hide yes)
			(effects
				(font
					(size 1 1)
					(thickness 0.15)
				)
				(justify mirror)
			)
		)
		(property "Val" "220R"
			(at 524.802 340.6 0)
			(layer "B.Fab")
			(hide yes)
			(effects
				(font
					(size 1 1)
					(thickness 0.15)
				)
				(justify mirror)
			)
		)
		(sheetname "HDMI + Ethernet")
		(sheetfile "hdmi-ethernet.kicad_sch")
		(attr smd)
		(fp_line
			(start -0.15 0.4)
			(end 0.15 0.4)
			(stroke
				(width 0.15)
				(type solid)
			)
			(layer "B.SilkS")
		)
		(fp_line
			(start -0.15 -0.4)
			(end 0.15 -0.4)
			(stroke
				(width 0.15)
				(type solid)
			)
			(layer "B.SilkS")
		)
		(fp_rect
			(start -1.25 0.65)
			(end 1.25 -0.65)
			(stroke
				(width 0.05)
				(type solid)
			)
			(fill no)
			(layer "B.CrtYd")
		)
		(fp_rect
			(start -0.8 0.4)
			(end 0.8 -0.4)
			(stroke
				(width 0.15)
				(type solid)
			)
			(fill no)
			(layer "B.Fab")
		)
		(pad "1" smd roundrect
			(at -0.7 0 180)
			(size 0.8 1)
			(layers "B.Cu" "B.Mask" "B.Paste")
			(roundrect_rratio 0.2)
			(net 845 "/HDMI + Ethernet/ETH_LED_LINK+")
			(pintype "passive")
		)
		(pad "2" smd roundrect
			(at 0.7 0 180)
			(size 0.8 1)
			(layers "B.Cu" "B.Mask" "B.Paste")
			(roundrect_rratio 0.2)
			(net 24 "+3V3")
			(pintype "passive")
		)
	)
	(footprint "antmicro-footprints:R_Array_4x0201_Panasonic_EXB18V"
		(layer "B.Cu")
		(at 251.251 137.7 90)
		(property "Reference" "R61"
			(at -1.1 -0.701 270)
			(layer "B.SilkS")
			(effects
				(font
					(size 0.7 0.7)
					(thickness 0.15)
				)
				(justify right bottom mirror)
			)
		)
		(property "Value" "R_4x33R_0201_array"
			(at -1.1 -1.8 270)
			(layer "B.Fab")
			(effects
				(font
					(size 0.7 0.7)
					(thickness 0.15)
				)
				(justify left bottom mirror)
			)
		)
		(property "Description" "Fixed Network Resistor, 33 ohm, Isolated, 4 Resistors, 0502 [1406 Metric], Flat, ± 5%"
			(at 0 0 90)
			(layer "F.Fab")
			(hide yes)
			(effects
				(font
					(size 1.27 1.27)
					(thickness 0.15)
				)
			)
		)
		(property "Author" "Antmicro"
			(at 388.951 -113.551 0)
			(layer "B.Fab")
			(hide yes)
			(effects
				(font
					(size 1 1)
					(thickness 0.15)
				)
				(justify mirror)
			)
		)
		(property "License" "Apache-2.0"
			(at 388.951 -113.551 0)
			(layer "B.Fab")
			(hide yes)
			(effects
				(font
					(size 1 1)
					(thickness 0.15)
				)
				(justify mirror)
			)
		)
		(property "MPN" "EXB-18V330JX"
			(at 388.951 -113.551 0)
			(layer "B.Fab")
			(hide yes)
			(effects
				(font
					(size 1 1)
					(thickness 0.15)
				)
				(justify mirror)
			)
		)
		(property "Manufacturer" "Panasonic"
			(at 388.951 -113.551 0)
			(layer "B.Fab")
			(hide yes)
			(effects
				(font
					(size 1 1)
					(thickness 0.15)
				)
				(justify mirror)
			)
		)
		(property "Val" "R_4x33R_0201"
			(at 388.951 -113.551 0)
			(layer "B.Fab")
			(hide yes)
			(effects
				(font
					(size 1 1)
					(thickness 0.15)
				)
				(justify mirror)
			)
		)
		(sheetname "SPI Flash + SD Card")
		(sheetfile "spi-flash.kicad_sch")
		(attr smd)
		(fp_line
			(start 0.8 0.45)
			(end 0.8 -0.45)
			(stroke
				(width 0.12)
				(type solid)
			)
			(layer "B.SilkS")
		)
		(fp_line
			(start -0.8 0.45)
			(end -0.8 -0.45)
			(stroke
				(width 0.12)
				(type solid)
			)
			(layer "B.SilkS")
		)
		(fp_rect
			(start -0.898 0.66)
			(end 0.898 -0.65)
			(stroke
				(width 0.05)
				(type solid)
			)
			(fill no)
			(layer "B.CrtYd")
		)
		(pad "1" smd roundrect
			(at -0.6 -0.298 90)
			(size 0.2 0.4)
			(layers "B.Cu" "B.Mask" "B.Paste")
			(roundrect_rratio 0.25)
			(net 390 "/FPGA Bank 33 & 34/SD_CARD.DAT2")
			(pinfunction "R1.1")
			(pintype "passive")
		)
		(pad "2" smd roundrect
			(at -0.202 -0.298 90)
			(size 0.2 0.4)
			(layers "B.Cu" "B.Mask" "B.Paste")
			(roundrect_rratio 0.25)
			(net 391 "/FPGA Bank 33 & 34/SD_CARD.DAT3")
			(pinfunction "R2.1")
			(pintype "passive")
		)
		(pad "3" smd roundrect
			(at 0.2 -0.298 90)
			(size 0.2 0.4)
			(layers "B.Cu" "B.Mask" "B.Paste")
			(roundrect_rratio 0.25)
			(net 393 "/FPGA Bank 33 & 34/SD_CARD.CMD")
			(pinfunction "R3.1")
			(pintype "passive")
		)
		(pad "4" smd roundrect
			(at 0.598 -0.298 90)
			(size 0.2 0.4)
			(layers "B.Cu" "B.Mask" "B.Paste")
			(roundrect_rratio 0.25)
			(net 363 "unconnected-(R61-R4.1-Pad4)")
			(pinfunction "R4.1")
			(pintype "passive+no_connect")
		)
		(pad "5" smd roundrect
			(at 0.598 0.3 90)
			(size 0.2 0.4)
			(layers "B.Cu" "B.Mask" "B.Paste")
			(roundrect_rratio 0.25)
			(net 364 "unconnected-(R61-R4.2-Pad5)")
			(pinfunction "R4.2")
			(pintype "passive+no_connect")
		)
		(pad "6" smd roundrect
			(at 0.2 0.3 90)
			(size 0.2 0.4)
			(layers "B.Cu" "B.Mask" "B.Paste")
			(roundrect_rratio 0.25)
			(net 329 "Net-(J23-CMD)")
			(pinfunction "R3.2")
			(pintype "passive")
		)
		(pad "7" smd roundrect
			(at -0.202 0.3 90)
			(size 0.2 0.4)
			(layers "B.Cu" "B.Mask" "B.Paste")
			(roundrect_rratio 0.25)
			(net 328 "Net-(J23-DAT3{slash}CD)")
			(pinfunction "R2.2")
			(pintype "passive")
		)
		(pad "8" smd roundrect
			(at -0.6 0.3 90)
			(size 0.2 0.4)
			(layers "B.Cu" "B.Mask" "B.Paste")
			(roundrect_rratio 0.25)
			(net 327 "Net-(J23-DAT2)")
			(pinfunction "R1.2")
			(pintype "passive")
		)
	)
	(footprint "antmicro-footprints:C_0402_1005Metric"
		(layer "B.Cu")
		(at 198.325 134.175 180)
		(descr "Capacitor SMD 0402")
		(tags "capacitor SMD 0402")
		(property "Reference" "C53"
			(at -26.025 28.1 0)
			(layer "B.SilkS")
			(effects
				(font
					(size 0.7 0.7)
					(thickness 0.15)
				)
				(justify left bottom mirror)
			)
		)
		(property "Value" "C_100n_0402"
			(at 0 -1.169 0)
			(layer "B.Fab")
			(effects
				(font
					(size 0.7 0.7)
					(thickness 0.15)
				)
				(justify left bottom mirror)
			)
		)
		(property "Description" "SMD Multilayer Ceramic Capacitor, 0.1 µF, 50 V, 0402 [1005 Metric], ± 10%, X5R, GRM Series"
			(at 0 0 180)
			(layer "F.Fab")
			(hide yes)
			(effects
				(font
					(size 1.27 1.27)
					(thickness 0.15)
				)
			)
		)
		(property "Author" "Antmicro"
			(at 396.65 268.35 0)
			(layer "B.Fab")
			(hide yes)
			(effects
				(font
					(size 1 1)
					(thickness 0.15)
				)
				(justify mirror)
			)
		)
		(property "Dielectric" "X5R"
			(at 396.65 268.35 0)
			(layer "B.Fab")
			(hide yes)
			(effects
				(font
					(size 1 1)
					(thickness 0.15)
				)
				(justify mirror)
			)
		)
		(property "License" "Apache-2.0"
			(at 396.65 268.35 0)
			(layer "B.Fab")
			(hide yes)
			(effects
				(font
					(size 1 1)
					(thickness 0.15)
				)
				(justify mirror)
			)
		)
		(property "MPN" "GRM155R61H104KE14D"
			(at 396.65 268.35 0)
			(layer "B.Fab")
			(hide yes)
			(effects
				(font
					(size 1 1)
					(thickness 0.15)
				)
				(justify mirror)
			)
		)
		(property "Manufacturer" "Murata"
			(at 396.65 268.35 0)
			(layer "B.Fab")
			(hide yes)
			(effects
				(font
					(size 1 1)
					(thickness 0.15)
				)
				(justify mirror)
			)
		)
		(property "Val" "100n"
			(at 396.65 268.35 0)
			(layer "B.Fab")
			(hide yes)
			(effects
				(font
					(size 1 1)
					(thickness 0.15)
				)
				(justify mirror)
			)
		)
		(property "Voltage" "50V"
			(at 396.65 268.35 0)
			(layer "B.Fab")
			(hide yes)
			(effects
				(font
					(size 1 1)
					(thickness 0.15)
				)
				(justify mirror)
			)
		)
		(sheetname "FPGA supply")
		(sheetfile "fpga-supply.kicad_sch")
		(attr smd)
		(fp_rect
			(start -0.925 0.47)
			(end 0.925 -0.47)
			(stroke
				(width 0.05)
				(type default)
			)
			(fill no)
			(layer "B.CrtYd")
		)
		(fp_line
			(start 0.504 0.25)
			(end 0.504 -0.248)
			(stroke
				(width 0.15)
				(type solid)
			)
			(layer "B.Fab")
		)
		(fp_line
			(start 0.504 -0.248)
			(end -0.494 -0.248)
			(stroke
				(width 0.15)
				(type solid)
			)
			(layer "B.Fab")
		)
		(fp_line
			(start -0.494 0.25)
			(end 0.504 0.25)
			(stroke
				(width 0.15)
				(type solid)
			)
			(layer "B.Fab")
		)
		(fp_line
			(start -0.494 -0.248)
			(end -0.494 0.25)
			(stroke
				(width 0.15)
				(type solid)
			)
			(layer "B.Fab")
		)
		(pad "1" smd roundrect
			(at -0.48 0 180)
			(size 0.59 0.64)
			(layers "B.Cu" "B.Mask" "B.Paste")
			(roundrect_rratio 0.25)
			(net 1 "GND")
			(pintype "passive")
		)
		(pad "2" smd roundrect
			(at 0.48 0 180)
			(size 0.59 0.64)
			(layers "B.Cu" "B.Mask" "B.Paste")
			(roundrect_rratio 0.25)
			(net 26 "+1V8")
			(pintype "passive")
		)
	)
	(footprint "antmicro-footprints:C_0402_1005Metric"
		(layer "B.Cu")
		(at 202 137.5 180)
		(descr "Capacitor SMD 0402")
		(tags "capacitor SMD 0402")
		(property "Reference" "C69"
			(at -1.1 -1.225 0)
			(layer "B.SilkS")
			(effects
				(font
					(size 0.7 0.7)
					(thickness 0.15)
				)
				(justify left bottom mirror)
			)
		)
		(property "Value" "C_100n_0402"
			(at 0 -1.169 0)
			(layer "B.Fab")
			(effects
				(font
					(size 0.7 0.7)
					(thickness 0.15)
				)
				(justify left bottom mirror)
			)
		)
		(property "Description" "SMD Multilayer Ceramic Capacitor, 0.1 µF, 50 V, 0402 [1005 Metric], ± 10%, X5R, GRM Series"
			(at 0 0 180)
			(layer "F.Fab")
			(hide yes)
			(effects
				(font
					(size 1.27 1.27)
					(thickness 0.15)
				)
			)
		)
		(property "Author" "Antmicro"
			(at 404 275 0)
			(layer "B.Fab")
			(hide yes)
			(effects
				(font
					(size 1 1)
					(thickness 0.15)
				)
				(justify mirror)
			)
		)
		(property "Dielectric" "X5R"
			(at 404 275 0)
			(layer "B.Fab")
			(hide yes)
			(effects
				(font
					(size 1 1)
					(thickness 0.15)
				)
				(justify mirror)
			)
		)
		(property "License" "Apache-2.0"
			(at 404 275 0)
			(layer "B.Fab")
			(hide yes)
			(effects
				(font
					(size 1 1)
					(thickness 0.15)
				)
				(justify mirror)
			)
		)
		(property "MPN" "GRM155R61H104KE14D"
			(at 404 275 0)
			(layer "B.Fab")
			(hide yes)
			(effects
				(font
					(size 1 1)
					(thickness 0.15)
				)
				(justify mirror)
			)
		)
		(property "Manufacturer" "Murata"
			(at 404 275 0)
			(layer "B.Fab")
			(hide yes)
			(effects
				(font
					(size 1 1)
					(thickness 0.15)
				)
				(justify mirror)
			)
		)
		(property "Val" "100n"
			(at 404 275 0)
			(layer "B.Fab")
			(hide yes)
			(effects
				(font
					(size 1 1)
					(thickness 0.15)
				)
				(justify mirror)
			)
		)
		(property "Voltage" "50V"
			(at 404 275 0)
			(layer "B.Fab")
			(hide yes)
			(effects
				(font
					(size 1 1)
					(thickness 0.15)
				)
				(justify mirror)
			)
		)
		(sheetname "FPGA Bank 18 & 32")
		(sheetfile "fpga-bank-18-32.kicad_sch")
		(attr smd)
		(fp_rect
			(start -0.925 0.47)
			(end 0.925 -0.47)
			(stroke
				(width 0.05)
				(type default)
			)
			(fill no)
			(layer "B.CrtYd")
		)
		(fp_line
			(start 0.504 0.25)
			(end 0.504 -0.248)
			(stroke
				(width 0.15)
				(type solid)
			)
			(layer "B.Fab")
		)
		(fp_line
			(start 0.504 -0.248)
			(end -0.494 -0.248)
			(stroke
				(width 0.15)
				(type solid)
			)
			(layer "B.Fab")
		)
		(fp_line
			(start -0.494 0.25)
			(end 0.504 0.25)
			(stroke
				(width 0.15)
				(type solid)
			)
			(layer "B.Fab")
		)
		(fp_line
			(start -0.494 -0.248)
			(end -0.494 0.25)
			(stroke
				(width 0.15)
				(type solid)
			)
			(layer "B.Fab")
		)
		(pad "1" smd roundrect
			(at -0.48 0 180)
			(size 0.59 0.64)
			(layers "B.Cu" "B.Mask" "B.Paste")
			(roundrect_rratio 0.25)
			(net 1 "GND")
			(pintype "passive")
		)
		(pad "2" smd roundrect
			(at 0.48 0 180)
			(size 0.59 0.64)
			(layers "B.Cu" "B.Mask" "B.Paste")
			(roundrect_rratio 0.25)
			(net 26 "+1V8")
			(pintype "passive")
		)
	)
	(footprint "antmicro-footprints:R_0402_1005Metric"
		(layer "B.Cu")
		(at 227.1 154.2 180)
		(descr "Resistor SMD 0402")
		(tags "resistor SMD 0402")
		(property "Reference" "R224"
			(at 0.725 -0.375 0)
			(layer "B.SilkS")
			(effects
				(font
					(size 0.7 0.7)
					(thickness 0.15)
				)
				(justify left bottom mirror)
			)
		)
		(property "Value" "R_10k_0402"
			(at 0 -1.4 0)
			(layer "B.Fab")
			(effects
				(font
					(size 0.7 0.7)
					(thickness 0.15)
				)
				(justify left bottom mirror)
			)
		)
		(property "Description" "SMD Chip Resistor, 10 kohm, ± 1%, 62.5 mW, 0402 [1005 Metric], Thick Film, General Purpose"
			(at 0 0 180)
			(layer "F.Fab")
			(hide yes)
			(effects
				(font
					(size 1.27 1.27)
					(thickness 0.15)
				)
			)
		)
		(property "Author" "Antmicro"
			(at 454.2 308.4 0)
			(layer "B.Fab")
			(hide yes)
			(effects
				(font
					(size 1 1)
					(thickness 0.15)
				)
				(justify mirror)
			)
		)
		(property "DNP" "DNP"
			(at 454.2 308.4 0)
			(layer "B.Fab")
			(hide yes)
			(effects
				(font
					(size 1 1)
					(thickness 0.15)
				)
				(justify mirror)
			)
		)
		(property "License" "Apache-2.0"
			(at 454.2 308.4 0)
			(layer "B.Fab")
			(hide yes)
			(effects
				(font
					(size 1 1)
					(thickness 0.15)
				)
				(justify mirror)
			)
		)
		(property "MPN" "CR0402-FX-1002GLF"
			(at 454.2 308.4 0)
			(layer "B.Fab")
			(hide yes)
			(effects
				(font
					(size 1 1)
					(thickness 0.15)
				)
				(justify mirror)
			)
		)
		(property "Manufacturer" "Bourns"
			(at 454.2 308.4 0)
			(layer "B.Fab")
			(hide yes)
			(effects
				(font
					(size 1 1)
					(thickness 0.15)
				)
				(justify mirror)
			)
		)
		(property "Tolerance" "1%"
			(at 454.2 308.4 0)
			(layer "B.Fab")
			(hide yes)
			(effects
				(font
					(size 1 1)
					(thickness 0.15)
				)
				(justify mirror)
			)
		)
		(property "Val" "10k"
			(at 454.2 308.4 0)
			(layer "B.Fab")
			(hide yes)
			(effects
				(font
					(size 1 1)
					(thickness 0.15)
				)
				(justify mirror)
			)
		)
		(property "dnp" ""
			(at 454.2 308.4 0)
			(layer "B.Fab")
			(hide yes)
			(effects
				(font
					(size 1 1)
					(thickness 0.15)
				)
				(justify mirror)
			)
		)
		(property "exclude_from_bom" ""
			(at 454.2 308.4 0)
			(layer "B.Fab")
			(hide yes)
			(effects
				(font
					(size 1 1)
					(thickness 0.15)
				)
				(justify mirror)
			)
		)
		(sheetname "HDMI + Ethernet")
		(sheetfile "hdmi-ethernet.kicad_sch")
		(attr smd exclude_from_bom)
		(fp_rect
			(start -0.925 0.47)
			(end 0.925 -0.47)
			(stroke
				(width 0.05)
				(type default)
			)
			(fill no)
			(layer "B.CrtYd")
		)
		(fp_rect
			(start -0.5 0.25)
			(end 0.5 -0.25)
			(stroke
				(width 0.15)
				(type solid)
			)
			(fill no)
			(layer "B.Fab")
		)
		(pad "1" smd roundrect
			(at -0.48 0 180)
			(size 0.59 0.64)
			(layers "B.Cu" "B.Mask" "B.Paste")
			(roundrect_rratio 0.25)
			(net 846 "/HDMI + Ethernet/ETH_LED_SPD-")
			(pintype "passive")
		)
		(pad "2" smd roundrect
			(at 0.48 0 180)
			(size 0.59 0.64)
			(layers "B.Cu" "B.Mask" "B.Paste")
			(roundrect_rratio 0.25)
			(net 26 "+1V8")
			(pintype "passive")
		)
	)
	(footprint "antmicro-footprints:C_0201"
		(layer "B.Cu")
		(at 193.5 127)
		(descr "Capacitor SMD 0201")
		(tags "capacitor SMD 0201")
		(property "Reference" "C126"
			(at 21.075 -29.15 0)
			(layer "B.SilkS")
			(effects
				(font
					(size 0.7 0.7)
					(thickness 0.15)
				)
				(justify right bottom mirror)
			)
		)
		(property "Value" "C_100n_0201"
			(at 0 -1.4 0)
			(layer "B.Fab")
			(effects
				(font
					(size 0.7 0.7)
					(thickness 0.15)
				)
				(justify right bottom mirror)
			)
		)
		(property "Description" "SMD Multilayer Ceramic Capacitor, 0.1 µF, 6.3 V, 0201 [0603 Metric], ± 10%, X6S, CC Series"
			(at 0 0 0)
			(layer "F.Fab")
			(hide yes)
			(effects
				(font
					(size 1.27 1.27)
					(thickness 0.15)
				)
			)
		)
		(property "Author" "Antmicro"
			(at 0 0 0)
			(layer "B.Fab")
			(hide yes)
			(effects
				(font
					(size 1 1)
					(thickness 0.15)
				)
				(justify mirror)
			)
		)
		(property "Dielectric" ""
			(at 0 0 0)
			(layer "B.Fab")
			(hide yes)
			(effects
				(font
					(size 1 1)
					(thickness 0.15)
				)
				(justify mirror)
			)
		)
		(property "License" "Apache-2.0"
			(at 0 0 0)
			(layer "B.Fab")
			(hide yes)
			(effects
				(font
					(size 1 1)
					(thickness 0.15)
				)
				(justify mirror)
			)
		)
		(property "MPN" "CC0201KRX6S5BB104"
			(at 0 0 0)
			(layer "B.Fab")
			(hide yes)
			(effects
				(font
					(size 1 1)
					(thickness 0.15)
				)
				(justify mirror)
			)
		)
		(property "Manufacturer" "YAGEO"
			(at 0 0 0)
			(layer "B.Fab")
			(hide yes)
			(effects
				(font
					(size 1 1)
					(thickness 0.15)
				)
				(justify mirror)
			)
		)
		(property "Val" "100n"
			(at 0 0 0)
			(layer "B.Fab")
			(hide yes)
			(effects
				(font
					(size 1 1)
					(thickness 0.15)
				)
				(justify mirror)
			)
		)
		(property "Voltage" ""
			(at 0 0 0)
			(layer "B.Fab")
			(hide yes)
			(effects
				(font
					(size 1 1)
					(thickness 0.15)
				)
				(justify mirror)
			)
		)
		(sheetname "FPGA supply")
		(sheetfile "fpga-supply.kicad_sch")
		(attr smd)
		(fp_rect
			(start -0.7 0.35)
			(end 0.7 -0.35)
			(stroke
				(width 0.05)
				(type default)
			)
			(fill no)
			(layer "B.CrtYd")
		)
		(fp_rect
			(start 0.3 -0.15)
			(end -0.301 0.149)
			(stroke
				(width 0.15)
				(type solid)
			)
			(fill no)
			(layer "B.Fab")
		)
		(pad "" smd roundrect
			(at -0.349 0.002)
			(size 0.318 0.36)
			(layers "B.Paste")
			(roundrect_rratio 0.25)
		)
		(pad "" smd roundrect
			(at 0.341 0.002)
			(size 0.318 0.36)
			(layers "B.Paste")
			(roundrect_rratio 0.25)
		)
		(pad "1" smd roundrect
			(at -0.321 0.002)
			(size 0.46 0.4)
			(layers "B.Cu" "B.Mask")
			(roundrect_rratio 0.25)
			(net 1 "GND")
			(pintype "passive")
		)
		(pad "2" smd roundrect
			(at 0.32 0.002)
			(size 0.46 0.4)
			(layers "B.Cu" "B.Mask")
			(roundrect_rratio 0.25)
			(net 650 "+1V0")
			(pintype "passive")
		)
	)
	(footprint "antmicro-footprints:C_0402_1005Metric"
		(layer "B.Cu")
		(at 208.5 116 -90)
		(descr "Capacitor SMD 0402")
		(tags "capacitor SMD 0402")
		(property "Reference" "C47"
			(at -1.1 -1.275 90)
			(layer "B.SilkS")
			(effects
				(font
					(size 0.7 0.7)
					(thickness 0.15)
				)
				(justify left bottom mirror)
			)
		)
		(property "Value" "C_100n_0402"
			(at 0 -1.169 90)
			(layer "B.Fab")
			(effects
				(font
					(size 0.7 0.7)
					(thickness 0.15)
				)
				(justify left bottom mirror)
			)
		)
		(property "Description" "SMD Multilayer Ceramic Capacitor, 0.1 µF, 50 V, 0402 [1005 Metric], ± 10%, X5R, GRM Series"
			(at 0 0 270)
			(layer "F.Fab")
			(hide yes)
			(effects
				(font
					(size 1.27 1.27)
					(thickness 0.15)
				)
			)
		)
		(property "Author" "Antmicro"
			(at 92.5 324.5 0)
			(layer "B.Fab")
			(hide yes)
			(effects
				(font
					(size 1 1)
					(thickness 0.15)
				)
				(justify mirror)
			)
		)
		(property "Dielectric" "X5R"
			(at 92.5 324.5 0)
			(layer "B.Fab")
			(hide yes)
			(effects
				(font
					(size 1 1)
					(thickness 0.15)
				)
				(justify mirror)
			)
		)
		(property "License" "Apache-2.0"
			(at 92.5 324.5 0)
			(layer "B.Fab")
			(hide yes)
			(effects
				(font
					(size 1 1)
					(thickness 0.15)
				)
				(justify mirror)
			)
		)
		(property "MPN" "GRM155R61H104KE14D"
			(at 92.5 324.5 0)
			(layer "B.Fab")
			(hide yes)
			(effects
				(font
					(size 1 1)
					(thickness 0.15)
				)
				(justify mirror)
			)
		)
		(property "Manufacturer" "Murata"
			(at 92.5 324.5 0)
			(layer "B.Fab")
			(hide yes)
			(effects
				(font
					(size 1 1)
					(thickness 0.15)
				)
				(justify mirror)
			)
		)
		(property "Val" "100n"
			(at 92.5 324.5 0)
			(layer "B.Fab")
			(hide yes)
			(effects
				(font
					(size 1 1)
					(thickness 0.15)
				)
				(justify mirror)
			)
		)
		(property "Voltage" "50V"
			(at 92.5 324.5 0)
			(layer "B.Fab")
			(hide yes)
			(effects
				(font
					(size 1 1)
					(thickness 0.15)
				)
				(justify mirror)
			)
		)
		(sheetname "FPGA Bank 16 & 17")
		(sheetfile "fpga-bank-16-17.kicad_sch")
		(attr smd)
		(fp_rect
			(start -0.925 0.47)
			(end 0.925 -0.47)
			(stroke
				(width 0.05)
				(type default)
			)
			(fill no)
			(layer "B.CrtYd")
		)
		(fp_line
			(start -0.494 0.25)
			(end 0.504 0.25)
			(stroke
				(width 0.15)
				(type solid)
			)
			(layer "B.Fab")
		)
		(fp_line
			(start 0.504 0.25)
			(end 0.504 -0.248)
			(stroke
				(width 0.15)
				(type solid)
			)
			(layer "B.Fab")
		)
		(fp_line
			(start -0.494 -0.248)
			(end -0.494 0.25)
			(stroke
				(width 0.15)
				(type solid)
			)
			(layer "B.Fab")
		)
		(fp_line
			(start 0.504 -0.248)
			(end -0.494 -0.248)
			(stroke
				(width 0.15)
				(type solid)
			)
			(layer "B.Fab")
		)
		(pad "1" smd roundrect
			(at -0.48 0 270)
			(size 0.59 0.64)
			(layers "B.Cu" "B.Mask" "B.Paste")
			(roundrect_rratio 0.25)
			(net 1 "GND")
			(pintype "passive")
		)
		(pad "2" smd roundrect
			(at 0.48 0 270)
			(size 0.59 0.64)
			(layers "B.Cu" "B.Mask" "B.Paste")
			(roundrect_rratio 0.25)
			(net 3 "VCC_USR_B")
			(pintype "passive")
		)
	)
	(footprint "antmicro-footprints:R_0402_1005Metric"
		(layer "B.Cu")
		(at 252.101 179.05 90)
		(descr "Resistor SMD 0402")
		(tags "resistor SMD 0402")
		(property "Reference" "R48"
			(at -0.775 0.374 270)
			(layer "B.SilkS")
			(effects
				(font
					(size 0.7 0.7)
					(thickness 0.15)
				)
				(justify left bottom mirror)
			)
		)
		(property "Value" "R_49k9_0402"
			(at 0 -1.4 270)
			(layer "B.Fab")
			(effects
				(font
					(size 0.7 0.7)
					(thickness 0.15)
				)
				(justify left bottom mirror)
			)
		)
		(property "Description" "SMD Chip Resistor, 49.9 kohm, ± 1%, 63 mW, 0402 [1005 Metric], Thick Film, General Purpose"
			(at 0 0 90)
			(layer "F.Fab")
			(hide yes)
			(effects
				(font
					(size 1.27 1.27)
					(thickness 0.15)
				)
			)
		)
		(property "Author" "Antmicro"
			(at 431.151 -73.051 0)
			(layer "B.Fab")
			(hide yes)
			(effects
				(font
					(size 1 1)
					(thickness 0.15)
				)
				(justify mirror)
			)
		)
		(property "License" "Apache-2.0"
			(at 431.151 -73.051 0)
			(layer "B.Fab")
			(hide yes)
			(effects
				(font
					(size 1 1)
					(thickness 0.15)
				)
				(justify mirror)
			)
		)
		(property "MPN" "CR0402-FX-4992GLF"
			(at 431.151 -73.051 0)
			(layer "B.Fab")
			(hide yes)
			(effects
				(font
					(size 1 1)
					(thickness 0.15)
				)
				(justify mirror)
			)
		)
		(property "Manufacturer" "Bourns"
			(at 431.151 -73.051 0)
			(layer "B.Fab")
			(hide yes)
			(effects
				(font
					(size 1 1)
					(thickness 0.15)
				)
				(justify mirror)
			)
		)
		(property "Tolerance" "1%"
			(at 431.151 -73.051 0)
			(layer "B.Fab")
			(hide yes)
			(effects
				(font
					(size 1 1)
					(thickness 0.15)
				)
				(justify mirror)
			)
		)
		(property "Val" "49k9"
			(at 431.151 -73.051 0)
			(layer "B.Fab")
			(hide yes)
			(effects
				(font
					(size 1 1)
					(thickness 0.15)
				)
				(justify mirror)
			)
		)
		(sheetname "Power supply")
		(sheetfile "power-supply.kicad_sch")
		(attr smd)
		(fp_rect
			(start -0.925 0.47)
			(end 0.925 -0.47)
			(stroke
				(width 0.05)
				(type default)
			)
			(fill no)
			(layer "B.CrtYd")
		)
		(fp_rect
			(start -0.5 0.25)
			(end 0.5 -0.25)
			(stroke
				(width 0.15)
				(type solid)
			)
			(fill no)
			(layer "B.Fab")
		)
		(pad "1" smd roundrect
			(at -0.48 0 90)
			(size 0.59 0.64)
			(layers "B.Cu" "B.Mask" "B.Paste")
			(roundrect_rratio 0.25)
			(net 697 "/Power supply/VSS")
			(pintype "passive")
		)
		(pad "2" smd roundrect
			(at 0.48 0 90)
			(size 0.59 0.64)
			(layers "B.Cu" "B.Mask" "B.Paste")
			(roundrect_rratio 0.25)
			(net 882 "/Power supply/REF")
			(pintype "passive")
		)
	)
	(footprint "antmicro-footprints:R_Array_4x0201_Panasonic_EXB18V"
		(layer "B.Cu")
		(at 164.199999 146.199999 180)
		(property "Reference" "R16"
			(at 6.699999 -6.125001 0)
			(layer "B.SilkS")
			(effects
				(font
					(size 0.7 0.7)
					(thickness 0.15)
				)
				(justify right bottom mirror)
			)
		)
		(property "Value" "4x39R_0201_array"
			(at -1.1 -1.8 0)
			(layer "B.Fab")
			(effects
				(font
					(size 0.7 0.7)
					(thickness 0.15)
				)
				(justify left bottom mirror)
			)
		)
		(property "Description" "Fixed Network Resistor, 39 ohm, Isolated, 4 Resistors, 0502 [1406 Metric], Flat, ± 5%"
			(at 0 0 180)
			(layer "F.Fab")
			(hide yes)
			(effects
				(font
					(size 1.27 1.27)
					(thickness 0.15)
				)
			)
		)
		(property "Author" "Antmicro"
			(at 328.399998 292.399998 0)
			(layer "B.Fab")
			(hide yes)
			(effects
				(font
					(size 1 1)
					(thickness 0.15)
				)
				(justify mirror)
			)
		)
		(property "License" "Apache-2.0"
			(at 328.399998 292.399998 0)
			(layer "B.Fab")
			(hide yes)
			(effects
				(font
					(size 1 1)
					(thickness 0.15)
				)
				(justify mirror)
			)
		)
		(property "MPN" "EXB-18V390JX"
			(at 328.399998 292.399998 0)
			(layer "B.Fab")
			(hide yes)
			(effects
				(font
					(size 1 1)
					(thickness 0.15)
				)
				(justify mirror)
			)
		)
		(property "Manufacturer" "Panasonic"
			(at 328.399998 292.399998 0)
			(layer "B.Fab")
			(hide yes)
			(effects
				(font
					(size 1 1)
					(thickness 0.15)
				)
				(justify mirror)
			)
		)
		(property "Val" "4x39R_0201"
			(at 328.399998 292.399998 0)
			(layer "B.Fab")
			(hide yes)
			(effects
				(font
					(size 1 1)
					(thickness 0.15)
				)
				(justify mirror)
			)
		)
		(sheetname "DRAM + SRAM")
		(sheetfile "ram.kicad_sch")
		(attr smd)
		(fp_line
			(start 0.8 0.45)
			(end 0.8 -0.45)
			(stroke
				(width 0.12)
				(type solid)
			)
			(layer "B.SilkS")
		)
		(fp_line
			(start -0.8 0.45)
			(end -0.8 -0.45)
			(stroke
				(width 0.12)
				(type solid)
			)
			(layer "B.SilkS")
		)
		(fp_rect
			(start -0.898 0.66)
			(end 0.898 -0.65)
			(stroke
				(width 0.05)
				(type solid)
			)
			(fill no)
			(layer "B.CrtYd")
		)
		(pad "1" smd roundrect
			(at -0.6 -0.298 180)
			(size 0.2 0.4)
			(layers "B.Cu" "B.Mask" "B.Paste")
			(roundrect_rratio 0.25)
			(net 542 "/DRAM + SRAM/DDR.A11")
			(pinfunction "R1.1")
			(pintype "passive")
		)
		(pad "2" smd roundrect
			(at -0.202 -0.298 180)
			(size 0.2 0.4)
			(layers "B.Cu" "B.Mask" "B.Paste")
			(roundrect_rratio 0.25)
			(net 537 "/DRAM + SRAM/DDR.A6")
			(pinfunction "R2.1")
			(pintype "passive")
		)
		(pad "3" smd roundrect
			(at 0.2 -0.298 180)
			(size 0.2 0.4)
			(layers "B.Cu" "B.Mask" "B.Paste")
			(roundrect_rratio 0.25)
			(net 545 "/DRAM + SRAM/DDR.A14")
			(pinfunction "R3.1")
			(pintype "passive")
		)
		(pad "4" smd roundrect
			(at 0.598 -0.298 180)
			(size 0.2 0.4)
			(layers "B.Cu" "B.Mask" "B.Paste")
			(roundrect_rratio 0.25)
			(net 539 "/DRAM + SRAM/DDR.A8")
			(pinfunction "R4.1")
			(pintype "passive")
		)
		(pad "5" smd roundrect
			(at 0.598 0.3 180)
			(size 0.2 0.4)
			(layers "B.Cu" "B.Mask" "B.Paste")
			(roundrect_rratio 0.25)
			(net 7 "+0V675_VTT")
			(pinfunction "R4.2")
			(pintype "passive")
		)
		(pad "6" smd roundrect
			(at 0.2 0.3 180)
			(size 0.2 0.4)
			(layers "B.Cu" "B.Mask" "B.Paste")
			(roundrect_rratio 0.25)
			(net 7 "+0V675_VTT")
			(pinfunction "R3.2")
			(pintype "passive")
		)
		(pad "7" smd roundrect
			(at -0.202 0.3 180)
			(size 0.2 0.4)
			(layers "B.Cu" "B.Mask" "B.Paste")
			(roundrect_rratio 0.25)
			(net 7 "+0V675_VTT")
			(pinfunction "R2.2")
			(pintype "passive")
		)
		(pad "8" smd roundrect
			(at -0.6 0.3 180)
			(size 0.2 0.4)
			(layers "B.Cu" "B.Mask" "B.Paste")
			(roundrect_rratio 0.25)
			(net 7 "+0V675_VTT")
			(pinfunction "R1.2")
			(pintype "passive")
		)
	)
	(footprint "antmicro-footprints:C_0201"
		(layer "B.Cu")
		(at 191 116 -45)
		(descr "Capacitor SMD 0201")
		(tags "capacitor SMD 0201")
		(property "Reference" "C57"
			(at 1.202082 1.166726 315)
			(unlocked yes)
			(layer "B.SilkS")
			(effects
				(font
					(size 0.7 0.7)
					(thickness 0.15)
				)
				(justify left bottom mirror)
			)
		)
		(property "Value" "C_4u7_0201"
			(at 0 -1.399999 135)
			(layer "B.Fab")
			(effects
				(font
					(size 0.7 0.7)
					(thickness 0.15)
				)
				(justify left bottom mirror)
			)
		)
		(property "Description" "SMD Multilayer Ceramic Capacitor, 4.7 µF, 6.3 V, 0201 [0603 Metric], ± 20%, X5R, GRM Series"
			(at 0 0 315)
			(layer "F.Fab")
			(hide yes)
			(effects
				(font
					(size 1.27 1.27)
					(thickness 0.15)
				)
			)
		)
		(property "Author" "Antmicro"
			(at -26.081781 169.033008 0)
			(layer "B.Fab")
			(hide yes)
			(effects
				(font
					(size 1 1)
					(thickness 0.15)
				)
				(justify mirror)
			)
		)
		(property "Dielectric" ""
			(at -26.081781 169.033008 0)
			(layer "B.Fab")
			(hide yes)
			(effects
				(font
					(size 1 1)
					(thickness 0.15)
				)
				(justify mirror)
			)
		)
		(property "License" "Apache-2.0"
			(at -26.081781 169.033008 0)
			(layer "B.Fab")
			(hide yes)
			(effects
				(font
					(size 1 1)
					(thickness 0.15)
				)
				(justify mirror)
			)
		)
		(property "MPN" "GRM035R60J475ME15D"
			(at -26.081781 169.033008 0)
			(layer "B.Fab")
			(hide yes)
			(effects
				(font
					(size 1 1)
					(thickness 0.15)
				)
				(justify mirror)
			)
		)
		(property "Manufacturer" "Murata"
			(at -26.081781 169.033008 0)
			(layer "B.Fab")
			(hide yes)
			(effects
				(font
					(size 1 1)
					(thickness 0.15)
				)
				(justify mirror)
			)
		)
		(property "Val" "4u7"
			(at -26.081781 169.033008 0)
			(layer "B.Fab")
			(hide yes)
			(effects
				(font
					(size 1 1)
					(thickness 0.15)
				)
				(justify mirror)
			)
		)
		(property "Voltage" ""
			(at -26.081781 169.033008 0)
			(layer "B.Fab")
			(hide yes)
			(effects
				(font
					(size 1 1)
					(thickness 0.15)
				)
				(justify mirror)
			)
		)
		(sheetname "FPGA supply")
		(sheetfile "fpga-supply.kicad_sch")
		(attr smd)
		(fp_poly
			(pts
				(xy -0.7 0.35) (xy 0.7 0.35) (xy 0.7 -0.35) (xy -0.7 -0.35)
			)
			(stroke
				(width 0.05)
				(type default)
			)
			(fill no)
			(layer "B.CrtYd")
		)
		(fp_poly
			(pts
				(xy 0.3 -0.15) (xy -0.301 -0.15) (xy -0.301 0.149) (xy 0.3 0.149)
			)
			(stroke
				(width 0.15)
				(type solid)
			)
			(fill no)
			(layer "B.Fab")
		)
		(pad "" smd roundrect
			(at -0.349 0.002 315)
			(size 0.318 0.36)
			(layers "B.Paste")
			(roundrect_rratio 0.25)
		)
		(pad "" smd roundrect
			(at 0.341 0.002 315)
			(size 0.318 0.36)
			(layers "B.Paste")
			(roundrect_rratio 0.25)
		)
		(pad "1" smd roundrect
			(at -0.321 0.002 315)
			(size 0.46 0.4)
			(layers "B.Cu" "B.Mask")
			(roundrect_rratio 0.25)
			(net 1 "GND")
			(pintype "passive")
		)
		(pad "2" smd roundrect
			(at 0.32 0.002 315)
			(size 0.46 0.4)
			(layers "B.Cu" "B.Mask")
			(roundrect_rratio 0.25)
			(net 6 "+1V0_MGTAVCC")
			(pintype "passive")
		)
	)
	(footprint "antmicro-footprints:C_0402_1005Metric"
		(layer "B.Cu")
		(at 234.381 111.12 -90)
		(descr "Capacitor SMD 0402")
		(tags "capacitor SMD 0402")
		(property "Reference" "C212"
			(at -1.47 0.506 90)
			(layer "B.SilkS")
			(effects
				(font
					(size 0.7 0.7)
					(thickness 0.15)
				)
				(justify left bottom mirror)
			)
		)
		(property "Value" "C_100n_0402"
			(at 0 -1.4 90)
			(layer "B.Fab")
			(effects
				(font
					(size 0.7 0.7)
					(thickness 0.15)
				)
				(justify left bottom mirror)
			)
		)
		(property "Description" "SMD Multilayer Ceramic Capacitor, 0.1 µF, 50 V, 0402 [1005 Metric], ± 10%, X5R, GRM Series"
			(at 0 0 270)
			(layer "F.Fab")
			(hide yes)
			(effects
				(font
					(size 1.27 1.27)
					(thickness 0.15)
				)
			)
		)
		(property "Author" "Antmicro"
			(at 123.261 345.501 0)
			(layer "B.Fab")
			(hide yes)
			(effects
				(font
					(size 1 1)
					(thickness 0.15)
				)
				(justify mirror)
			)
		)
		(property "Dielectric" "X5R"
			(at 123.261 345.501 0)
			(layer "B.Fab")
			(hide yes)
			(effects
				(font
					(size 1 1)
					(thickness 0.15)
				)
				(justify mirror)
			)
		)
		(property "License" "Apache-2.0"
			(at 123.261 345.501 0)
			(layer "B.Fab")
			(hide yes)
			(effects
				(font
					(size 1 1)
					(thickness 0.15)
				)
				(justify mirror)
			)
		)
		(property "MPN" "GRM155R61H104KE14D"
			(at 123.261 345.501 0)
			(layer "B.Fab")
			(hide yes)
			(effects
				(font
					(size 1 1)
					(thickness 0.15)
				)
				(justify mirror)
			)
		)
		(property "Manufacturer" "Murata"
			(at 123.261 345.501 0)
			(layer "B.Fab")
			(hide yes)
			(effects
				(font
					(size 1 1)
					(thickness 0.15)
				)
				(justify mirror)
			)
		)
		(property "Val" "100n"
			(at 123.261 345.501 0)
			(layer "B.Fab")
			(hide yes)
			(effects
				(font
					(size 1 1)
					(thickness 0.15)
				)
				(justify mirror)
			)
		)
		(property "Voltage" "50V"
			(at 123.261 345.501 0)
			(layer "B.Fab")
			(hide yes)
			(effects
				(font
					(size 1 1)
					(thickness 0.15)
				)
				(justify mirror)
			)
		)
		(sheetname "SPI Flash + SD Card")
		(sheetfile "spi-flash.kicad_sch")
		(attr smd)
		(fp_rect
			(start -0.925 0.47)
			(end 0.925 -0.47)
			(stroke
				(width 0.05)
				(type default)
			)
			(fill no)
			(layer "B.CrtYd")
		)
		(fp_line
			(start -0.494 0.25)
			(end 0.504 0.25)
			(stroke
				(width 0.15)
				(type solid)
			)
			(layer "B.Fab")
		)
		(fp_line
			(start 0.504 0.25)
			(end 0.504 -0.248)
			(stroke
				(width 0.15)
				(type solid)
			)
			(layer "B.Fab")
		)
		(fp_line
			(start -0.494 -0.248)
			(end -0.494 0.25)
			(stroke
				(width 0.15)
				(type solid)
			)
			(layer "B.Fab")
		)
		(fp_line
			(start 0.504 -0.248)
			(end -0.494 -0.248)
			(stroke
				(width 0.15)
				(type solid)
			)
			(layer "B.Fab")
		)
		(pad "1" smd roundrect
			(at -0.48 0 270)
			(size 0.59 0.64)
			(layers "B.Cu" "B.Mask" "B.Paste")
			(roundrect_rratio 0.25)
			(net 1 "GND")
			(pintype "passive")
		)
		(pad "2" smd roundrect
			(at 0.48 0 270)
			(size 0.59 0.64)
			(layers "B.Cu" "B.Mask" "B.Paste")
			(roundrect_rratio 0.25)
			(net 3 "VCC_USR_B")
			(pintype "passive")
		)
	)
	(footprint "antmicro-footprints:NetTie-2_SMD_Pad0.127mm"
		(layer "B.Cu")
		(at 190.090001 112.88 180)
		(descr "Net tie, 2 pin, 0.127mm  SMD pads")
		(tags "net tie")
		(property "Reference" "NT34"
			(at -0.128 1.345 0)
			(layer "B.SilkS")
			(hide yes)
			(effects
				(font
					(size 0.7 0.7)
					(thickness 0.15)
				)
				(justify left bottom mirror)
			)
		)
		(property "Value" "Net-Tie_2"
			(at 0 -1.199 0)
			(layer "B.Fab")
			(effects
				(font
					(size 0.7 0.7)
					(thickness 0.15)
				)
				(justify left bottom mirror)
			)
		)
		(property "Description" "Net tie, 2 pins"
			(at 0 0 180)
			(layer "F.Fab")
			(hide yes)
			(effects
				(font
					(size 1.27 1.27)
					(thickness 0.15)
				)
			)
		)
		(property "Author" "Antmicro"
			(at 380.180002 225.76 0)
			(layer "B.Fab")
			(hide yes)
			(effects
				(font
					(size 1 1)
					(thickness 0.15)
				)
				(justify mirror)
			)
		)
		(property "License" "Apache-2.0"
			(at 380.180002 225.76 0)
			(layer "B.Fab")
			(hide yes)
			(effects
				(font
					(size 1 1)
					(thickness 0.15)
				)
				(justify mirror)
			)
		)
		(property "MPN" ""
			(at 380.180002 225.76 0)
			(layer "B.Fab")
			(hide yes)
			(effects
				(font
					(size 1 1)
					(thickness 0.15)
				)
				(justify mirror)
			)
		)
		(property "Manufacturer" ""
			(at 380.180002 225.76 0)
			(layer "B.Fab")
			(hide yes)
			(effects
				(font
					(size 1 1)
					(thickness 0.15)
				)
				(justify mirror)
			)
		)
		(sheetname "DC-DC Converters")
		(sheetfile "dc-dc.kicad_sch")
		(attr exclude_from_pos_files)
		(net_tie_pad_groups "1, 2")
		(fp_poly
			(pts
				(xy -0.0635 0.0635) (xy 0.0625 0.0635) (xy 0.0625 -0.0635) (xy -0.0635 -0.0635)
			)
			(stroke
				(width 0)
				(type solid)
			)
			(fill yes)
			(layer "B.Cu")
		)
		(pad "1" smd roundrect
			(at -0.127 0)
			(size 0.127 0.127)
			(layers "B.Cu")
			(roundrect_rratio 0.5)
			(chamfer_ratio 0)
			(chamfer top_left bottom_left)
			(net 1 "GND")
			(pinfunction "1")
			(pintype "passive")
		)
		(pad "2" smd roundrect
			(at 0.126 0 180)
			(size 0.127 0.127)
			(layers "B.Cu")
			(roundrect_rratio 0.5)
			(chamfer_ratio 0)
			(chamfer top_left bottom_left)
			(net 1222 "/DC-DC Converters/SENSE_1V0_N")
			(pinfunction "2")
			(pintype "passive")
		)
	)
	(footprint "antmicro-footprints:USON-10_2.5x1mm_P0.5mm"
		(layer "B.Cu")
		(at 257.251 107.625 90)
		(descr "USON-10 2.5x1mm_ Pitch 0.5mm")
		(tags "USON-10 2.5x1mm Pitch 0.5mm")
		(property "Reference" "U28"
			(at 0.875 1.024 0)
			(layer "B.SilkS")
			(effects
				(font
					(size 0.7 0.7)
					(thickness 0.15)
				)
				(justify left bottom mirror)
			)
		)
		(property "Value" "TPD4E05U06QDQARQ1"
			(at 0.018 -2.499 270)
			(layer "B.Fab")
			(effects
				(font
					(size 0.7 0.7)
					(thickness 0.15)
				)
				(justify left bottom mirror)
			)
		)
		(property "Description" "ESD protection"
			(at 0 0 90)
			(layer "F.Fab")
			(hide yes)
			(effects
				(font
					(size 1.27 1.27)
					(thickness 0.15)
				)
			)
		)
		(property "Author" "Antmicro"
			(at 364.876 -149.626 0)
			(layer "B.Fab")
			(hide yes)
			(effects
				(font
					(size 1 1)
					(thickness 0.15)
				)
				(justify mirror)
			)
		)
		(property "License" "Apache-2.0"
			(at 364.876 -149.626 0)
			(layer "B.Fab")
			(hide yes)
			(effects
				(font
					(size 1 1)
					(thickness 0.15)
				)
				(justify mirror)
			)
		)
		(property "MPN" "TPD4E05U06QDQARQ1"
			(at 364.876 -149.626 0)
			(layer "B.Fab")
			(hide yes)
			(effects
				(font
					(size 1 1)
					(thickness 0.15)
				)
				(justify mirror)
			)
		)
		(property "Manufacturer" "Texas Instruments"
			(at 364.876 -149.626 0)
			(layer "B.Fab")
			(hide yes)
			(effects
				(font
					(size 1 1)
					(thickness 0.15)
				)
				(justify mirror)
			)
		)
		(sheetname "HDMI + Ethernet")
		(sheetfile "hdmi-ethernet.kicad_sch")
		(attr smd)
		(fp_line
			(start 0.498 -1.398)
			(end -0.5 -1.398)
			(stroke
				(width 0.15)
				(type solid)
			)
			(layer "B.SilkS")
		)
		(fp_line
			(start 0.498 1.401)
			(end -0.5 1.401)
			(stroke
				(width 0.15)
				(type solid)
			)
			(layer "B.SilkS")
		)
		(fp_circle
			(center -0.68 1.27)
			(end -0.63 1.27)
			(stroke
				(width 0.15)
				(type solid)
			)
			(fill yes)
			(layer "B.SilkS")
		)
		(fp_rect
			(start -0.8 1.5)
			(end 0.8 -1.499)
			(stroke
				(width 0.05)
				(type solid)
			)
			(fill no)
			(layer "B.CrtYd")
		)
		(fp_line
			(start -0.5 -1.249)
			(end 0.498 -1.249)
			(stroke
				(width 0.15)
				(type solid)
			)
			(layer "B.Fab")
		)
		(fp_line
			(start -0.5 1)
			(end -0.5 -1.249)
			(stroke
				(width 0.15)
				(type solid)
			)
			(layer "B.Fab")
		)
		(fp_line
			(start 0.498 1.25)
			(end 0.498 -1.249)
			(stroke
				(width 0.15)
				(type solid)
			)
			(layer "B.Fab")
		)
		(fp_line
			(start 0.498 1.25)
			(end -0.25 1.25)
			(stroke
				(width 0.15)
				(type solid)
			)
			(layer "B.Fab")
		)
		(fp_line
			(start -0.25 1.25)
			(end -0.5 1)
			(stroke
				(width 0.15)
				(type solid)
			)
			(layer "B.Fab")
		)
		(pad "1" smd roundrect
			(at -0.387 1 180)
			(size 0.25 0.55)
			(layers "B.Cu" "B.Mask" "B.Paste")
			(roundrect_rratio 0.25)
			(net 867 "/HDMI + Ethernet/HDMI_CONN_D2_P")
			(pintype "passive")
		)
		(pad "2" smd roundrect
			(at -0.387 0.5 180)
			(size 0.25 0.55)
			(layers "B.Cu" "B.Mask" "B.Paste")
			(roundrect_rratio 0.25)
			(net 866 "/HDMI + Ethernet/HDMI_CONN_D2_N")
			(pintype "passive")
		)
		(pad "3" smd roundrect
			(at -0.387 0 180)
			(size 0.4 0.55)
			(layers "B.Cu" "B.Mask" "B.Paste")
			(roundrect_rratio 0.25)
			(net 1 "GND")
			(pintype "power_in")
		)
		(pad "4" smd roundrect
			(at -0.387 -0.498 180)
			(size 0.25 0.55)
			(layers "B.Cu" "B.Mask" "B.Paste")
			(roundrect_rratio 0.25)
			(net 865 "/HDMI + Ethernet/HDMI_CONN_D1_P")
			(pintype "passive")
		)
		(pad "5" smd roundrect
			(at -0.387 -0.998 180)
			(size 0.25 0.55)
			(layers "B.Cu" "B.Mask" "B.Paste")
			(roundrect_rratio 0.25)
			(net 864 "/HDMI + Ethernet/HDMI_CONN_D1_N")
			(pintype "passive")
		)
		(pad "6" smd roundrect
			(at 0.385 -0.998 180)
			(size 0.25 0.55)
			(layers "B.Cu" "B.Mask" "B.Paste")
			(roundrect_rratio 0.25)
			(net 864 "/HDMI + Ethernet/HDMI_CONN_D1_N")
			(pintype "passive")
		)
		(pad "7" smd roundrect
			(at 0.385 -0.498 180)
			(size 0.25 0.55)
			(layers "B.Cu" "B.Mask" "B.Paste")
			(roundrect_rratio 0.25)
			(net 865 "/HDMI + Ethernet/HDMI_CONN_D1_P")
			(pintype "passive")
		)
		(pad "8" smd roundrect
			(at 0.385 0 180)
			(size 0.4 0.55)
			(layers "B.Cu" "B.Mask" "B.Paste")
			(roundrect_rratio 0.25)
			(net 1 "GND")
			(pintype "passive")
		)
		(pad "9" smd roundrect
			(at 0.385 0.5 180)
			(size 0.25 0.55)
			(layers "B.Cu" "B.Mask" "B.Paste")
			(roundrect_rratio 0.25)
			(net 866 "/HDMI + Ethernet/HDMI_CONN_D2_N")
			(pintype "passive")
		)
		(pad "10" smd roundrect
			(at 0.385 1 180)
			(size 0.25 0.55)
			(layers "B.Cu" "B.Mask" "B.Paste")
			(roundrect_rratio 0.25)
			(net 867 "/HDMI + Ethernet/HDMI_CONN_D2_P")
			(pintype "passive")
		)
	)
	(footprint "antmicro-footprints:C_0402_1005Metric"
		(layer "B.Cu")
		(at 214 138.5)
		(descr "Capacitor SMD 0402")
		(tags "capacitor SMD 0402")
		(property "Reference" "C30"
			(at 1.1 -0.45 180)
			(layer "B.SilkS")
			(effects
				(font
					(size 0.7 0.7)
					(thickness 0.15)
				)
				(justify left bottom mirror)
			)
		)
		(property "Value" "C_100n_0402"
			(at 0 -1.169 180)
			(layer "B.Fab")
			(effects
				(font
					(size 0.7 0.7)
					(thickness 0.15)
				)
				(justify left bottom mirror)
			)
		)
		(property "Description" "SMD Multilayer Ceramic Capacitor, 0.1 µF, 50 V, 0402 [1005 Metric], ± 10%, X5R, GRM Series"
			(at 0 0 0)
			(layer "F.Fab")
			(hide yes)
			(effects
				(font
					(size 1.27 1.27)
					(thickness 0.15)
				)
			)
		)
		(property "Author" "Antmicro"
			(at 0 0 0)
			(layer "B.Fab")
			(hide yes)
			(effects
				(font
					(size 1 1)
					(thickness 0.15)
				)
				(justify mirror)
			)
		)
		(property "Dielectric" "X5R"
			(at 0 0 0)
			(layer "B.Fab")
			(hide yes)
			(effects
				(font
					(size 1 1)
					(thickness 0.15)
				)
				(justify mirror)
			)
		)
		(property "License" "Apache-2.0"
			(at 0 0 0)
			(layer "B.Fab")
			(hide yes)
			(effects
				(font
					(size 1 1)
					(thickness 0.15)
				)
				(justify mirror)
			)
		)
		(property "MPN" "GRM155R61H104KE14D"
			(at 0 0 0)
			(layer "B.Fab")
			(hide yes)
			(effects
				(font
					(size 1 1)
					(thickness 0.15)
				)
				(justify mirror)
			)
		)
		(property "Manufacturer" "Murata"
			(at 0 0 0)
			(layer "B.Fab")
			(hide yes)
			(effects
				(font
					(size 1 1)
					(thickness 0.15)
				)
				(justify mirror)
			)
		)
		(property "Val" "100n"
			(at 0 0 0)
			(layer "B.Fab")
			(hide yes)
			(effects
				(font
					(size 1 1)
					(thickness 0.15)
				)
				(justify mirror)
			)
		)
		(property "Voltage" "50V"
			(at 0 0 0)
			(layer "B.Fab")
			(hide yes)
			(effects
				(font
					(size 1 1)
					(thickness 0.15)
				)
				(justify mirror)
			)
		)
		(sheetname "FPGA Bank 12 & 13")
		(sheetfile "fpga-bank-12-13.kicad_sch")
		(attr smd)
		(fp_rect
			(start -0.925 0.47)
			(end 0.925 -0.47)
			(stroke
				(width 0.05)
				(type default)
			)
			(fill no)
			(layer "B.CrtYd")
		)
		(fp_line
			(start -0.494 -0.248)
			(end -0.494 0.25)
			(stroke
				(width 0.15)
				(type solid)
			)
			(layer "B.Fab")
		)
		(fp_line
			(start -0.494 0.25)
			(end 0.504 0.25)
			(stroke
				(width 0.15)
				(type solid)
			)
			(layer "B.Fab")
		)
		(fp_line
			(start 0.504 -0.248)
			(end -0.494 -0.248)
			(stroke
				(width 0.15)
				(type solid)
			)
			(layer "B.Fab")
		)
		(fp_line
			(start 0.504 0.25)
			(end 0.504 -0.248)
			(stroke
				(width 0.15)
				(type solid)
			)
			(layer "B.Fab")
		)
		(pad "1" smd roundrect
			(at -0.48 0)
			(size 0.59 0.64)
			(layers "B.Cu" "B.Mask" "B.Paste")
			(roundrect_rratio 0.25)
			(net 1 "GND")
			(pintype "passive")
		)
		(pad "2" smd roundrect
			(at 0.48 0)
			(size 0.59 0.64)
			(layers "B.Cu" "B.Mask" "B.Paste")
			(roundrect_rratio 0.25)
			(net 24 "+3V3")
			(pintype "passive")
		)
	)
	(footprint "antmicro-footprints:C_0201"
		(layer "B.Cu")
		(at 198.55 131.44)
		(descr "Capacitor SMD 0201")
		(tags "capacitor SMD 0201")
		(property "Reference" "C266"
			(at 23.525 -28.165 0)
			(layer "B.SilkS")
			(effects
				(font
					(size 0.7 0.7)
					(thickness 0.15)
				)
				(justify right bottom mirror)
			)
		)
		(property "Value" "C_100n_0201"
			(at 0 -1.4 0)
			(layer "B.Fab")
			(effects
				(font
					(size 0.7 0.7)
					(thickness 0.15)
				)
				(justify right bottom mirror)
			)
		)
		(property "Description" "SMD Multilayer Ceramic Capacitor, 0.1 µF, 6.3 V, 0201 [0603 Metric], ± 10%, X6S, CC Series"
			(at 0 0 0)
			(layer "F.Fab")
			(hide yes)
			(effects
				(font
					(size 1.27 1.27)
					(thickness 0.15)
				)
			)
		)
		(property "Author" "Antmicro"
			(at 0 0 0)
			(layer "B.Fab")
			(hide yes)
			(effects
				(font
					(size 1 1)
					(thickness 0.15)
				)
				(justify mirror)
			)
		)
		(property "Dielectric" ""
			(at 0 0 0)
			(layer "B.Fab")
			(hide yes)
			(effects
				(font
					(size 1 1)
					(thickness 0.15)
				)
				(justify mirror)
			)
		)
		(property "License" "Apache-2.0"
			(at 0 0 0)
			(layer "B.Fab")
			(hide yes)
			(effects
				(font
					(size 1 1)
					(thickness 0.15)
				)
				(justify mirror)
			)
		)
		(property "MPN" "CC0201KRX6S5BB104"
			(at 0 0 0)
			(layer "B.Fab")
			(hide yes)
			(effects
				(font
					(size 1 1)
					(thickness 0.15)
				)
				(justify mirror)
			)
		)
		(property "Manufacturer" "YAGEO"
			(at 0 0 0)
			(layer "B.Fab")
			(hide yes)
			(effects
				(font
					(size 1 1)
					(thickness 0.15)
				)
				(justify mirror)
			)
		)
		(property "Val" "100n"
			(at 0 0 0)
			(layer "B.Fab")
			(hide yes)
			(effects
				(font
					(size 1 1)
					(thickness 0.15)
				)
				(justify mirror)
			)
		)
		(property "Voltage" ""
			(at 0 0 0)
			(layer "B.Fab")
			(hide yes)
			(effects
				(font
					(size 1 1)
					(thickness 0.15)
				)
				(justify mirror)
			)
		)
		(sheetname "FPGA Config")
		(sheetfile "fpga-config.kicad_sch")
		(attr smd)
		(fp_rect
			(start -0.7 0.35)
			(end 0.7 -0.35)
			(stroke
				(width 0.05)
				(type default)
			)
			(fill no)
			(layer "B.CrtYd")
		)
		(fp_rect
			(start 0.3 -0.15)
			(end -0.301 0.149)
			(stroke
				(width 0.15)
				(type solid)
			)
			(fill no)
			(layer "B.Fab")
		)
		(pad "" smd roundrect
			(at -0.349 0.002)
			(size 0.318 0.36)
			(layers "B.Paste")
			(roundrect_rratio 0.25)
		)
		(pad "" smd roundrect
			(at 0.341 0.002)
			(size 0.318 0.36)
			(layers "B.Paste")
			(roundrect_rratio 0.25)
		)
		(pad "1" smd roundrect
			(at -0.321 0.002)
			(size 0.46 0.4)
			(layers "B.Cu" "B.Mask")
			(roundrect_rratio 0.25)
			(net 870 "VREFN")
			(pintype "passive")
		)
		(pad "2" smd roundrect
			(at 0.32 0.002)
			(size 0.46 0.4)
			(layers "B.Cu" "B.Mask")
			(roundrect_rratio 0.25)
			(net 649 "VREFP")
			(pintype "passive")
		)
	)
	(footprint "antmicro-footprints:C_0603_1608Metric"
		(layer "B.Cu")
		(at 195.5 130)
		(descr "Capacitor SMD 0603")
		(tags "capacitor 0603")
		(property "Reference" "C51"
			(at 21.975 -28.05 0)
			(layer "B.SilkS")
			(effects
				(font
					(size 0.7 0.7)
					(thickness 0.15)
				)
				(justify right bottom mirror)
			)
		)
		(property "Value" "C_47u_0603"
			(at 0 -1.6 0)
			(layer "B.Fab")
			(effects
				(font
					(size 0.7 0.7)
					(thickness 0.15)
				)
				(justify right bottom mirror)
			)
		)
		(property "Description" "SMD Multilayer Ceramic Capacitor, 47 µF, 6.3 V, 0603 [1608 Metric], ± 20%, X5R, GRM Series"
			(at 0 0 0)
			(layer "F.Fab")
			(hide yes)
			(effects
				(font
					(size 1.27 1.27)
					(thickness 0.15)
				)
			)
		)
		(property "Author" "Antmicro"
			(at 0 0 0)
			(layer "B.Fab")
			(hide yes)
			(effects
				(font
					(size 1 1)
					(thickness 0.15)
				)
				(justify mirror)
			)
		)
		(property "Dielectric" ""
			(at 0 0 0)
			(layer "B.Fab")
			(hide yes)
			(effects
				(font
					(size 1 1)
					(thickness 0.15)
				)
				(justify mirror)
			)
		)
		(property "License" "Apache-2.0"
			(at 0 0 0)
			(layer "B.Fab")
			(hide yes)
			(effects
				(font
					(size 1 1)
					(thickness 0.15)
				)
				(justify mirror)
			)
		)
		(property "MPN" "GRM188R60J476ME15D"
			(at 0 0 0)
			(layer "B.Fab")
			(hide yes)
			(effects
				(font
					(size 1 1)
					(thickness 0.15)
				)
				(justify mirror)
			)
		)
		(property "Manufacturer" "Murata"
			(at 0 0 0)
			(layer "B.Fab")
			(hide yes)
			(effects
				(font
					(size 1 1)
					(thickness 0.15)
				)
				(justify mirror)
			)
		)
		(property "Val" "47u"
			(at 0 0 0)
			(layer "B.Fab")
			(hide yes)
			(effects
				(font
					(size 1 1)
					(thickness 0.15)
				)
				(justify mirror)
			)
		)
		(property "Voltage" ""
			(at 0 0 0)
			(layer "B.Fab")
			(hide yes)
			(effects
				(font
					(size 1 1)
					(thickness 0.15)
				)
				(justify mirror)
			)
		)
		(sheetname "FPGA supply")
		(sheetfile "fpga-supply.kicad_sch")
		(attr smd)
		(fp_line
			(start -0.15 -0.4)
			(end 0.15 -0.4)
			(stroke
				(width 0.15)
				(type solid)
			)
			(layer "B.SilkS")
		)
		(fp_line
			(start -0.15 0.4)
			(end 0.15 0.4)
			(stroke
				(width 0.15)
				(type solid)
			)
			(layer "B.SilkS")
		)
		(fp_rect
			(start -1.25 0.65)
			(end 1.25 -0.65)
			(stroke
				(width 0.05)
				(type solid)
			)
			(fill no)
			(layer "B.CrtYd")
		)
		(fp_rect
			(start -0.8 0.4)
			(end 0.8 -0.4)
			(stroke
				(width 0.15)
				(type solid)
			)
			(fill no)
			(layer "B.Fab")
		)
		(pad "1" smd roundrect
			(at -0.7 0)
			(size 0.8 1)
			(layers "B.Cu" "B.Mask" "B.Paste")
			(roundrect_rratio 0.2)
			(net 1 "GND")
			(pintype "passive")
		)
		(pad "2" smd roundrect
			(at 0.7 0)
			(size 0.8 1)
			(layers "B.Cu" "B.Mask" "B.Paste")
			(roundrect_rratio 0.2)
			(net 26 "+1V8")
			(pintype "passive")
		)
	)
	(footprint "antmicro-footprints:R_0402_1005Metric"
		(layer "B.Cu")
		(at 261.5 95.8)
		(descr "Resistor SMD 0402")
		(tags "resistor SMD 0402")
		(property "Reference" "R129"
			(at 1.375 1.25 180)
			(layer "B.SilkS")
			(effects
				(font
					(size 0.7 0.7)
					(thickness 0.15)
				)
				(justify left bottom mirror)
			)
		)
		(property "Value" "R_1k_0402"
			(at 0 -1.4 180)
			(layer "B.Fab")
			(effects
				(font
					(size 0.7 0.7)
					(thickness 0.15)
				)
				(justify left bottom mirror)
			)
		)
		(property "Description" "SMD Chip Resistor, 1 kohm, ± 1%, 63 mW, 0402 [1005 Metric], Thick Film, General Purpose"
			(at 0 0 0)
			(layer "F.Fab")
			(hide yes)
			(effects
				(font
					(size 1.27 1.27)
					(thickness 0.15)
				)
			)
		)
		(property "Author" "Antmicro"
			(at 0 0 0)
			(layer "B.Fab")
			(hide yes)
			(effects
				(font
					(size 1 1)
					(thickness 0.15)
				)
				(justify mirror)
			)
		)
		(property "License" "Apache-2.0"
			(at 0 0 0)
			(layer "B.Fab")
			(hide yes)
			(effects
				(font
					(size 1 1)
					(thickness 0.15)
				)
				(justify mirror)
			)
		)
		(property "MPN" "CR0402-FX-1001GLF"
			(at 0 0 0)
			(layer "B.Fab")
			(hide yes)
			(effects
				(font
					(size 1 1)
					(thickness 0.15)
				)
				(justify mirror)
			)
		)
		(property "Manufacturer" "Bourns"
			(at 0 0 0)
			(layer "B.Fab")
			(hide yes)
			(effects
				(font
					(size 1 1)
					(thickness 0.15)
				)
				(justify mirror)
			)
		)
		(property "Tolerance" "1%"
			(at 0 0 0)
			(layer "B.Fab")
			(hide yes)
			(effects
				(font
					(size 1 1)
					(thickness 0.15)
				)
				(justify mirror)
			)
		)
		(property "Val" "1k"
			(at 0 0 0)
			(layer "B.Fab")
			(hide yes)
			(effects
				(font
					(size 1 1)
					(thickness 0.15)
				)
				(justify mirror)
			)
		)
		(sheetname "User GPIO + LED + button + DIP switch")
		(sheetfile "user-gpio.kicad_sch")
		(attr smd)
		(fp_rect
			(start -0.925 0.47)
			(end 0.925 -0.47)
			(stroke
				(width 0.05)
				(type default)
			)
			(fill no)
			(layer "B.CrtYd")
		)
		(fp_rect
			(start -0.5 0.25)
			(end 0.5 -0.25)
			(stroke
				(width 0.15)
				(type solid)
			)
			(fill no)
			(layer "B.Fab")
		)
		(pad "1" smd roundrect
			(at -0.48 0)
			(size 0.59 0.64)
			(layers "B.Cu" "B.Mask" "B.Paste")
			(roundrect_rratio 0.25)
			(net 24 "+3V3")
			(pintype "passive")
		)
		(pad "2" smd roundrect
			(at 0.48 0)
			(size 0.59 0.64)
			(layers "B.Cu" "B.Mask" "B.Paste")
			(roundrect_rratio 0.25)
			(net 785 "Net-(D23-A)")
			(pintype "passive")
		)
	)
	(footprint "antmicro-footprints:C_0402_1005Metric"
		(layer "B.Cu")
		(at 194.5 143 90)
		(descr "Capacitor SMD 0402")
		(tags "capacitor SMD 0402")
		(property "Reference" "C90"
			(at 1.075 -0.425 270)
			(layer "B.SilkS")
			(effects
				(font
					(size 0.7 0.7)
					(thickness 0.15)
				)
				(justify left bottom mirror)
			)
		)
		(property "Value" "C_100n_0402"
			(at 0 -1.169 270)
			(layer "B.Fab")
			(effects
				(font
					(size 0.7 0.7)
					(thickness 0.15)
				)
				(justify left bottom mirror)
			)
		)
		(property "Description" "SMD Multilayer Ceramic Capacitor, 0.1 µF, 50 V, 0402 [1005 Metric], ± 10%, X5R, GRM Series"
			(at 0 0 90)
			(layer "F.Fab")
			(hide yes)
			(effects
				(font
					(size 1.27 1.27)
					(thickness 0.15)
				)
			)
		)
		(property "Author" "Antmicro"
			(at 337.5 -51.5 0)
			(layer "B.Fab")
			(hide yes)
			(effects
				(font
					(size 1 1)
					(thickness 0.15)
				)
				(justify mirror)
			)
		)
		(property "Dielectric" "X5R"
			(at 337.5 -51.5 0)
			(layer "B.Fab")
			(hide yes)
			(effects
				(font
					(size 1 1)
					(thickness 0.15)
				)
				(justify mirror)
			)
		)
		(property "License" "Apache-2.0"
			(at 337.5 -51.5 0)
			(layer "B.Fab")
			(hide yes)
			(effects
				(font
					(size 1 1)
					(thickness 0.15)
				)
				(justify mirror)
			)
		)
		(property "MPN" "GRM155R61H104KE14D"
			(at 337.5 -51.5 0)
			(layer "B.Fab")
			(hide yes)
			(effects
				(font
					(size 1 1)
					(thickness 0.15)
				)
				(justify mirror)
			)
		)
		(property "Manufacturer" "Murata"
			(at 337.5 -51.5 0)
			(layer "B.Fab")
			(hide yes)
			(effects
				(font
					(size 1 1)
					(thickness 0.15)
				)
				(justify mirror)
			)
		)
		(property "Val" "100n"
			(at 337.5 -51.5 0)
			(layer "B.Fab")
			(hide yes)
			(effects
				(font
					(size 1 1)
					(thickness 0.15)
				)
				(justify mirror)
			)
		)
		(property "Voltage" "50V"
			(at 337.5 -51.5 0)
			(layer "B.Fab")
			(hide yes)
			(effects
				(font
					(size 1 1)
					(thickness 0.15)
				)
				(justify mirror)
			)
		)
		(sheetname "FPGA Bank 33 & 34")
		(sheetfile "fpga-bank-33-34.kicad_sch")
		(attr smd)
		(fp_rect
			(start -0.925 0.47)
			(end 0.925 -0.47)
			(stroke
				(width 0.05)
				(type default)
			)
			(fill no)
			(layer "B.CrtYd")
		)
		(fp_line
			(start 0.504 -0.248)
			(end -0.494 -0.248)
			(stroke
				(width 0.15)
				(type solid)
			)
			(layer "B.Fab")
		)
		(fp_line
			(start -0.494 -0.248)
			(end -0.494 0.25)
			(stroke
				(width 0.15)
				(type solid)
			)
			(layer "B.Fab")
		)
		(fp_line
			(start 0.504 0.25)
			(end 0.504 -0.248)
			(stroke
				(width 0.15)
				(type solid)
			)
			(layer "B.Fab")
		)
		(fp_line
			(start -0.494 0.25)
			(end 0.504 0.25)
			(stroke
				(width 0.15)
				(type solid)
			)
			(layer "B.Fab")
		)
		(pad "1" smd roundrect
			(at -0.48 0 90)
			(size 0.59 0.64)
			(layers "B.Cu" "B.Mask" "B.Paste")
			(roundrect_rratio 0.25)
			(net 1 "GND")
			(pintype "passive")
		)
		(pad "2" smd roundrect
			(at 0.48 0 90)
			(size 0.59 0.64)
			(layers "B.Cu" "B.Mask" "B.Paste")
			(roundrect_rratio 0.25)
			(net 26 "+1V8")
			(pintype "passive")
		)
	)
	(footprint "antmicro-footprints:C_0402_1005Metric"
		(layer "B.Cu")
		(at 171.15 141.7 180)
		(descr "Capacitor SMD 0402")
		(tags "capacitor SMD 0402")
		(property "Reference" "C186"
			(at -0.975 0.475 0)
			(layer "B.SilkS")
			(effects
				(font
					(size 0.7 0.7)
					(thickness 0.15)
				)
				(justify left bottom mirror)
			)
		)
		(property "Value" "C_100n_0402"
			(at 0 -1.169 0)
			(layer "B.Fab")
			(effects
				(font
					(size 0.7 0.7)
					(thickness 0.15)
				)
				(justify left bottom mirror)
			)
		)
		(property "Description" "SMD Multilayer Ceramic Capacitor, 0.1 µF, 50 V, 0402 [1005 Metric], ± 10%, X5R, GRM Series"
			(at 0 0 180)
			(layer "F.Fab")
			(hide yes)
			(effects
				(font
					(size 1.27 1.27)
					(thickness 0.15)
				)
			)
		)
		(property "Author" "Antmicro"
			(at 342.3 283.4 0)
			(layer "B.Fab")
			(hide yes)
			(effects
				(font
					(size 1 1)
					(thickness 0.15)
				)
				(justify mirror)
			)
		)
		(property "Dielectric" "X5R"
			(at 342.3 283.4 0)
			(layer "B.Fab")
			(hide yes)
			(effects
				(font
					(size 1 1)
					(thickness 0.15)
				)
				(justify mirror)
			)
		)
		(property "License" "Apache-2.0"
			(at 342.3 283.4 0)
			(layer "B.Fab")
			(hide yes)
			(effects
				(font
					(size 1 1)
					(thickness 0.15)
				)
				(justify mirror)
			)
		)
		(property "MPN" "GRM155R61H104KE14D"
			(at 342.3 283.4 0)
			(layer "B.Fab")
			(hide yes)
			(effects
				(font
					(size 1 1)
					(thickness 0.15)
				)
				(justify mirror)
			)
		)
		(property "Manufacturer" "Murata"
			(at 342.3 283.4 0)
			(layer "B.Fab")
			(hide yes)
			(effects
				(font
					(size 1 1)
					(thickness 0.15)
				)
				(justify mirror)
			)
		)
		(property "Val" "100n"
			(at 342.3 283.4 0)
			(layer "B.Fab")
			(hide yes)
			(effects
				(font
					(size 1 1)
					(thickness 0.15)
				)
				(justify mirror)
			)
		)
		(property "Voltage" "50V"
			(at 342.3 283.4 0)
			(layer "B.Fab")
			(hide yes)
			(effects
				(font
					(size 1 1)
					(thickness 0.15)
				)
				(justify mirror)
			)
		)
		(sheetname "DRAM + SRAM")
		(sheetfile "ram.kicad_sch")
		(attr smd)
		(fp_rect
			(start -0.925 0.47)
			(end 0.925 -0.47)
			(stroke
				(width 0.05)
				(type default)
			)
			(fill no)
			(layer "B.CrtYd")
		)
		(fp_line
			(start 0.504 0.25)
			(end 0.504 -0.248)
			(stroke
				(width 0.15)
				(type solid)
			)
			(layer "B.Fab")
		)
		(fp_line
			(start 0.504 -0.248)
			(end -0.494 -0.248)
			(stroke
				(width 0.15)
				(type solid)
			)
			(layer "B.Fab")
		)
		(fp_line
			(start -0.494 0.25)
			(end 0.504 0.25)
			(stroke
				(width 0.15)
				(type solid)
			)
			(layer "B.Fab")
		)
		(fp_line
			(start -0.494 -0.248)
			(end -0.494 0.25)
			(stroke
				(width 0.15)
				(type solid)
			)
			(layer "B.Fab")
		)
		(pad "1" smd roundrect
			(at -0.48 0 180)
			(size 0.59 0.64)
			(layers "B.Cu" "B.Mask" "B.Paste")
			(roundrect_rratio 0.25)
			(net 1 "GND")
			(pintype "passive")
		)
		(pad "2" smd roundrect
			(at 0.48 0 180)
			(size 0.59 0.64)
			(layers "B.Cu" "B.Mask" "B.Paste")
			(roundrect_rratio 0.25)
			(net 11 "+0V675_VREF")
			(pintype "passive")
		)
	)
	(footprint "antmicro-footprints:R_0402_1005Metric"
		(layer "B.Cu")
		(at 159 185.9 -90)
		(descr "Resistor SMD 0402")
		(tags "resistor SMD 0402")
		(property "Reference" "R294"
			(at -3.6 -0.4 90)
			(layer "B.SilkS")
			(effects
				(font
					(size 0.7 0.7)
					(thickness 0.15)
				)
				(justify left bottom mirror)
			)
		)
		(property "Value" "R_47k_0402"
			(at 0 -1.4 90)
			(layer "B.Fab")
			(effects
				(font
					(size 0.7 0.7)
					(thickness 0.15)
				)
				(justify left bottom mirror)
			)
		)
		(property "Description" "SMD Chip Resistor, 47 kohm, ± 1%, 62.5 mW, 0402 [1005 Metric], Thick Film, General Purpose"
			(at 0 0 270)
			(layer "F.Fab")
			(hide yes)
			(effects
				(font
					(size 1.27 1.27)
					(thickness 0.15)
				)
			)
		)
		(property "Author" "Antmicro"
			(at -26.9 344.9 0)
			(layer "B.Fab")
			(hide yes)
			(effects
				(font
					(size 1 1)
					(thickness 0.15)
				)
				(justify mirror)
			)
		)
		(property "License" "Apache-2.0"
			(at -26.9 344.9 0)
			(layer "B.Fab")
			(hide yes)
			(effects
				(font
					(size 1 1)
					(thickness 0.15)
				)
				(justify mirror)
			)
		)
		(property "MPN" "CR0402-FX-4702GLF"
			(at -26.9 344.9 0)
			(layer "B.Fab")
			(hide yes)
			(effects
				(font
					(size 1 1)
					(thickness 0.15)
				)
				(justify mirror)
			)
		)
		(property "Manufacturer" "Bourns"
			(at -26.9 344.9 0)
			(layer "B.Fab")
			(hide yes)
			(effects
				(font
					(size 1 1)
					(thickness 0.15)
				)
				(justify mirror)
			)
		)
		(property "Tolerance" "1%"
			(at -26.9 344.9 0)
			(layer "B.Fab")
			(hide yes)
			(effects
				(font
					(size 1 1)
					(thickness 0.15)
				)
				(justify mirror)
			)
		)
		(property "Val" "47k"
			(at -26.9 344.9 0)
			(layer "B.Fab")
			(hide yes)
			(effects
				(font
					(size 1 1)
					(thickness 0.15)
				)
				(justify mirror)
			)
		)
		(sheetname "DC-DC Converters")
		(sheetfile "dc-dc.kicad_sch")
		(attr smd)
		(fp_rect
			(start -0.925 0.47)
			(end 0.925 -0.47)
			(stroke
				(width 0.05)
				(type default)
			)
			(fill no)
			(layer "B.CrtYd")
		)
		(fp_rect
			(start -0.5 0.25)
			(end 0.5 -0.25)
			(stroke
				(width 0.15)
				(type solid)
			)
			(fill no)
			(layer "B.Fab")
		)
		(pad "1" smd roundrect
			(at -0.48 0 270)
			(size 0.59 0.64)
			(layers "B.Cu" "B.Mask" "B.Paste")
			(roundrect_rratio 0.25)
			(net 1340 "/SUP_MCU.SW_STATE")
			(pintype "passive")
		)
		(pad "2" smd roundrect
			(at 0.48 0 270)
			(size 0.59 0.64)
			(layers "B.Cu" "B.Mask" "B.Paste")
			(roundrect_rratio 0.25)
			(net 701 "/DC-DC Converters/PB_CTRL_OUT")
			(pintype "passive")
		)
	)
	(footprint "antmicro-footprints:NetTie-2_SMD_Pad0.127mm"
		(layer "B.Cu")
		(at 252.501 148.4 -90)
		(descr "Net tie, 2 pin, 0.127mm  SMD pads")
		(tags "net tie")
		(property "Reference" "NT10"
			(at -0.128 1.345 90)
			(layer "B.SilkS")
			(hide yes)
			(effects
				(font
					(size 0.7 0.7)
					(thickness 0.15)
				)
				(justify left bottom mirror)
			)
		)
		(property "Value" "Net-Tie_2"
			(at 0 -1.199 90)
			(layer "B.Fab")
			(effects
				(font
					(size 0.7 0.7)
					(thickness 0.15)
				)
				(justify left bottom mirror)
			)
		)
		(property "Description" "Net tie, 2 pins"
			(at 0 0 270)
			(layer "F.Fab")
			(hide yes)
			(effects
				(font
					(size 1.27 1.27)
					(thickness 0.15)
				)
			)
		)
		(property "Author" "Antmicro"
			(at 104.101 400.901 0)
			(layer "B.Fab")
			(hide yes)
			(effects
				(font
					(size 1 1)
					(thickness 0.15)
				)
				(justify mirror)
			)
		)
		(property "License" "Apache-2.0"
			(at 104.101 400.901 0)
			(layer "B.Fab")
			(hide yes)
			(effects
				(font
					(size 1 1)
					(thickness 0.15)
				)
				(justify mirror)
			)
		)
		(property "MPN" ""
			(at 104.101 400.901 0)
			(layer "B.Fab")
			(hide yes)
			(effects
				(font
					(size 1 1)
					(thickness 0.15)
				)
				(justify mirror)
			)
		)
		(property "Manufacturer" ""
			(at 104.101 400.901 0)
			(layer "B.Fab")
			(hide yes)
			(effects
				(font
					(size 1 1)
					(thickness 0.15)
				)
				(justify mirror)
			)
		)
		(sheetname "FPGA Bank 14 & 15")
		(sheetfile "fpga-bank-14-15.kicad_sch")
		(attr exclude_from_pos_files)
		(net_tie_pad_groups "1, 2")
		(fp_poly
			(pts
				(xy -0.0635 0.0635) (xy 0.0625 0.0635) (xy 0.0625 -0.0635) (xy -0.0635 -0.0635)
			)
			(stroke
				(width 0)
				(type solid)
			)
			(fill yes)
			(layer "B.Cu")
		)
		(pad "1" smd roundrect
			(at -0.127 0 90)
			(size 0.127 0.127)
			(layers "B.Cu")
			(roundrect_rratio 0.5)
			(chamfer_ratio 0)
			(chamfer top_left bottom_left)
			(net 1295 "/USB_SPI.MOSI")
			(pinfunction "1")
			(pintype "passive")
		)
		(pad "2" smd roundrect
			(at 0.126 0 270)
			(size 0.127 0.127)
			(layers "B.Cu")
			(roundrect_rratio 0.5)
			(chamfer_ratio 0)
			(chamfer top_left bottom_left)
			(net 1321 "/SUP_MCU.MOSI")
			(pinfunction "2")
			(pintype "passive")
		)
	)
	(footprint "antmicro-footprints:QFN-2L_1.6x1x0.55mm"
		(layer "B.Cu")
		(at 264.75 93.2 90)
		(property "Reference" "D36"
			(at -2.45 -0.8 90)
			(layer "B.SilkS")
			(effects
				(font
					(size 0.7 0.7)
					(thickness 0.15)
				)
				(justify right bottom mirror)
			)
		)
		(property "Value" "ESDA25P35-1U1M"
			(at 0 -1.7 90)
			(layer "B.Fab")
			(effects
				(font
					(size 0.7 0.7)
					(thickness 0.15)
				)
				(justify right bottom mirror)
			)
		)
		(property "Description" "Unidirectional TVS, 30 kV, QFN-2L, 22 V, 195 pF"
			(at 0 0 90)
			(layer "F.Fab")
			(hide yes)
			(effects
				(font
					(size 1.27 1.27)
					(thickness 0.15)
				)
			)
		)
		(property "Author" "Antmicro"
			(at 357.95 -171.55 0)
			(layer "B.Fab")
			(hide yes)
			(effects
				(font
					(size 1 1)
					(thickness 0.15)
				)
				(justify mirror)
			)
		)
		(property "License" "Apache-2.0"
			(at 357.95 -171.55 0)
			(layer "B.Fab")
			(hide yes)
			(effects
				(font
					(size 1 1)
					(thickness 0.15)
				)
				(justify mirror)
			)
		)
		(property "MPN" "ESDA25P35-1U1M"
			(at 357.95 -171.55 0)
			(layer "B.Fab")
			(hide yes)
			(effects
				(font
					(size 1 1)
					(thickness 0.15)
				)
				(justify mirror)
			)
		)
		(property "Manufacturer" "STMicroelectronics"
			(at 357.95 -171.55 0)
			(layer "B.Fab")
			(hide yes)
			(effects
				(font
					(size 1 1)
					(thickness 0.15)
				)
				(justify mirror)
			)
		)
		(property "Public" "False"
			(at 357.95 -171.55 0)
			(layer "B.Fab")
			(hide yes)
			(effects
				(font
					(size 1 1)
					(thickness 0.15)
				)
				(justify mirror)
			)
		)
		(sheetname "User GPIO + LED + button + DIP switch")
		(sheetfile "user-gpio.kicad_sch")
		(attr smd)
		(fp_line
			(start 0.27 -0.3)
			(end -0.27 -0.3)
			(stroke
				(width 0.15)
				(type solid)
			)
			(layer "B.SilkS")
		)
		(fp_line
			(start 0.27 0.3)
			(end -0.27 0.3)
			(stroke
				(width 0.15)
				(type solid)
			)
			(layer "B.SilkS")
		)
		(fp_line
			(start -1.2 0.4)
			(end -1.2 -0.4)
			(stroke
				(width 0.15)
				(type solid)
			)
			(layer "B.SilkS")
		)
		(fp_rect
			(start 1.25 -0.65)
			(end -1.25 0.65)
			(stroke
				(width 0.05)
				(type solid)
			)
			(fill no)
			(layer "B.CrtYd")
		)
		(fp_line
			(start 0.201 -0.2)
			(end 0.201 0)
			(stroke
				(width 0.15)
				(type solid)
			)
			(layer "B.Fab")
		)
		(fp_line
			(start -0.199 -0.2)
			(end -0.199 -0.1)
			(stroke
				(width 0.15)
				(type solid)
			)
			(layer "B.Fab")
		)
		(fp_line
			(start 0.599 0)
			(end 0.201 0)
			(stroke
				(width 0.15)
				(type solid)
			)
			(layer "B.Fab")
		)
		(fp_line
			(start 0.201 0)
			(end 0.201 0.202)
			(stroke
				(width 0.15)
				(type solid)
			)
			(layer "B.Fab")
		)
		(fp_line
			(start -0.101 0)
			(end 0.201 -0.2)
			(stroke
				(width 0.15)
				(type solid)
			)
			(layer "B.Fab")
		)
		(fp_line
			(start -0.199 0)
			(end -0.597 0)
			(stroke
				(width 0.15)
				(type solid)
			)
			(layer "B.Fab")
		)
		(fp_line
			(start 0.201 0.202)
			(end -0.101 0)
			(stroke
				(width 0.15)
				(type solid)
			)
			(layer "B.Fab")
		)
		(fp_line
			(start -0.199 0.202)
			(end -0.199 -0.1)
			(stroke
				(width 0.15)
				(type solid)
			)
			(layer "B.Fab")
		)
		(fp_rect
			(start 0.848 -0.4)
			(end -0.85 0.402)
			(stroke
				(width 0.15)
				(type solid)
			)
			(fill no)
			(layer "B.Fab")
		)
		(pad "1" smd roundrect
			(at -0.7 0 270)
			(size 0.8 1)
			(layers "B.Cu" "B.Mask" "B.Paste")
			(roundrect_rratio 0.2)
			(net 1232 "/USER_IO.BUTTON3")
			(pinfunction "C")
			(pintype "passive")
		)
		(pad "2" smd roundrect
			(at 0.7 0 270)
			(size 0.8 1)
			(layers "B.Cu" "B.Mask" "B.Paste")
			(roundrect_rratio 0.2)
			(net 1 "GND")
			(pinfunction "A")
			(pintype "passive")
		)
	)
	(footprint "antmicro-footprints:R_0402_1005Metric"
		(layer "B.Cu")
		(at 191.8 133.3 180)
		(descr "Resistor SMD 0402")
		(tags "resistor SMD 0402")
		(property "Reference" "R1"
			(at -22.375 28.1 0)
			(layer "B.SilkS")
			(effects
				(font
					(size 0.7 0.7)
					(thickness 0.15)
				)
				(justify left bottom mirror)
			)
		)
		(property "Value" "R_100R_0402"
			(at 0 -1.4 0)
			(layer "B.Fab")
			(effects
				(font
					(size 0.7 0.7)
					(thickness 0.15)
				)
				(justify left bottom mirror)
			)
		)
		(property "Description" "SMD Chip Resistor, 100 ohm, ± 1%, 62.5 mW, 0402 [1005 Metric], Thick Film, General Purpose"
			(at 0 0 180)
			(layer "F.Fab")
			(hide yes)
			(effects
				(font
					(size 1.27 1.27)
					(thickness 0.15)
				)
			)
		)
		(property "Author" "Antmicro"
			(at 383.6 266.6 0)
			(layer "B.Fab")
			(hide yes)
			(effects
				(font
					(size 1 1)
					(thickness 0.15)
				)
				(justify mirror)
			)
		)
		(property "License" "Apache-2.0"
			(at 383.6 266.6 0)
			(layer "B.Fab")
			(hide yes)
			(effects
				(font
					(size 1 1)
					(thickness 0.15)
				)
				(justify mirror)
			)
		)
		(property "MPN" "CR0402-FX-1000GLF"
			(at 383.6 266.6 0)
			(layer "B.Fab")
			(hide yes)
			(effects
				(font
					(size 1 1)
					(thickness 0.15)
				)
				(justify mirror)
			)
		)
		(property "Manufacturer" "Bourns"
			(at 383.6 266.6 0)
			(layer "B.Fab")
			(hide yes)
			(effects
				(font
					(size 1 1)
					(thickness 0.15)
				)
				(justify mirror)
			)
		)
		(property "Tolerance" "1%"
			(at 383.6 266.6 0)
			(layer "B.Fab")
			(hide yes)
			(effects
				(font
					(size 1 1)
					(thickness 0.15)
				)
				(justify mirror)
			)
		)
		(property "Val" "100R"
			(at 383.6 266.6 0)
			(layer "B.Fab")
			(hide yes)
			(effects
				(font
					(size 1 1)
					(thickness 0.15)
				)
				(justify mirror)
			)
		)
		(sheetname "FPGA supply")
		(sheetfile "fpga-supply.kicad_sch")
		(attr smd)
		(fp_rect
			(start -0.925 0.47)
			(end 0.925 -0.47)
			(stroke
				(width 0.05)
				(type default)
			)
			(fill no)
			(layer "B.CrtYd")
		)
		(fp_rect
			(start -0.5 0.25)
			(end 0.5 -0.25)
			(stroke
				(width 0.15)
				(type solid)
			)
			(fill no)
			(layer "B.Fab")
		)
		(pad "1" smd roundrect
			(at -0.48 0 180)
			(size 0.59 0.64)
			(layers "B.Cu" "B.Mask" "B.Paste")
			(roundrect_rratio 0.25)
			(net 494 "/FPGA supply/MGTRREF")
			(pintype "passive")
		)
		(pad "2" smd roundrect
			(at 0.48 0 180)
			(size 0.59 0.64)
			(layers "B.Cu" "B.Mask" "B.Paste")
			(roundrect_rratio 0.25)
			(net 8 "+1V2_MGTAVTT")
			(pintype "passive")
		)
	)
	(footprint "antmicro-footprints:C_0603_1608Metric"
		(layer "B.Cu")
		(at 200 144.4 90)
		(descr "Capacitor SMD 0603")
		(tags "capacitor 0603")
		(property "Reference" "C49"
			(at -1.09 1.42 90)
			(layer "B.SilkS")
			(effects
				(font
					(size 0.7 0.7)
					(thickness 0.15)
				)
				(justify right bottom mirror)
			)
		)
		(property "Value" "C_47u_0603"
			(at 0 -1.6 90)
			(layer "B.Fab")
			(effects
				(font
					(size 0.7 0.7)
					(thickness 0.15)
				)
				(justify right bottom mirror)
			)
		)
		(property "Description" "SMD Multilayer Ceramic Capacitor, 47 µF, 6.3 V, 0603 [1608 Metric], ± 20%, X5R, GRM Series"
			(at 0 0 90)
			(layer "F.Fab")
			(hide yes)
			(effects
				(font
					(size 1.27 1.27)
					(thickness 0.15)
				)
			)
		)
		(property "Author" "Antmicro"
			(at 344.4 -55.6 0)
			(layer "B.Fab")
			(hide yes)
			(effects
				(font
					(size 1 1)
					(thickness 0.15)
				)
				(justify mirror)
			)
		)
		(property "Dielectric" ""
			(at 344.4 -55.6 0)
			(layer "B.Fab")
			(hide yes)
			(effects
				(font
					(size 1 1)
					(thickness 0.15)
				)
				(justify mirror)
			)
		)
		(property "License" "Apache-2.0"
			(at 344.4 -55.6 0)
			(layer "B.Fab")
			(hide yes)
			(effects
				(font
					(size 1 1)
					(thickness 0.15)
				)
				(justify mirror)
			)
		)
		(property "MPN" "GRM188R60J476ME15D"
			(at 344.4 -55.6 0)
			(layer "B.Fab")
			(hide yes)
			(effects
				(font
					(size 1 1)
					(thickness 0.15)
				)
				(justify mirror)
			)
		)
		(property "Manufacturer" "Murata"
			(at 344.4 -55.6 0)
			(layer "B.Fab")
			(hide yes)
			(effects
				(font
					(size 1 1)
					(thickness 0.15)
				)
				(justify mirror)
			)
		)
		(property "Val" "47u"
			(at 344.4 -55.6 0)
			(layer "B.Fab")
			(hide yes)
			(effects
				(font
					(size 1 1)
					(thickness 0.15)
				)
				(justify mirror)
			)
		)
		(property "Voltage" ""
			(at 344.4 -55.6 0)
			(layer "B.Fab")
			(hide yes)
			(effects
				(font
					(size 1 1)
					(thickness 0.15)
				)
				(justify mirror)
			)
		)
		(sheetname "FPGA supply")
		(sheetfile "fpga-supply.kicad_sch")
		(attr smd)
		(fp_line
			(start -0.15 -0.4)
			(end 0.15 -0.4)
			(stroke
				(width 0.15)
				(type solid)
			)
			(layer "B.SilkS")
		)
		(fp_line
			(start -0.15 0.4)
			(end 0.15 0.4)
			(stroke
				(width 0.15)
				(type solid)
			)
			(layer "B.SilkS")
		)
		(fp_rect
			(start -1.25 0.65)
			(end 1.25 -0.65)
			(stroke
				(width 0.05)
				(type solid)
			)
			(fill no)
			(layer "B.CrtYd")
		)
		(fp_rect
			(start -0.8 0.4)
			(end 0.8 -0.4)
			(stroke
				(width 0.15)
				(type solid)
			)
			(fill no)
			(layer "B.Fab")
		)
		(pad "1" smd roundrect
			(at -0.7 0 90)
			(size 0.8 1)
			(layers "B.Cu" "B.Mask" "B.Paste")
			(roundrect_rratio 0.2)
			(net 1 "GND")
			(pintype "passive")
		)
		(pad "2" smd roundrect
			(at 0.7 0 90)
			(size 0.8 1)
			(layers "B.Cu" "B.Mask" "B.Paste")
			(roundrect_rratio 0.2)
			(net 26 "+1V8")
			(pintype "passive")
		)
	)
	(footprint "antmicro-footprints:R_0402_1005Metric"
		(layer "B.Cu")
		(at 265.901 145.35)
		(descr "Resistor SMD 0402")
		(tags "resistor SMD 0402")
		(property "Reference" "R57"
			(at -3.851 0.325 180)
			(layer "B.SilkS")
			(effects
				(font
					(size 0.7 0.7)
					(thickness 0.15)
				)
				(justify left bottom mirror)
			)
		)
		(property "Value" "R_1k_0402"
			(at 0 -1.4 180)
			(layer "B.Fab")
			(effects
				(font
					(size 0.7 0.7)
					(thickness 0.15)
				)
				(justify left bottom mirror)
			)
		)
		(property "Description" "SMD Chip Resistor, 1 kohm, ± 1%, 63 mW, 0402 [1005 Metric], Thick Film, General Purpose"
			(at 0 0 0)
			(layer "F.Fab")
			(hide yes)
			(effects
				(font
					(size 1.27 1.27)
					(thickness 0.15)
				)
			)
		)
		(property "Author" "Antmicro"
			(at 0 0 0)
			(layer "B.Fab")
			(hide yes)
			(effects
				(font
					(size 1 1)
					(thickness 0.15)
				)
				(justify mirror)
			)
		)
		(property "License" "Apache-2.0"
			(at 0 0 0)
			(layer "B.Fab")
			(hide yes)
			(effects
				(font
					(size 1 1)
					(thickness 0.15)
				)
				(justify mirror)
			)
		)
		(property "MPN" "CR0402-FX-1001GLF"
			(at 0 0 0)
			(layer "B.Fab")
			(hide yes)
			(effects
				(font
					(size 1 1)
					(thickness 0.15)
				)
				(justify mirror)
			)
		)
		(property "Manufacturer" "Bourns"
			(at 0 0 0)
			(layer "B.Fab")
			(hide yes)
			(effects
				(font
					(size 1 1)
					(thickness 0.15)
				)
				(justify mirror)
			)
		)
		(property "Tolerance" "1%"
			(at 0 0 0)
			(layer "B.Fab")
			(hide yes)
			(effects
				(font
					(size 1 1)
					(thickness 0.15)
				)
				(justify mirror)
			)
		)
		(property "Val" "1k"
			(at 0 0 0)
			(layer "B.Fab")
			(hide yes)
			(effects
				(font
					(size 1 1)
					(thickness 0.15)
				)
				(justify mirror)
			)
		)
		(sheetname "Power supply")
		(sheetfile "power-supply.kicad_sch")
		(attr smd)
		(fp_rect
			(start -0.925 0.47)
			(end 0.925 -0.47)
			(stroke
				(width 0.05)
				(type default)
			)
			(fill no)
			(layer "B.CrtYd")
		)
		(fp_rect
			(start -0.5 0.25)
			(end 0.5 -0.25)
			(stroke
				(width 0.15)
				(type solid)
			)
			(fill no)
			(layer "B.Fab")
		)
		(pad "1" smd roundrect
			(at -0.48 0)
			(size 0.59 0.64)
			(layers "B.Cu" "B.Mask" "B.Paste")
			(roundrect_rratio 0.25)
			(net 700 "/Power supply/USB_PD_VBUS")
			(pintype "passive")
		)
		(pad "2" smd roundrect
			(at 0.48 0)
			(size 0.59 0.64)
			(layers "B.Cu" "B.Mask" "B.Paste")
			(roundrect_rratio 0.25)
			(net 20 "Net-(D13-A)")
			(pintype "passive")
		)
	)
	(footprint "antmicro-footprints:R_0402_1005Metric"
		(layer "B.Cu")
		(at 253.101 179.06 90)
		(descr "Resistor SMD 0402")
		(tags "resistor SMD 0402")
		(property "Reference" "R49"
			(at -0.775 0.374 270)
			(layer "B.SilkS")
			(effects
				(font
					(size 0.7 0.7)
					(thickness 0.15)
				)
				(justify left bottom mirror)
			)
		)
		(property "Value" "R_0R_0402"
			(at 0 -1.4 270)
			(layer "B.Fab")
			(effects
				(font
					(size 0.7 0.7)
					(thickness 0.15)
				)
				(justify left bottom mirror)
			)
		)
		(property "Description" "SMD Chip Resistor, Jumper, 0 ohm, 100 mW, 0402 [1005 Metric], Thick Film, General Purpose"
			(at 0 0 90)
			(layer "F.Fab")
			(hide yes)
			(effects
				(font
					(size 1.27 1.27)
					(thickness 0.15)
				)
			)
		)
		(property "Author" "Antmicro"
			(at 432.161 -74.041 0)
			(layer "B.Fab")
			(hide yes)
			(effects
				(font
					(size 1 1)
					(thickness 0.15)
				)
				(justify mirror)
			)
		)
		(property "Current" "1A"
			(at 432.161 -74.041 0)
			(layer "B.Fab")
			(hide yes)
			(effects
				(font
					(size 1 1)
					(thickness 0.15)
				)
				(justify mirror)
			)
		)
		(property "License" "Apache-2.0"
			(at 432.161 -74.041 0)
			(layer "B.Fab")
			(hide yes)
			(effects
				(font
					(size 1 1)
					(thickness 0.15)
				)
				(justify mirror)
			)
		)
		(property "MPN" "ERJ2GE0R00X"
			(at 432.161 -74.041 0)
			(layer "B.Fab")
			(hide yes)
			(effects
				(font
					(size 1 1)
					(thickness 0.15)
				)
				(justify mirror)
			)
		)
		(property "Manufacturer" "Panasonic"
			(at 432.161 -74.041 0)
			(layer "B.Fab")
			(hide yes)
			(effects
				(font
					(size 1 1)
					(thickness 0.15)
				)
				(justify mirror)
			)
		)
		(property "Tolerance" ""
			(at 432.161 -74.041 0)
			(layer "B.Fab")
			(hide yes)
			(effects
				(font
					(size 1 1)
					(thickness 0.15)
				)
				(justify mirror)
			)
		)
		(property "Val" "0R"
			(at 432.161 -74.041 0)
			(layer "B.Fab")
			(hide yes)
			(effects
				(font
					(size 1 1)
					(thickness 0.15)
				)
				(justify mirror)
			)
		)
		(sheetname "Power supply")
		(sheetfile "power-supply.kicad_sch")
		(attr smd)
		(fp_rect
			(start -0.925 0.47)
			(end 0.925 -0.47)
			(stroke
				(width 0.05)
				(type default)
			)
			(fill no)
			(layer "B.CrtYd")
		)
		(fp_rect
			(start -0.5 0.25)
			(end 0.5 -0.25)
			(stroke
				(width 0.15)
				(type solid)
			)
			(fill no)
			(layer "B.Fab")
		)
		(pad "1" smd roundrect
			(at -0.48 0 90)
			(size 0.59 0.64)
			(layers "B.Cu" "B.Mask" "B.Paste")
			(roundrect_rratio 0.25)
			(net 697 "/Power supply/VSS")
			(pintype "passive")
		)
		(pad "2" smd roundrect
			(at 0.48 0 90)
			(size 0.59 0.64)
			(layers "B.Cu" "B.Mask" "B.Paste")
			(roundrect_rratio 0.25)
			(net 883 "/Power supply/MPS_DUTY")
			(pintype "passive")
		)
	)
	(footprint "antmicro-footprints:C_0201"
		(layer "B.Cu")
		(at 193.125 132.75 90)
		(descr "Capacitor SMD 0201")
		(tags "capacitor SMD 0201")
		(property "Reference" "C110"
			(at 26.575 23.125 90)
			(layer "B.SilkS")
			(effects
				(font
					(size 0.7 0.7)
					(thickness 0.15)
				)
				(justify right bottom mirror)
			)
		)
		(property "Value" "C_4u7_0201"
			(at 0 -1.4 90)
			(layer "B.Fab")
			(effects
				(font
					(size 0.7 0.7)
					(thickness 0.15)
				)
				(justify right bottom mirror)
			)
		)
		(property "Description" "SMD Multilayer Ceramic Capacitor, 4.7 µF, 6.3 V, 0201 [0603 Metric], ± 20%, X5R, GRM Series"
			(at 0 0 90)
			(layer "F.Fab")
			(hide yes)
			(effects
				(font
					(size 1.27 1.27)
					(thickness 0.15)
				)
			)
		)
		(property "Author" "Antmicro"
			(at 325.875 -60.375 0)
			(layer "B.Fab")
			(hide yes)
			(effects
				(font
					(size 1 1)
					(thickness 0.15)
				)
				(justify mirror)
			)
		)
		(property "Dielectric" ""
			(at 325.875 -60.375 0)
			(layer "B.Fab")
			(hide yes)
			(effects
				(font
					(size 1 1)
					(thickness 0.15)
				)
				(justify mirror)
			)
		)
		(property "License" "Apache-2.0"
			(at 325.875 -60.375 0)
			(layer "B.Fab")
			(hide yes)
			(effects
				(font
					(size 1 1)
					(thickness 0.15)
				)
				(justify mirror)
			)
		)
		(property "MPN" "GRM035R60J475ME15D"
			(at 325.875 -60.375 0)
			(layer "B.Fab")
			(hide yes)
			(effects
				(font
					(size 1 1)
					(thickness 0.15)
				)
				(justify mirror)
			)
		)
		(property "Manufacturer" "Murata"
			(at 325.875 -60.375 0)
			(layer "B.Fab")
			(hide yes)
			(effects
				(font
					(size 1 1)
					(thickness 0.15)
				)
				(justify mirror)
			)
		)
		(property "Val" "4u7"
			(at 325.875 -60.375 0)
			(layer "B.Fab")
			(hide yes)
			(effects
				(font
					(size 1 1)
					(thickness 0.15)
				)
				(justify mirror)
			)
		)
		(property "Voltage" ""
			(at 325.875 -60.375 0)
			(layer "B.Fab")
			(hide yes)
			(effects
				(font
					(size 1 1)
					(thickness 0.15)
				)
				(justify mirror)
			)
		)
		(sheetname "FPGA supply")
		(sheetfile "fpga-supply.kicad_sch")
		(attr smd)
		(fp_rect
			(start -0.7 0.35)
			(end 0.7 -0.35)
			(stroke
				(width 0.05)
				(type default)
			)
			(fill no)
			(layer "B.CrtYd")
		)
		(fp_rect
			(start 0.3 -0.15)
			(end -0.301 0.149)
			(stroke
				(width 0.15)
				(type solid)
			)
			(fill no)
			(layer "B.Fab")
		)
		(pad "" smd roundrect
			(at -0.349 0.002 90)
			(size 0.318 0.36)
			(layers "B.Paste")
			(roundrect_rratio 0.25)
		)
		(pad "" smd roundrect
			(at 0.341 0.002 90)
			(size 0.318 0.36)
			(layers "B.Paste")
			(roundrect_rratio 0.25)
		)
		(pad "1" smd roundrect
			(at -0.321 0.002 90)
			(size 0.46 0.4)
			(layers "B.Cu" "B.Mask")
			(roundrect_rratio 0.25)
			(net 1 "GND")
			(pintype "passive")
		)
		(pad "2" smd roundrect
			(at 0.32 0.002 90)
			(size 0.46 0.4)
			(layers "B.Cu" "B.Mask")
			(roundrect_rratio 0.25)
			(net 26 "+1V8")
			(pintype "passive")
		)
	)
	(footprint "antmicro-footprints:C_0603_1608Metric"
		(layer "B.Cu")
		(at 207.65 130 180)
		(descr "Capacitor SMD 0603")
		(tags "capacitor 0603")
		(property "Reference" "C383"
			(at 0.4 -0.5 90)
			(layer "B.SilkS")
			(effects
				(font
					(size 0.7 0.7)
					(thickness 0.15)
				)
				(justify left bottom mirror)
			)
		)
		(property "Value" "C_47u_0603"
			(at 0 -1.6 0)
			(layer "B.Fab")
			(effects
				(font
					(size 0.7 0.7)
					(thickness 0.15)
				)
				(justify left bottom mirror)
			)
		)
		(property "Description" "SMD Multilayer Ceramic Capacitor, 47 µF, 6.3 V, 0603 [1608 Metric], ± 20%, X5R, GRM Series"
			(at 0 0 180)
			(layer "F.Fab")
			(hide yes)
			(effects
				(font
					(size 1.27 1.27)
					(thickness 0.15)
				)
			)
		)
		(property "Author" "Antmicro"
			(at 415.3 260 0)
			(layer "B.Fab")
			(hide yes)
			(effects
				(font
					(size 1 1)
					(thickness 0.15)
				)
				(justify mirror)
			)
		)
		(property "Dielectric" ""
			(at 415.3 260 0)
			(layer "B.Fab")
			(hide yes)
			(effects
				(font
					(size 1 1)
					(thickness 0.15)
				)
				(justify mirror)
			)
		)
		(property "License" "Apache-2.0"
			(at 415.3 260 0)
			(layer "B.Fab")
			(hide yes)
			(effects
				(font
					(size 1 1)
					(thickness 0.15)
				)
				(justify mirror)
			)
		)
		(property "MPN" "GRM188R60J476ME15D"
			(at 415.3 260 0)
			(layer "B.Fab")
			(hide yes)
			(effects
				(font
					(size 1 1)
					(thickness 0.15)
				)
				(justify mirror)
			)
		)
		(property "Manufacturer" "Murata"
			(at 415.3 260 0)
			(layer "B.Fab")
			(hide yes)
			(effects
				(font
					(size 1 1)
					(thickness 0.15)
				)
				(justify mirror)
			)
		)
		(property "Val" "47u"
			(at 415.3 260 0)
			(layer "B.Fab")
			(hide yes)
			(effects
				(font
					(size 1 1)
					(thickness 0.15)
				)
				(justify mirror)
			)
		)
		(property "Voltage" ""
			(at 415.3 260 0)
			(layer "B.Fab")
			(hide yes)
			(effects
				(font
					(size 1 1)
					(thickness 0.15)
				)
				(justify mirror)
			)
		)
		(sheetname "FPGA supply")
		(sheetfile "fpga-supply.kicad_sch")
		(attr smd)
		(fp_line
			(start -0.15 0.4)
			(end 0.15 0.4)
			(stroke
				(width 0.15)
				(type solid)
			)
			(layer "B.SilkS")
		)
		(fp_line
			(start -0.15 -0.4)
			(end 0.15 -0.4)
			(stroke
				(width 0.15)
				(type solid)
			)
			(layer "B.SilkS")
		)
		(fp_rect
			(start -1.25 0.65)
			(end 1.25 -0.65)
			(stroke
				(width 0.05)
				(type solid)
			)
			(fill no)
			(layer "B.CrtYd")
		)
		(fp_rect
			(start -0.8 0.4)
			(end 0.8 -0.4)
			(stroke
				(width 0.15)
				(type solid)
			)
			(fill no)
			(layer "B.Fab")
		)
		(pad "1" smd roundrect
			(at -0.7 0 180)
			(size 0.8 1)
			(layers "B.Cu" "B.Mask" "B.Paste")
			(roundrect_rratio 0.2)
			(net 1 "GND")
			(pintype "passive")
		)
		(pad "2" smd roundrect
			(at 0.7 0 180)
			(size 0.8 1)
			(layers "B.Cu" "B.Mask" "B.Paste")
			(roundrect_rratio 0.2)
			(net 650 "+1V0")
			(pintype "passive")
		)
	)
	(footprint "antmicro-footprints:R_0402_1005Metric"
		(layer "B.Cu")
		(at 198.991252 99.25 -90)
		(descr "Resistor SMD 0402")
		(tags "resistor SMD 0402")
		(property "Reference" "R206"
			(at 3.8 -0.433748 90)
			(layer "B.SilkS")
			(effects
				(font
					(size 0.7 0.7)
					(thickness 0.15)
				)
				(justify left bottom mirror)
			)
		)
		(property "Value" "R_10k_0402"
			(at 0 -1.4 90)
			(layer "B.Fab")
			(effects
				(font
					(size 0.7 0.7)
					(thickness 0.15)
				)
				(justify left bottom mirror)
			)
		)
		(property "Description" "SMD Chip Resistor, 10 kohm, ± 1%, 62.5 mW, 0402 [1005 Metric], Thick Film, General Purpose"
			(at 0 0 270)
			(layer "F.Fab")
			(hide yes)
			(effects
				(font
					(size 1.27 1.27)
					(thickness 0.15)
				)
			)
		)
		(property "Author" "Antmicro"
			(at 99.741252 298.241252 0)
			(layer "B.Fab")
			(hide yes)
			(effects
				(font
					(size 1 1)
					(thickness 0.15)
				)
				(justify mirror)
			)
		)
		(property "License" "Apache-2.0"
			(at 99.741252 298.241252 0)
			(layer "B.Fab")
			(hide yes)
			(effects
				(font
					(size 1 1)
					(thickness 0.15)
				)
				(justify mirror)
			)
		)
		(property "MPN" "CR0402-FX-1002GLF"
			(at 99.741252 298.241252 0)
			(layer "B.Fab")
			(hide yes)
			(effects
				(font
					(size 1 1)
					(thickness 0.15)
				)
				(justify mirror)
			)
		)
		(property "Manufacturer" "Bourns"
			(at 99.741252 298.241252 0)
			(layer "B.Fab")
			(hide yes)
			(effects
				(font
					(size 1 1)
					(thickness 0.15)
				)
				(justify mirror)
			)
		)
		(property "Tolerance" "1%"
			(at 99.741252 298.241252 0)
			(layer "B.Fab")
			(hide yes)
			(effects
				(font
					(size 1 1)
					(thickness 0.15)
				)
				(justify mirror)
			)
		)
		(property "Val" "10k"
			(at 99.741252 298.241252 0)
			(layer "B.Fab")
			(hide yes)
			(effects
				(font
					(size 1 1)
					(thickness 0.15)
				)
				(justify mirror)
			)
		)
		(sheetname "HDMI + Ethernet")
		(sheetfile "hdmi-ethernet.kicad_sch")
		(attr smd)
		(fp_rect
			(start -0.925 0.47)
			(end 0.925 -0.47)
			(stroke
				(width 0.05)
				(type default)
			)
			(fill no)
			(layer "B.CrtYd")
		)
		(fp_rect
			(start -0.5 0.25)
			(end 0.5 -0.25)
			(stroke
				(width 0.15)
				(type solid)
			)
			(fill no)
			(layer "B.Fab")
		)
		(pad "1" smd roundrect
			(at -0.48 0 270)
			(size 0.59 0.64)
			(layers "B.Cu" "B.Mask" "B.Paste")
			(roundrect_rratio 0.25)
			(net 508 "/FPGA Bank 16 & 17/GBE_RGMII.~{INT}")
			(pintype "passive")
		)
		(pad "2" smd roundrect
			(at 0.48 0 270)
			(size 0.59 0.64)
			(layers "B.Cu" "B.Mask" "B.Paste")
			(roundrect_rratio 0.25)
			(net 24 "+3V3")
			(pintype "passive")
		)
	)
	(footprint "antmicro-footprints:C_0402_1005Metric"
		(layer "B.Cu")
		(at 211 144.5 180)
		(descr "Capacitor SMD 0402")
		(tags "capacitor SMD 0402")
		(property "Reference" "C12"
			(at -1.15 0.45 0)
			(layer "B.SilkS")
			(effects
				(font
					(size 0.7 0.7)
					(thickness 0.15)
				)
				(justify left bottom mirror)
			)
		)
		(property "Value" "C_100n_0402"
			(at 0 -1.169 0)
			(layer "B.Fab")
			(effects
				(font
					(size 0.7 0.7)
					(thickness 0.15)
				)
				(justify left bottom mirror)
			)
		)
		(property "Description" "SMD Multilayer Ceramic Capacitor, 0.1 µF, 50 V, 0402 [1005 Metric], ± 10%, X5R, GRM Series"
			(at 0 0 180)
			(layer "F.Fab")
			(hide yes)
			(effects
				(font
					(size 1.27 1.27)
					(thickness 0.15)
				)
			)
		)
		(property "Author" "Antmicro"
			(at 422 289 0)
			(layer "B.Fab")
			(hide yes)
			(effects
				(font
					(size 1 1)
					(thickness 0.15)
				)
				(justify mirror)
			)
		)
		(property "Dielectric" "X5R"
			(at 422 289 0)
			(layer "B.Fab")
			(hide yes)
			(effects
				(font
					(size 1 1)
					(thickness 0.15)
				)
				(justify mirror)
			)
		)
		(property "License" "Apache-2.0"
			(at 422 289 0)
			(layer "B.Fab")
			(hide yes)
			(effects
				(font
					(size 1 1)
					(thickness 0.15)
				)
				(justify mirror)
			)
		)
		(property "MPN" "GRM155R61H104KE14D"
			(at 422 289 0)
			(layer "B.Fab")
			(hide yes)
			(effects
				(font
					(size 1 1)
					(thickness 0.15)
				)
				(justify mirror)
			)
		)
		(property "Manufacturer" "Murata"
			(at 422 289 0)
			(layer "B.Fab")
			(hide yes)
			(effects
				(font
					(size 1 1)
					(thickness 0.15)
				)
				(justify mirror)
			)
		)
		(property "Val" "100n"
			(at 422 289 0)
			(layer "B.Fab")
			(hide yes)
			(effects
				(font
					(size 1 1)
					(thickness 0.15)
				)
				(justify mirror)
			)
		)
		(property "Voltage" "50V"
			(at 422 289 0)
			(layer "B.Fab")
			(hide yes)
			(effects
				(font
					(size 1 1)
					(thickness 0.15)
				)
				(justify mirror)
			)
		)
		(sheetname "FPGA Bank 12 & 13")
		(sheetfile "fpga-bank-12-13.kicad_sch")
		(attr smd)
		(fp_rect
			(start -0.925 0.47)
			(end 0.925 -0.47)
			(stroke
				(width 0.05)
				(type default)
			)
			(fill no)
			(layer "B.CrtYd")
		)
		(fp_line
			(start 0.504 0.25)
			(end 0.504 -0.248)
			(stroke
				(width 0.15)
				(type solid)
			)
			(layer "B.Fab")
		)
		(fp_line
			(start 0.504 -0.248)
			(end -0.494 -0.248)
			(stroke
				(width 0.15)
				(type solid)
			)
			(layer "B.Fab")
		)
		(fp_line
			(start -0.494 0.25)
			(end 0.504 0.25)
			(stroke
				(width 0.15)
				(type solid)
			)
			(layer "B.Fab")
		)
		(fp_line
			(start -0.494 -0.248)
			(end -0.494 0.25)
			(stroke
				(width 0.15)
				(type solid)
			)
			(layer "B.Fab")
		)
		(pad "1" smd roundrect
			(at -0.48 0 180)
			(size 0.59 0.64)
			(layers "B.Cu" "B.Mask" "B.Paste")
			(roundrect_rratio 0.25)
			(net 1 "GND")
			(pintype "passive")
		)
		(pad "2" smd roundrect
			(at 0.48 0 180)
			(size 0.59 0.64)
			(layers "B.Cu" "B.Mask" "B.Paste")
			(roundrect_rratio 0.25)
			(net 24 "+3V3")
			(pintype "passive")
		)
	)
	(footprint "antmicro-footprints:R_0402_1005Metric"
		(layer "B.Cu")
		(at 198.491252 93.55)
		(descr "Resistor SMD 0402")
		(tags "resistor SMD 0402")
		(property "Reference" "R211"
			(at 1.483748 -4.6 180)
			(layer "B.SilkS")
			(effects
				(font
					(size 0.7 0.7)
					(thickness 0.15)
				)
				(justify left bottom mirror)
			)
		)
		(property "Value" "R_2k2_0402"
			(at 0 -1.4 180)
			(layer "B.Fab")
			(effects
				(font
					(size 0.7 0.7)
					(thickness 0.15)
				)
				(justify left bottom mirror)
			)
		)
		(property "Description" "SMD Chip Resistor, 2.2 kohm, ± 1%, 62.5 mW, 0402 [1005 Metric], Thick Film, General Purpose"
			(at 0 0 0)
			(layer "F.Fab")
			(hide yes)
			(effects
				(font
					(size 1.27 1.27)
					(thickness 0.15)
				)
			)
		)
		(property "Author" "Antmicro"
			(at 0 0 0)
			(layer "B.Fab")
			(hide yes)
			(effects
				(font
					(size 1 1)
					(thickness 0.15)
				)
				(justify mirror)
			)
		)
		(property "License" "Apache-2.0"
			(at 0 0 0)
			(layer "B.Fab")
			(hide yes)
			(effects
				(font
					(size 1 1)
					(thickness 0.15)
				)
				(justify mirror)
			)
		)
		(property "MPN" "CR0402-FX-2201GLF"
			(at 0 0 0)
			(layer "B.Fab")
			(hide yes)
			(effects
				(font
					(size 1 1)
					(thickness 0.15)
				)
				(justify mirror)
			)
		)
		(property "Manufacturer" "Bourns"
			(at 0 0 0)
			(layer "B.Fab")
			(hide yes)
			(effects
				(font
					(size 1 1)
					(thickness 0.15)
				)
				(justify mirror)
			)
		)
		(property "Tolerance" "1%"
			(at 0 0 0)
			(layer "B.Fab")
			(hide yes)
			(effects
				(font
					(size 1 1)
					(thickness 0.15)
				)
				(justify mirror)
			)
		)
		(property "Val" "2k2"
			(at 0 0 0)
			(layer "B.Fab")
			(hide yes)
			(effects
				(font
					(size 1 1)
					(thickness 0.15)
				)
				(justify mirror)
			)
		)
		(sheetname "HDMI + Ethernet")
		(sheetfile "hdmi-ethernet.kicad_sch")
		(attr smd)
		(fp_rect
			(start -0.925 0.47)
			(end 0.925 -0.47)
			(stroke
				(width 0.05)
				(type default)
			)
			(fill no)
			(layer "B.CrtYd")
		)
		(fp_rect
			(start -0.5 0.25)
			(end 0.5 -0.25)
			(stroke
				(width 0.15)
				(type solid)
			)
			(fill no)
			(layer "B.Fab")
		)
		(pad "1" smd roundrect
			(at -0.48 0)
			(size 0.59 0.64)
			(layers "B.Cu" "B.Mask" "B.Paste")
			(roundrect_rratio 0.25)
			(net 505 "/FPGA Bank 16 & 17/GBE_RGMII.RXD1")
			(pintype "passive")
		)
		(pad "2" smd roundrect
			(at 0.48 0)
			(size 0.59 0.64)
			(layers "B.Cu" "B.Mask" "B.Paste")
			(roundrect_rratio 0.25)
			(net 1 "GND")
			(pintype "passive")
		)
	)
	(footprint "antmicro-footprints:R_0402_1005Metric"
		(layer "B.Cu")
		(at 171.25 169.31 90)
		(descr "Resistor SMD 0402")
		(tags "resistor SMD 0402")
		(property "Reference" "R306"
			(at -0.765 0.45 270)
			(layer "B.SilkS")
			(effects
				(font
					(size 0.7 0.7)
					(thickness 0.15)
				)
				(justify left bottom mirror)
			)
		)
		(property "Value" "R_0R_0402"
			(at 0 -1.4 270)
			(layer "B.Fab")
			(effects
				(font
					(size 0.7 0.7)
					(thickness 0.15)
				)
				(justify left bottom mirror)
			)
		)
		(property "Description" "SMD Chip Resistor, Jumper, 0 ohm, 100 mW, 0402 [1005 Metric], Thick Film, General Purpose"
			(at 0 0 90)
			(layer "F.Fab")
			(hide yes)
			(effects
				(font
					(size 1.27 1.27)
					(thickness 0.15)
				)
			)
		)
		(property "Author" "Antmicro"
			(at 340.56 -1.94 0)
			(layer "B.Fab")
			(hide yes)
			(effects
				(font
					(size 1 1)
					(thickness 0.15)
				)
				(justify mirror)
			)
		)
		(property "Current" "1A"
			(at 340.56 -1.94 0)
			(layer "B.Fab")
			(hide yes)
			(effects
				(font
					(size 1 1)
					(thickness 0.15)
				)
				(justify mirror)
			)
		)
		(property "DNP" "DNP"
			(at 340.56 -1.94 0)
			(layer "B.Fab")
			(hide yes)
			(effects
				(font
					(size 1 1)
					(thickness 0.15)
				)
				(justify mirror)
			)
		)
		(property "License" "Apache-2.0"
			(at 340.56 -1.94 0)
			(layer "B.Fab")
			(hide yes)
			(effects
				(font
					(size 1 1)
					(thickness 0.15)
				)
				(justify mirror)
			)
		)
		(property "MPN" "ERJ2GE0R00X"
			(at 340.56 -1.94 0)
			(layer "B.Fab")
			(hide yes)
			(effects
				(font
					(size 1 1)
					(thickness 0.15)
				)
				(justify mirror)
			)
		)
		(property "Manufacturer" "Panasonic"
			(at 340.56 -1.94 0)
			(layer "B.Fab")
			(hide yes)
			(effects
				(font
					(size 1 1)
					(thickness 0.15)
				)
				(justify mirror)
			)
		)
		(property "Tolerance" ""
			(at 340.56 -1.94 0)
			(layer "B.Fab")
			(hide yes)
			(effects
				(font
					(size 1 1)
					(thickness 0.15)
				)
				(justify mirror)
			)
		)
		(property "Val" "0R"
			(at 340.56 -1.94 0)
			(layer "B.Fab")
			(hide yes)
			(effects
				(font
					(size 1 1)
					(thickness 0.15)
				)
				(justify mirror)
			)
		)
		(property "dnp" ""
			(at 340.56 -1.94 0)
			(layer "B.Fab")
			(hide yes)
			(effects
				(font
					(size 1 1)
					(thickness 0.15)
				)
				(justify mirror)
			)
		)
		(property "exclude_from_bom" ""
			(at 340.56 -1.94 0)
			(layer "B.Fab")
			(hide yes)
			(effects
				(font
					(size 1 1)
					(thickness 0.15)
				)
				(justify mirror)
			)
		)
		(sheetname "DC-DC Converters")
		(sheetfile "dc-dc.kicad_sch")
		(attr smd exclude_from_bom)
		(fp_rect
			(start -0.925 0.47)
			(end 0.925 -0.47)
			(stroke
				(width 0.05)
				(type default)
			)
			(fill no)
			(layer "B.CrtYd")
		)
		(fp_rect
			(start -0.5 0.25)
			(end 0.5 -0.25)
			(stroke
				(width 0.15)
				(type solid)
			)
			(fill no)
			(layer "B.Fab")
		)
		(pad "1" smd roundrect
			(at -0.48 0 90)
			(size 0.59 0.64)
			(layers "B.Cu" "B.Mask" "B.Paste")
			(roundrect_rratio 0.25)
			(net 958 "/DC-DC Converters/FB5")
			(pintype "passive")
		)
		(pad "2" smd roundrect
			(at 0.48 0 90)
			(size 0.59 0.64)
			(layers "B.Cu" "B.Mask" "B.Paste")
			(roundrect_rratio 0.25)
			(net 1219 "/DC-DC Converters/SENSE_3V3_1_P")
			(pintype "passive")
		)
	)
	(footprint "antmicro-footprints:R_0402_1005Metric"
		(layer "B.Cu")
		(at 165.8 183.7 -90)
		(descr "Resistor SMD 0402")
		(tags "resistor SMD 0402")
		(property "Reference" "R283"
			(at -3.625 -0.325 90)
			(layer "B.SilkS")
			(effects
				(font
					(size 0.7 0.7)
					(thickness 0.15)
				)
				(justify left bottom mirror)
			)
		)
		(property "Value" "R_47k_0402"
			(at 0 -1.4 90)
			(layer "B.Fab")
			(effects
				(font
					(size 0.7 0.7)
					(thickness 0.15)
				)
				(justify left bottom mirror)
			)
		)
		(property "Description" "SMD Chip Resistor, 47 kohm, ± 1%, 62.5 mW, 0402 [1005 Metric], Thick Film, General Purpose"
			(at 0 0 270)
			(layer "F.Fab")
			(hide yes)
			(effects
				(font
					(size 1.27 1.27)
					(thickness 0.15)
				)
			)
		)
		(property "Author" "Antmicro"
			(at -17.9 349.5 0)
			(layer "B.Fab")
			(hide yes)
			(effects
				(font
					(size 1 1)
					(thickness 0.15)
				)
				(justify mirror)
			)
		)
		(property "DNP" "DNP"
			(at -17.9 349.5 0)
			(layer "B.Fab")
			(hide yes)
			(effects
				(font
					(size 1 1)
					(thickness 0.15)
				)
				(justify mirror)
			)
		)
		(property "License" "Apache-2.0"
			(at -17.9 349.5 0)
			(layer "B.Fab")
			(hide yes)
			(effects
				(font
					(size 1 1)
					(thickness 0.15)
				)
				(justify mirror)
			)
		)
		(property "MPN" "CR0402-FX-4702GLF"
			(at -17.9 349.5 0)
			(layer "B.Fab")
			(hide yes)
			(effects
				(font
					(size 1 1)
					(thickness 0.15)
				)
				(justify mirror)
			)
		)
		(property "Manufacturer" "Bourns"
			(at -17.9 349.5 0)
			(layer "B.Fab")
			(hide yes)
			(effects
				(font
					(size 1 1)
					(thickness 0.15)
				)
				(justify mirror)
			)
		)
		(property "Tolerance" "1%"
			(at -17.9 349.5 0)
			(layer "B.Fab")
			(hide yes)
			(effects
				(font
					(size 1 1)
					(thickness 0.15)
				)
				(justify mirror)
			)
		)
		(property "Val" "47k"
			(at -17.9 349.5 0)
			(layer "B.Fab")
			(hide yes)
			(effects
				(font
					(size 1 1)
					(thickness 0.15)
				)
				(justify mirror)
			)
		)
		(property "dnp" ""
			(at -17.9 349.5 0)
			(layer "B.Fab")
			(hide yes)
			(effects
				(font
					(size 1 1)
					(thickness 0.15)
				)
				(justify mirror)
			)
		)
		(property "exclude_from_bom" ""
			(at -17.9 349.5 0)
			(layer "B.Fab")
			(hide yes)
			(effects
				(font
					(size 1 1)
					(thickness 0.15)
				)
				(justify mirror)
			)
		)
		(sheetname "DC-DC Converters")
		(sheetfile "dc-dc.kicad_sch")
		(attr smd exclude_from_bom)
		(fp_rect
			(start -0.925 0.47)
			(end 0.925 -0.47)
			(stroke
				(width 0.05)
				(type default)
			)
			(fill no)
			(layer "B.CrtYd")
		)
		(fp_rect
			(start -0.5 0.25)
			(end 0.5 -0.25)
			(stroke
				(width 0.15)
				(type solid)
			)
			(fill no)
			(layer "B.Fab")
		)
		(pad "1" smd roundrect
			(at -0.48 0 270)
			(size 0.59 0.64)
			(layers "B.Cu" "B.Mask" "B.Paste")
			(roundrect_rratio 0.25)
			(net 956 "/DC-DC Converters/POE_DC")
			(pintype "passive")
		)
		(pad "2" smd roundrect
			(at 0.48 0 270)
			(size 0.59 0.64)
			(layers "B.Cu" "B.Mask" "B.Paste")
			(roundrect_rratio 0.25)
			(net 797 "/DC-DC Converters/PB_CTRL_OE")
			(pintype "passive")
		)
	)
	(footprint "antmicro-footprints:R_0402_1005Metric"
		(layer "B.Cu")
		(at 165.1125 168.6 90)
		(descr "Resistor SMD 0402")
		(tags "resistor SMD 0402")
		(property "Reference" "R305"
			(at -0.725 0.4375 270)
			(layer "B.SilkS")
			(effects
				(font
					(size 0.7 0.7)
					(thickness 0.15)
				)
				(justify left bottom mirror)
			)
		)
		(property "Value" "R_0R_0402"
			(at 0 -1.4 270)
			(layer "B.Fab")
			(effects
				(font
					(size 0.7 0.7)
					(thickness 0.15)
				)
				(justify left bottom mirror)
			)
		)
		(property "Description" "SMD Chip Resistor, Jumper, 0 ohm, 100 mW, 0402 [1005 Metric], Thick Film, General Purpose"
			(at 0 0 90)
			(layer "F.Fab")
			(hide yes)
			(effects
				(font
					(size 1.27 1.27)
					(thickness 0.15)
				)
			)
		)
		(property "Author" "Antmicro"
			(at 333.7125 3.4875 0)
			(layer "B.Fab")
			(hide yes)
			(effects
				(font
					(size 1 1)
					(thickness 0.15)
				)
				(justify mirror)
			)
		)
		(property "Current" "1A"
			(at 333.7125 3.4875 0)
			(layer "B.Fab")
			(hide yes)
			(effects
				(font
					(size 1 1)
					(thickness 0.15)
				)
				(justify mirror)
			)
		)
		(property "DNP" "DNP"
			(at 333.7125 3.4875 0)
			(layer "B.Fab")
			(hide yes)
			(effects
				(font
					(size 1 1)
					(thickness 0.15)
				)
				(justify mirror)
			)
		)
		(property "License" "Apache-2.0"
			(at 333.7125 3.4875 0)
			(layer "B.Fab")
			(hide yes)
			(effects
				(font
					(size 1 1)
					(thickness 0.15)
				)
				(justify mirror)
			)
		)
		(property "MPN" "ERJ2GE0R00X"
			(at 333.7125 3.4875 0)
			(layer "B.Fab")
			(hide yes)
			(effects
				(font
					(size 1 1)
					(thickness 0.15)
				)
				(justify mirror)
			)
		)
		(property "Manufacturer" "Panasonic"
			(at 333.7125 3.4875 0)
			(layer "B.Fab")
			(hide yes)
			(effects
				(font
					(size 1 1)
					(thickness 0.15)
				)
				(justify mirror)
			)
		)
		(property "Tolerance" ""
			(at 333.7125 3.4875 0)
			(layer "B.Fab")
			(hide yes)
			(effects
				(font
					(size 1 1)
					(thickness 0.15)
				)
				(justify mirror)
			)
		)
		(property "Val" "0R"
			(at 333.7125 3.4875 0)
			(layer "B.Fab")
			(hide yes)
			(effects
				(font
					(size 1 1)
					(thickness 0.15)
				)
				(justify mirror)
			)
		)
		(property "dnp" ""
			(at 333.7125 3.4875 0)
			(layer "B.Fab")
			(hide yes)
			(effects
				(font
					(size 1 1)
					(thickness 0.15)
				)
				(justify mirror)
			)
		)
		(property "exclude_from_bom" ""
			(at 333.7125 3.4875 0)
			(layer "B.Fab")
			(hide yes)
			(effects
				(font
					(size 1 1)
					(thickness 0.15)
				)
				(justify mirror)
			)
		)
		(sheetname "DC-DC Converters")
		(sheetfile "dc-dc.kicad_sch")
		(attr smd exclude_from_bom)
		(fp_rect
			(start -0.925 0.47)
			(end 0.925 -0.47)
			(stroke
				(width 0.05)
				(type default)
			)
			(fill no)
			(layer "B.CrtYd")
		)
		(fp_rect
			(start -0.5 0.25)
			(end 0.5 -0.25)
			(stroke
				(width 0.15)
				(type solid)
			)
			(fill no)
			(layer "B.Fab")
		)
		(pad "1" smd roundrect
			(at -0.48 0 90)
			(size 0.59 0.64)
			(layers "B.Cu" "B.Mask" "B.Paste")
			(roundrect_rratio 0.25)
			(net 960 "/DC-DC Converters/FB2")
			(pintype "passive")
		)
		(pad "2" smd roundrect
			(at 0.48 0 90)
			(size 0.59 0.64)
			(layers "B.Cu" "B.Mask" "B.Paste")
			(roundrect_rratio 0.25)
			(net 1224 "/DC-DC Converters/SENSE_1V8_P")
			(pintype "passive")
		)
	)
	(footprint "antmicro-footprints:C_0201"
		(layer "B.Cu")
		(at 201.5 130.45)
		(descr "Capacitor SMD 0201")
		(tags "capacitor SMD 0201")
		(property "Reference" "C50"
			(at 24.7 -28.75 0)
			(layer "B.SilkS")
			(effects
				(font
					(size 0.7 0.7)
					(thickness 0.15)
				)
				(justify right bottom mirror)
			)
		)
		(property "Value" "C_4u7_0201"
			(at 0 -1.4 0)
			(layer "B.Fab")
			(effects
				(font
					(size 0.7 0.7)
					(thickness 0.15)
				)
				(justify right bottom mirror)
			)
		)
		(property "Description" "SMD Multilayer Ceramic Capacitor, 4.7 µF, 6.3 V, 0201 [0603 Metric], ± 20%, X5R, GRM Series"
			(at 0 0 0)
			(layer "F.Fab")
			(hide yes)
			(effects
				(font
					(size 1.27 1.27)
					(thickness 0.15)
				)
			)
		)
		(property "Author" "Antmicro"
			(at 0 0 0)
			(layer "B.Fab")
			(hide yes)
			(effects
				(font
					(size 1 1)
					(thickness 0.15)
				)
				(justify mirror)
			)
		)
		(property "Dielectric" ""
			(at 0 0 0)
			(layer "B.Fab")
			(hide yes)
			(effects
				(font
					(size 1 1)
					(thickness 0.15)
				)
				(justify mirror)
			)
		)
		(property "License" "Apache-2.0"
			(at 0 0 0)
			(layer "B.Fab")
			(hide yes)
			(effects
				(font
					(size 1 1)
					(thickness 0.15)
				)
				(justify mirror)
			)
		)
		(property "MPN" "GRM035R60J475ME15D"
			(at 0 0 0)
			(layer "B.Fab")
			(hide yes)
			(effects
				(font
					(size 1 1)
					(thickness 0.15)
				)
				(justify mirror)
			)
		)
		(property "Manufacturer" "Murata"
			(at 0 0 0)
			(layer "B.Fab")
			(hide yes)
			(effects
				(font
					(size 1 1)
					(thickness 0.15)
				)
				(justify mirror)
			)
		)
		(property "Val" "4u7"
			(at 0 0 0)
			(layer "B.Fab")
			(hide yes)
			(effects
				(font
					(size 1 1)
					(thickness 0.15)
				)
				(justify mirror)
			)
		)
		(property "Voltage" ""
			(at 0 0 0)
			(layer "B.Fab")
			(hide yes)
			(effects
				(font
					(size 1 1)
					(thickness 0.15)
				)
				(justify mirror)
			)
		)
		(sheetname "FPGA supply")
		(sheetfile "fpga-supply.kicad_sch")
		(attr smd)
		(fp_rect
			(start -0.7 0.35)
			(end 0.7 -0.35)
			(stroke
				(width 0.05)
				(type default)
			)
			(fill no)
			(layer "B.CrtYd")
		)
		(fp_rect
			(start 0.3 -0.15)
			(end -0.301 0.149)
			(stroke
				(width 0.15)
				(type solid)
			)
			(fill no)
			(layer "B.Fab")
		)
		(pad "" smd roundrect
			(at -0.349 0.002)
			(size 0.318 0.36)
			(layers "B.Paste")
			(roundrect_rratio 0.25)
		)
		(pad "" smd roundrect
			(at 0.341 0.002)
			(size 0.318 0.36)
			(layers "B.Paste")
			(roundrect_rratio 0.25)
		)
		(pad "1" smd roundrect
			(at -0.321 0.002)
			(size 0.46 0.4)
			(layers "B.Cu" "B.Mask")
			(roundrect_rratio 0.25)
			(net 1 "GND")
			(pintype "passive")
		)
		(pad "2" smd roundrect
			(at 0.32 0.002)
			(size 0.46 0.4)
			(layers "B.Cu" "B.Mask")
			(roundrect_rratio 0.25)
			(net 650 "+1V0")
			(pintype "passive")
		)
	)
	(footprint "antmicro-footprints:R_0402_1005Metric"
		(layer "B.Cu")
		(at 223.586 148.2 180)
		(descr "Resistor SMD 0402")
		(tags "resistor SMD 0402")
		(property "Reference" "R221"
			(at -1.839 -2.35 0)
			(layer "B.SilkS")
			(effects
				(font
					(size 0.7 0.7)
					(thickness 0.15)
				)
				(justify left bottom mirror)
			)
		)
		(property "Value" "R_10k_0402"
			(at 0 -1.4 0)
			(layer "B.Fab")
			(effects
				(font
					(size 0.7 0.7)
					(thickness 0.15)
				)
				(justify left bottom mirror)
			)
		)
		(property "Description" "SMD Chip Resistor, 10 kohm, ± 1%, 62.5 mW, 0402 [1005 Metric], Thick Film, General Purpose"
			(at 0 0 180)
			(layer "F.Fab")
			(hide yes)
			(effects
				(font
					(size 1.27 1.27)
					(thickness 0.15)
				)
			)
		)
		(property "Author" "Antmicro"
			(at 447.172 296.4 0)
			(layer "B.Fab")
			(hide yes)
			(effects
				(font
					(size 1 1)
					(thickness 0.15)
				)
				(justify mirror)
			)
		)
		(property "License" "Apache-2.0"
			(at 447.172 296.4 0)
			(layer "B.Fab")
			(hide yes)
			(effects
				(font
					(size 1 1)
					(thickness 0.15)
				)
				(justify mirror)
			)
		)
		(property "MPN" "CR0402-FX-1002GLF"
			(at 447.172 296.4 0)
			(layer "B.Fab")
			(hide yes)
			(effects
				(font
					(size 1 1)
					(thickness 0.15)
				)
				(justify mirror)
			)
		)
		(property "Manufacturer" "Bourns"
			(at 447.172 296.4 0)
			(layer "B.Fab")
			(hide yes)
			(effects
				(font
					(size 1 1)
					(thickness 0.15)
				)
				(justify mirror)
			)
		)
		(property "Tolerance" "1%"
			(at 447.172 296.4 0)
			(layer "B.Fab")
			(hide yes)
			(effects
				(font
					(size 1 1)
					(thickness 0.15)
				)
				(justify mirror)
			)
		)
		(property "Val" "10k"
			(at 447.172 296.4 0)
			(layer "B.Fab")
			(hide yes)
			(effects
				(font
					(size 1 1)
					(thickness 0.15)
				)
				(justify mirror)
			)
		)
		(sheetname "HDMI + Ethernet")
		(sheetfile "hdmi-ethernet.kicad_sch")
		(attr smd)
		(fp_rect
			(start -0.925 0.47)
			(end 0.925 -0.47)
			(stroke
				(width 0.05)
				(type default)
			)
			(fill no)
			(layer "B.CrtYd")
		)
		(fp_rect
			(start -0.5 0.25)
			(end 0.5 -0.25)
			(stroke
				(width 0.15)
				(type solid)
			)
			(fill no)
			(layer "B.Fab")
		)
		(pad "1" smd roundrect
			(at -0.48 0 180)
			(size 0.59 0.64)
			(layers "B.Cu" "B.Mask" "B.Paste")
			(roundrect_rratio 0.25)
			(net 946 "/HDMI + Ethernet/ETH_PHY_RXDO")
			(pintype "passive")
		)
		(pad "2" smd roundrect
			(at 0.48 0 180)
			(size 0.59 0.64)
			(layers "B.Cu" "B.Mask" "B.Paste")
			(roundrect_rratio 0.25)
			(net 26 "+1V8")
			(pintype "passive")
		)
	)
	(footprint "antmicro-footprints:R_0402_1005Metric"
		(layer "B.Cu")
		(at 258.4 86.2 -90)
		(descr "Resistor SMD 0402")
		(tags "resistor SMD 0402")
		(property "Reference" "R354"
			(at -1.225 0.475 90)
			(layer "B.SilkS")
			(effects
				(font
					(size 0.7 0.7)
					(thickness 0.15)
				)
				(justify left bottom mirror)
			)
		)
		(property "Value" "R_100k_0402"
			(at 0 -1.4 90)
			(layer "B.Fab")
			(effects
				(font
					(size 0.7 0.7)
					(thickness 0.15)
				)
				(justify left bottom mirror)
			)
		)
		(property "Description" "SMD Chip Resistor, 100 kohm, ± 1%, 62.5 mW, 0402 [1005 Metric], Thick Film, General Purpose"
			(at 0 0 270)
			(layer "F.Fab")
			(hide yes)
			(effects
				(font
					(size 1.27 1.27)
					(thickness 0.15)
				)
			)
		)
		(property "Author" "Antmicro"
			(at 172.2 344.6 0)
			(layer "B.Fab")
			(hide yes)
			(effects
				(font
					(size 1 1)
					(thickness 0.15)
				)
				(justify mirror)
			)
		)
		(property "License" "Apache-2.0"
			(at 172.2 344.6 0)
			(layer "B.Fab")
			(hide yes)
			(effects
				(font
					(size 1 1)
					(thickness 0.15)
				)
				(justify mirror)
			)
		)
		(property "MPN" "CR0402-FX-1003GLF"
			(at 172.2 344.6 0)
			(layer "B.Fab")
			(hide yes)
			(effects
				(font
					(size 1 1)
					(thickness 0.15)
				)
				(justify mirror)
			)
		)
		(property "Manufacturer" "Bourns"
			(at 172.2 344.6 0)
			(layer "B.Fab")
			(hide yes)
			(effects
				(font
					(size 1 1)
					(thickness 0.15)
				)
				(justify mirror)
			)
		)
		(property "Tolerance" "1%"
			(at 172.2 344.6 0)
			(layer "B.Fab")
			(hide yes)
			(effects
				(font
					(size 1 1)
					(thickness 0.15)
				)
				(justify mirror)
			)
		)
		(property "Val" "100k"
			(at 172.2 344.6 0)
			(layer "B.Fab")
			(hide yes)
			(effects
				(font
					(size 1 1)
					(thickness 0.15)
				)
				(justify mirror)
			)
		)
		(sheetname "User GPIO + LED + button + DIP switch")
		(sheetfile "user-gpio.kicad_sch")
		(attr smd)
		(fp_rect
			(start -0.925 0.47)
			(end 0.925 -0.47)
			(stroke
				(width 0.05)
				(type default)
			)
			(fill no)
			(layer "B.CrtYd")
		)
		(fp_rect
			(start -0.5 0.25)
			(end 0.5 -0.25)
			(stroke
				(width 0.15)
				(type solid)
			)
			(fill no)
			(layer "B.Fab")
		)
		(pad "1" smd roundrect
			(at -0.48 0 270)
			(size 0.59 0.64)
			(layers "B.Cu" "B.Mask" "B.Paste")
			(roundrect_rratio 0.25)
			(net 1300 "/USER_IO.LED_GREEN1")
			(pintype "passive")
		)
		(pad "2" smd roundrect
			(at 0.48 0 270)
			(size 0.59 0.64)
			(layers "B.Cu" "B.Mask" "B.Paste")
			(roundrect_rratio 0.25)
			(net 1 "GND")
			(pintype "passive")
		)
	)
	(footprint "antmicro-footprints:NetTie-2_SMD_Pad0.127mm"
		(layer "B.Cu")
		(at 196.92 87.08 45)
		(descr "Net tie, 2 pin, 0.127mm  SMD pads")
		(tags "net tie")
		(property "Reference" "NT38"
			(at -0.128 1.345 225)
			(layer "B.SilkS")
			(hide yes)
			(effects
				(font
					(size 0.7 0.7)
					(thickness 0.15)
				)
				(justify left bottom mirror)
			)
		)
		(property "Value" "Net-Tie_2"
			(at 0 -1.199 225)
			(layer "B.Fab")
			(effects
				(font
					(size 0.7 0.7)
					(thickness 0.15)
				)
				(justify left bottom mirror)
			)
		)
		(property "Description" "Net tie, 2 pins"
			(at 0 0 45)
			(layer "F.Fab")
			(hide yes)
			(effects
				(font
					(size 1.27 1.27)
					(thickness 0.15)
				)
			)
		)
		(property "Author" "Antmicro"
			(at 119.251391 -113.738326 0)
			(layer "B.Fab")
			(hide yes)
			(effects
				(font
					(size 1 1)
					(thickness 0.15)
				)
				(justify mirror)
			)
		)
		(property "License" "Apache-2.0"
			(at 119.251391 -113.738326 0)
			(layer "B.Fab")
			(hide yes)
			(effects
				(font
					(size 1 1)
					(thickness 0.15)
				)
				(justify mirror)
			)
		)
		(property "MPN" ""
			(at 119.251391 -113.738326 0)
			(layer "B.Fab")
			(hide yes)
			(effects
				(font
					(size 1 1)
					(thickness 0.15)
				)
				(justify mirror)
			)
		)
		(property "Manufacturer" ""
			(at 119.251391 -113.738326 0)
			(layer "B.Fab")
			(hide yes)
			(effects
				(font
					(size 1 1)
					(thickness 0.15)
				)
				(justify mirror)
			)
		)
		(sheetname "DC-DC Converters")
		(sheetfile "dc-dc.kicad_sch")
		(attr exclude_from_pos_files)
		(net_tie_pad_groups "1, 2")
		(fp_poly
			(pts
				(xy -0.0635 0.0635) (xy 0.0625 0.0635) (xy 0.0625 -0.0635) (xy -0.0635 -0.0635)
			)
			(stroke
				(width 0)
				(type solid)
			)
			(fill yes)
			(layer "B.Cu")
		)
		(pad "1" smd roundrect
			(at -0.127001 0 225)
			(size 0.127 0.127)
			(layers "B.Cu")
			(roundrect_rratio 0.5)
			(chamfer_ratio 0)
			(chamfer top_left bottom_left)
			(net 1226 "/DC-DC Converters/SENSE_1V2_P")
			(pinfunction "1")
			(pintype "passive")
		)
		(pad "2" smd roundrect
			(at 0.125999 0 45)
			(size 0.127 0.127)
			(layers "B.Cu")
			(roundrect_rratio 0.5)
			(chamfer_ratio 0)
			(chamfer top_left bottom_left)
			(net 727 "+1V2")
			(pinfunction "2")
			(pintype "passive")
		)
	)
	(footprint "antmicro-footprints:R_0402_1005Metric"
		(layer "B.Cu")
		(at 255.001 161.6 90)
		(descr "Resistor SMD 0402")
		(tags "resistor SMD 0402")
		(property "Reference" "R245"
			(at 1.35 5.299 270)
			(layer "B.SilkS")
			(effects
				(font
					(size 0.7 0.7)
					(thickness 0.15)
				)
				(justify left bottom mirror)
			)
		)
		(property "Value" "R_49R9_0402"
			(at 0 -1.4 270)
			(layer "B.Fab")
			(effects
				(font
					(size 0.7 0.7)
					(thickness 0.15)
				)
				(justify left bottom mirror)
			)
		)
		(property "Description" "SMD Chip Resistor, 49.9 ohm, ± 1%, 62.5 mW, 0402 [1005 Metric], Thick Film, General Purpose"
			(at 0 0 90)
			(layer "F.Fab")
			(hide yes)
			(effects
				(font
					(size 1.27 1.27)
					(thickness 0.15)
				)
			)
		)
		(property "Author" "Antmicro"
			(at 416.601 -93.401 0)
			(layer "B.Fab")
			(hide yes)
			(effects
				(font
					(size 1 1)
					(thickness 0.15)
				)
				(justify mirror)
			)
		)
		(property "License" "Apache-2.0"
			(at 416.601 -93.401 0)
			(layer "B.Fab")
			(hide yes)
			(effects
				(font
					(size 1 1)
					(thickness 0.15)
				)
				(justify mirror)
			)
		)
		(property "MPN" "CR0402-FX-49R9GLF"
			(at 416.601 -93.401 0)
			(layer "B.Fab")
			(hide yes)
			(effects
				(font
					(size 1 1)
					(thickness 0.15)
				)
				(justify mirror)
			)
		)
		(property "Manufacturer" "Bourns"
			(at 416.601 -93.401 0)
			(layer "B.Fab")
			(hide yes)
			(effects
				(font
					(size 1 1)
					(thickness 0.15)
				)
				(justify mirror)
			)
		)
		(property "Tolerance" "1%"
			(at 416.601 -93.401 0)
			(layer "B.Fab")
			(hide yes)
			(effects
				(font
					(size 1 1)
					(thickness 0.15)
				)
				(justify mirror)
			)
		)
		(property "Val" "49R9"
			(at 416.601 -93.401 0)
			(layer "B.Fab")
			(hide yes)
			(effects
				(font
					(size 1 1)
					(thickness 0.15)
				)
				(justify mirror)
			)
		)
		(sheetname "HDMI + Ethernet")
		(sheetfile "hdmi-ethernet.kicad_sch")
		(attr smd)
		(fp_rect
			(start -0.925 0.47)
			(end 0.925 -0.47)
			(stroke
				(width 0.05)
				(type default)
			)
			(fill no)
			(layer "B.CrtYd")
		)
		(fp_rect
			(start -0.5 0.25)
			(end 0.5 -0.25)
			(stroke
				(width 0.15)
				(type solid)
			)
			(fill no)
			(layer "B.Fab")
		)
		(pad "1" smd roundrect
			(at -0.48 0 90)
			(size 0.59 0.64)
			(layers "B.Cu" "B.Mask" "B.Paste")
			(roundrect_rratio 0.25)
			(net 724 "/HDMI + Ethernet/ETH1_P")
			(pintype "passive")
		)
		(pad "2" smd roundrect
			(at 0.48 0 90)
			(size 0.59 0.64)
			(layers "B.Cu" "B.Mask" "B.Paste")
			(roundrect_rratio 0.25)
			(net 721 "/HDMI + Ethernet/ETH_3V3")
			(pintype "passive")
		)
	)
	(footprint "antmicro-footprints:R_0402_1005Metric"
		(layer "B.Cu")
		(at 165.685001 118.065001 180)
		(descr "Resistor SMD 0402")
		(tags "resistor SMD 0402")
		(property "Reference" "R267"
			(at 0.835001 -0.434999 0)
			(layer "B.SilkS")
			(effects
				(font
					(size 0.7 0.7)
					(thickness 0.15)
				)
				(justify left bottom mirror)
			)
		)
		(property "Value" "R_4k7_0402"
			(at 0 -1.4 0)
			(layer "B.Fab")
			(effects
				(font
					(size 0.7 0.7)
					(thickness 0.15)
				)
				(justify left bottom mirror)
			)
		)
		(property "Description" "SMD Chip Resistor, 4.7 kohm, ± 1%, 62.5 mW, 0402 [1005 Metric], Thick Film, General Purpose"
			(at 0 0 180)
			(layer "F.Fab")
			(hide yes)
			(effects
				(font
					(size 1.27 1.27)
					(thickness 0.15)
				)
			)
		)
		(property "Author" "Antmicro"
			(at 331.370002 236.130002 0)
			(layer "B.Fab")
			(hide yes)
			(effects
				(font
					(size 1 1)
					(thickness 0.15)
				)
				(justify mirror)
			)
		)
		(property "License" "Apache-2.0"
			(at 331.370002 236.130002 0)
			(layer "B.Fab")
			(hide yes)
			(effects
				(font
					(size 1 1)
					(thickness 0.15)
				)
				(justify mirror)
			)
		)
		(property "MPN" "CR0402-FX-4701GLF"
			(at 331.370002 236.130002 0)
			(layer "B.Fab")
			(hide yes)
			(effects
				(font
					(size 1 1)
					(thickness 0.15)
				)
				(justify mirror)
			)
		)
		(property "Manufacturer" "Bourns"
			(at 331.370002 236.130002 0)
			(layer "B.Fab")
			(hide yes)
			(effects
				(font
					(size 1 1)
					(thickness 0.15)
				)
				(justify mirror)
			)
		)
		(property "Tolerance" "1%"
			(at 331.370002 236.130002 0)
			(layer "B.Fab")
			(hide yes)
			(effects
				(font
					(size 1 1)
					(thickness 0.15)
				)
				(justify mirror)
			)
		)
		(property "Val" "4k7"
			(at 331.370002 236.130002 0)
			(layer "B.Fab")
			(hide yes)
			(effects
				(font
					(size 1 1)
					(thickness 0.15)
				)
				(justify mirror)
			)
		)
		(sheetname "FMC+ HSPC")
		(sheetfile "fmc-hspc.kicad_sch")
		(attr smd)
		(fp_rect
			(start -0.925 0.47)
			(end 0.925 -0.47)
			(stroke
				(width 0.05)
				(type default)
			)
			(fill no)
			(layer "B.CrtYd")
		)
		(fp_rect
			(start -0.5 0.25)
			(end 0.5 -0.25)
			(stroke
				(width 0.15)
				(type solid)
			)
			(fill no)
			(layer "B.Fab")
		)
		(pad "1" smd roundrect
			(at -0.48 0 180)
			(size 0.59 0.64)
			(layers "B.Cu" "B.Mask" "B.Paste")
			(roundrect_rratio 0.25)
			(net 24 "+3V3")
			(pintype "passive")
		)
		(pad "2" smd roundrect
			(at 0.48 0 180)
			(size 0.59 0.64)
			(layers "B.Cu" "B.Mask" "B.Paste")
			(roundrect_rratio 0.25)
			(net 383 "FMC.SCL_3V3")
			(pintype "passive")
		)
	)
	(footprint "antmicro-footprints:R_0402_1005Metric"
		(layer "B.Cu")
		(at 195.691252 95.85 180)
		(descr "Resistor SMD 0402")
		(tags "resistor SMD 0402")
		(property "Reference" "R207"
			(at 0.716252 -0.425 0)
			(layer "B.SilkS")
			(effects
				(font
					(size 0.7 0.7)
					(thickness 0.15)
				)
				(justify left bottom mirror)
			)
		)
		(property "Value" "R_10k_0402"
			(at 0 -1.4 0)
			(layer "B.Fab")
			(effects
				(font
					(size 0.7 0.7)
					(thickness 0.15)
				)
				(justify left bottom mirror)
			)
		)
		(property "Description" "SMD Chip Resistor, 10 kohm, ± 1%, 62.5 mW, 0402 [1005 Metric], Thick Film, General Purpose"
			(at 0 0 180)
			(layer "F.Fab")
			(hide yes)
			(effects
				(font
					(size 1.27 1.27)
					(thickness 0.15)
				)
			)
		)
		(property "Author" "Antmicro"
			(at 391.382504 191.7 0)
			(layer "B.Fab")
			(hide yes)
			(effects
				(font
					(size 1 1)
					(thickness 0.15)
				)
				(justify mirror)
			)
		)
		(property "DNP" "DNP"
			(at 391.382504 191.7 0)
			(layer "B.Fab")
			(hide yes)
			(effects
				(font
					(size 1 1)
					(thickness 0.15)
				)
				(justify mirror)
			)
		)
		(property "License" "Apache-2.0"
			(at 391.382504 191.7 0)
			(layer "B.Fab")
			(hide yes)
			(effects
				(font
					(size 1 1)
					(thickness 0.15)
				)
				(justify mirror)
			)
		)
		(property "MPN" "CR0402-FX-1002GLF"
			(at 391.382504 191.7 0)
			(layer "B.Fab")
			(hide yes)
			(effects
				(font
					(size 1 1)
					(thickness 0.15)
				)
				(justify mirror)
			)
		)
		(property "Manufacturer" "Bourns"
			(at 391.382504 191.7 0)
			(layer "B.Fab")
			(hide yes)
			(effects
				(font
					(size 1 1)
					(thickness 0.15)
				)
				(justify mirror)
			)
		)
		(property "Tolerance" "1%"
			(at 391.382504 191.7 0)
			(layer "B.Fab")
			(hide yes)
			(effects
				(font
					(size 1 1)
					(thickness 0.15)
				)
				(justify mirror)
			)
		)
		(property "Val" "10k"
			(at 391.382504 191.7 0)
			(layer "B.Fab")
			(hide yes)
			(effects
				(font
					(size 1 1)
					(thickness 0.15)
				)
				(justify mirror)
			)
		)
		(property "dnp" ""
			(at 391.382504 191.7 0)
			(layer "B.Fab")
			(hide yes)
			(effects
				(font
					(size 1 1)
					(thickness 0.15)
				)
				(justify mirror)
			)
		)
		(property "exclude_from_bom" ""
			(at 391.382504 191.7 0)
			(layer "B.Fab")
			(hide yes)
			(effects
				(font
					(size 1 1)
					(thickness 0.15)
				)
				(justify mirror)
			)
		)
		(sheetname "HDMI + Ethernet")
		(sheetfile "hdmi-ethernet.kicad_sch")
		(attr smd exclude_from_bom)
		(fp_rect
			(start -0.925 0.47)
			(end 0.925 -0.47)
			(stroke
				(width 0.05)
				(type default)
			)
			(fill no)
			(layer "B.CrtYd")
		)
		(fp_rect
			(start -0.5 0.25)
			(end 0.5 -0.25)
			(stroke
				(width 0.15)
				(type solid)
			)
			(fill no)
			(layer "B.Fab")
		)
		(pad "1" smd roundrect
			(at -0.48 0 180)
			(size 0.59 0.64)
			(layers "B.Cu" "B.Mask" "B.Paste")
			(roundrect_rratio 0.25)
			(net 509 "/FPGA Bank 16 & 17/GBE_RGMII.RX_DV")
			(pintype "passive")
		)
		(pad "2" smd roundrect
			(at 0.48 0 180)
			(size 0.59 0.64)
			(layers "B.Cu" "B.Mask" "B.Paste")
			(roundrect_rratio 0.25)
			(net 24 "+3V3")
			(pintype "passive")
		)
	)
	(footprint "antmicro-footprints:C_0402_1005Metric"
		(layer "B.Cu")
		(at 214.5 135 -90)
		(descr "Capacitor SMD 0402")
		(tags "capacitor SMD 0402")
		(property "Reference" "C41"
			(at -1.05 -1.325 90)
			(layer "B.SilkS")
			(effects
				(font
					(size 0.7 0.7)
					(thickness 0.15)
				)
				(justify left bottom mirror)
			)
		)
		(property "Value" "C_100n_0402"
			(at 0 -1.169 90)
			(layer "B.Fab")
			(effects
				(font
					(size 0.7 0.7)
					(thickness 0.15)
				)
				(justify left bottom mirror)
			)
		)
		(property "Description" "SMD Multilayer Ceramic Capacitor, 0.1 µF, 50 V, 0402 [1005 Metric], ± 10%, X5R, GRM Series"
			(at 0 0 270)
			(layer "F.Fab")
			(hide yes)
			(effects
				(font
					(size 1.27 1.27)
					(thickness 0.15)
				)
			)
		)
		(property "Author" "Antmicro"
			(at 79.5 349.5 0)
			(layer "B.Fab")
			(hide yes)
			(effects
				(font
					(size 1 1)
					(thickness 0.15)
				)
				(justify mirror)
			)
		)
		(property "Dielectric" "X5R"
			(at 79.5 349.5 0)
			(layer "B.Fab")
			(hide yes)
			(effects
				(font
					(size 1 1)
					(thickness 0.15)
				)
				(justify mirror)
			)
		)
		(property "License" "Apache-2.0"
			(at 79.5 349.5 0)
			(layer "B.Fab")
			(hide yes)
			(effects
				(font
					(size 1 1)
					(thickness 0.15)
				)
				(justify mirror)
			)
		)
		(property "MPN" "GRM155R61H104KE14D"
			(at 79.5 349.5 0)
			(layer "B.Fab")
			(hide yes)
			(effects
				(font
					(size 1 1)
					(thickness 0.15)
				)
				(justify mirror)
			)
		)
		(property "Manufacturer" "Murata"
			(at 79.5 349.5 0)
			(layer "B.Fab")
			(hide yes)
			(effects
				(font
					(size 1 1)
					(thickness 0.15)
				)
				(justify mirror)
			)
		)
		(property "Val" "100n"
			(at 79.5 349.5 0)
			(layer "B.Fab")
			(hide yes)
			(effects
				(font
					(size 1 1)
					(thickness 0.15)
				)
				(justify mirror)
			)
		)
		(property "Voltage" "50V"
			(at 79.5 349.5 0)
			(layer "B.Fab")
			(hide yes)
			(effects
				(font
					(size 1 1)
					(thickness 0.15)
				)
				(justify mirror)
			)
		)
		(sheetname "FPGA Bank 12 & 13")
		(sheetfile "fpga-bank-12-13.kicad_sch")
		(attr smd)
		(fp_rect
			(start -0.925 0.47)
			(end 0.925 -0.47)
			(stroke
				(width 0.05)
				(type default)
			)
			(fill no)
			(layer "B.CrtYd")
		)
		(fp_line
			(start -0.494 0.25)
			(end 0.504 0.25)
			(stroke
				(width 0.15)
				(type solid)
			)
			(layer "B.Fab")
		)
		(fp_line
			(start 0.504 0.25)
			(end 0.504 -0.248)
			(stroke
				(width 0.15)
				(type solid)
			)
			(layer "B.Fab")
		)
		(fp_line
			(start -0.494 -0.248)
			(end -0.494 0.25)
			(stroke
				(width 0.15)
				(type solid)
			)
			(layer "B.Fab")
		)
		(fp_line
			(start 0.504 -0.248)
			(end -0.494 -0.248)
			(stroke
				(width 0.15)
				(type solid)
			)
			(layer "B.Fab")
		)
		(pad "1" smd roundrect
			(at -0.48 0 270)
			(size 0.59 0.64)
			(layers "B.Cu" "B.Mask" "B.Paste")
			(roundrect_rratio 0.25)
			(net 1 "GND")
			(pintype "passive")
		)
		(pad "2" smd roundrect
			(at 0.48 0 270)
			(size 0.59 0.64)
			(layers "B.Cu" "B.Mask" "B.Paste")
			(roundrect_rratio 0.25)
			(net 24 "+3V3")
			(pintype "passive")
		)
	)
	(footprint "antmicro-footprints:C_0402_1005Metric"
		(layer "B.Cu")
		(at 203 135.5)
		(descr "Capacitor SMD 0402")
		(tags "capacitor SMD 0402")
		(property "Reference" "C77"
			(at 28.9 -28.075 180)
			(layer "B.SilkS")
			(effects
				(font
					(size 0.7 0.7)
					(thickness 0.15)
				)
				(justify left bottom mirror)
			)
		)
		(property "Value" "C_100n_0402"
			(at 0 -1.169 180)
			(layer "B.Fab")
			(effects
				(font
					(size 0.7 0.7)
					(thickness 0.15)
				)
				(justify left bottom mirror)
			)
		)
		(property "Description" "SMD Multilayer Ceramic Capacitor, 0.1 µF, 50 V, 0402 [1005 Metric], ± 10%, X5R, GRM Series"
			(at 0 0 0)
			(layer "F.Fab")
			(hide yes)
			(effects
				(font
					(size 1.27 1.27)
					(thickness 0.15)
				)
			)
		)
		(property "Author" "Antmicro"
			(at 0 0 0)
			(layer "B.Fab")
			(hide yes)
			(effects
				(font
					(size 1 1)
					(thickness 0.15)
				)
				(justify mirror)
			)
		)
		(property "Dielectric" "X5R"
			(at 0 0 0)
			(layer "B.Fab")
			(hide yes)
			(effects
				(font
					(size 1 1)
					(thickness 0.15)
				)
				(justify mirror)
			)
		)
		(property "License" "Apache-2.0"
			(at 0 0 0)
			(layer "B.Fab")
			(hide yes)
			(effects
				(font
					(size 1 1)
					(thickness 0.15)
				)
				(justify mirror)
			)
		)
		(property "MPN" "GRM155R61H104KE14D"
			(at 0 0 0)
			(layer "B.Fab")
			(hide yes)
			(effects
				(font
					(size 1 1)
					(thickness 0.15)
				)
				(justify mirror)
			)
		)
		(property "Manufacturer" "Murata"
			(at 0 0 0)
			(layer "B.Fab")
			(hide yes)
			(effects
				(font
					(size 1 1)
					(thickness 0.15)
				)
				(justify mirror)
			)
		)
		(property "Val" "100n"
			(at 0 0 0)
			(layer "B.Fab")
			(hide yes)
			(effects
				(font
					(size 1 1)
					(thickness 0.15)
				)
				(justify mirror)
			)
		)
		(property "Voltage" "50V"
			(at 0 0 0)
			(layer "B.Fab")
			(hide yes)
			(effects
				(font
					(size 1 1)
					(thickness 0.15)
				)
				(justify mirror)
			)
		)
		(sheetname "FPGA Bank 18 & 32")
		(sheetfile "fpga-bank-18-32.kicad_sch")
		(attr smd)
		(fp_rect
			(start -0.925 0.47)
			(end 0.925 -0.47)
			(stroke
				(width 0.05)
				(type default)
			)
			(fill no)
			(layer "B.CrtYd")
		)
		(fp_line
			(start -0.494 -0.248)
			(end -0.494 0.25)
			(stroke
				(width 0.15)
				(type solid)
			)
			(layer "B.Fab")
		)
		(fp_line
			(start -0.494 0.25)
			(end 0.504 0.25)
			(stroke
				(width 0.15)
				(type solid)
			)
			(layer "B.Fab")
		)
		(fp_line
			(start 0.504 -0.248)
			(end -0.494 -0.248)
			(stroke
				(width 0.15)
				(type solid)
			)
			(layer "B.Fab")
		)
		(fp_line
			(start 0.504 0.25)
			(end 0.504 -0.248)
			(stroke
				(width 0.15)
				(type solid)
			)
			(layer "B.Fab")
		)
		(pad "1" smd roundrect
			(at -0.48 0)
			(size 0.59 0.64)
			(layers "B.Cu" "B.Mask" "B.Paste")
			(roundrect_rratio 0.25)
			(net 1 "GND")
			(pintype "passive")
		)
		(pad "2" smd roundrect
			(at 0.48 0)
			(size 0.59 0.64)
			(layers "B.Cu" "B.Mask" "B.Paste")
			(roundrect_rratio 0.25)
			(net 26 "+1V8")
			(pintype "passive")
		)
	)
	(footprint "antmicro-footprints:C_0402_1005Metric"
		(layer "B.Cu")
		(at 189.9 133.275 180)
		(descr "Capacitor SMD 0402")
		(tags "capacitor SMD 0402")
		(property "Reference" "C143"
			(at 1.025 -1.675 0)
			(layer "B.SilkS")
			(effects
				(font
					(size 0.7 0.7)
					(thickness 0.15)
				)
				(justify left bottom mirror)
			)
		)
		(property "Value" "C_100n_0402"
			(at 0 -1.169 0)
			(layer "B.Fab")
			(effects
				(font
					(size 0.7 0.7)
					(thickness 0.15)
				)
				(justify left bottom mirror)
			)
		)
		(property "Description" "SMD Multilayer Ceramic Capacitor, 0.1 µF, 50 V, 0402 [1005 Metric], ± 10%, X5R, GRM Series"
			(at 0 0 180)
			(layer "F.Fab")
			(hide yes)
			(effects
				(font
					(size 1.27 1.27)
					(thickness 0.15)
				)
			)
		)
		(property "Author" "Antmicro"
			(at 379.8 266.55 0)
			(layer "B.Fab")
			(hide yes)
			(effects
				(font
					(size 1 1)
					(thickness 0.15)
				)
				(justify mirror)
			)
		)
		(property "Dielectric" "X5R"
			(at 379.8 266.55 0)
			(layer "B.Fab")
			(hide yes)
			(effects
				(font
					(size 1 1)
					(thickness 0.15)
				)
				(justify mirror)
			)
		)
		(property "License" "Apache-2.0"
			(at 379.8 266.55 0)
			(layer "B.Fab")
			(hide yes)
			(effects
				(font
					(size 1 1)
					(thickness 0.15)
				)
				(justify mirror)
			)
		)
		(property "MPN" "GRM155R61H104KE14D"
			(at 379.8 266.55 0)
			(layer "B.Fab")
			(hide yes)
			(effects
				(font
					(size 1 1)
					(thickness 0.15)
				)
				(justify mirror)
			)
		)
		(property "Manufacturer" "Murata"
			(at 379.8 266.55 0)
			(layer "B.Fab")
			(hide yes)
			(effects
				(font
					(size 1 1)
					(thickness 0.15)
				)
				(justify mirror)
			)
		)
		(property "Val" "100n"
			(at 379.8 266.55 0)
			(layer "B.Fab")
			(hide yes)
			(effects
				(font
					(size 1 1)
					(thickness 0.15)
				)
				(justify mirror)
			)
		)
		(property "Voltage" "50V"
			(at 379.8 266.55 0)
			(layer "B.Fab")
			(hide yes)
			(effects
				(font
					(size 1 1)
					(thickness 0.15)
				)
				(justify mirror)
			)
		)
		(sheetname "FPGA supply")
		(sheetfile "fpga-supply.kicad_sch")
		(attr smd)
		(fp_rect
			(start -0.925 0.47)
			(end 0.925 -0.47)
			(stroke
				(width 0.05)
				(type default)
			)
			(fill no)
			(layer "B.CrtYd")
		)
		(fp_line
			(start 0.504 0.25)
			(end 0.504 -0.248)
			(stroke
				(width 0.15)
				(type solid)
			)
			(layer "B.Fab")
		)
		(fp_line
			(start 0.504 -0.248)
			(end -0.494 -0.248)
			(stroke
				(width 0.15)
				(type solid)
			)
			(layer "B.Fab")
		)
		(fp_line
			(start -0.494 0.25)
			(end 0.504 0.25)
			(stroke
				(width 0.15)
				(type solid)
			)
			(layer "B.Fab")
		)
		(fp_line
			(start -0.494 -0.248)
			(end -0.494 0.25)
			(stroke
				(width 0.15)
				(type solid)
			)
			(layer "B.Fab")
		)
		(pad "1" smd roundrect
			(at -0.48 0 180)
			(size 0.59 0.64)
			(layers "B.Cu" "B.Mask" "B.Paste")
			(roundrect_rratio 0.25)
			(net 1 "GND")
			(pintype "passive")
		)
		(pad "2" smd roundrect
			(at 0.48 0 180)
			(size 0.59 0.64)
			(layers "B.Cu" "B.Mask" "B.Paste")
			(roundrect_rratio 0.25)
			(net 8 "+1V2_MGTAVTT")
			(pintype "passive")
		)
	)
	(footprint "antmicro-footprints:C_0402_1005Metric"
		(layer "B.Cu")
		(at 160.5 144.525 -90)
		(descr "Capacitor SMD 0402")
		(tags "capacitor SMD 0402")
		(property "Reference" "C169"
			(at -1.9 3.475 90)
			(layer "B.SilkS")
			(effects
				(font
					(size 0.7 0.7)
					(thickness 0.15)
				)
				(justify left bottom mirror)
			)
		)
		(property "Value" "C_10u_0402"
			(at 0 -1.4 90)
			(layer "B.Fab")
			(effects
				(font
					(size 0.7 0.7)
					(thickness 0.15)
				)
				(justify left bottom mirror)
			)
		)
		(property "Description" "SMD Multilayer Ceramic Capacitor, 10 µF, 6.3 V, 0402 [1005 Metric], ± 20%, X5R, CC Series"
			(at 0 0 270)
			(layer "F.Fab")
			(hide yes)
			(effects
				(font
					(size 1.27 1.27)
					(thickness 0.15)
				)
			)
		)
		(property "Author" "Antmicro"
			(at 15.975 305.025 0)
			(layer "B.Fab")
			(hide yes)
			(effects
				(font
					(size 1 1)
					(thickness 0.15)
				)
				(justify mirror)
			)
		)
		(property "Dielectric" ""
			(at 15.975 305.025 0)
			(layer "B.Fab")
			(hide yes)
			(effects
				(font
					(size 1 1)
					(thickness 0.15)
				)
				(justify mirror)
			)
		)
		(property "License" "Apache-2.0"
			(at 15.975 305.025 0)
			(layer "B.Fab")
			(hide yes)
			(effects
				(font
					(size 1 1)
					(thickness 0.15)
				)
				(justify mirror)
			)
		)
		(property "MPN" "CC0402MRX5R5BB106"
			(at 15.975 305.025 0)
			(layer "B.Fab")
			(hide yes)
			(effects
				(font
					(size 1 1)
					(thickness 0.15)
				)
				(justify mirror)
			)
		)
		(property "Manufacturer" "YAGEO"
			(at 15.975 305.025 0)
			(layer "B.Fab")
			(hide yes)
			(effects
				(font
					(size 1 1)
					(thickness 0.15)
				)
				(justify mirror)
			)
		)
		(property "Val" "10u"
			(at 15.975 305.025 0)
			(layer "B.Fab")
			(hide yes)
			(effects
				(font
					(size 1 1)
					(thickness 0.15)
				)
				(justify mirror)
			)
		)
		(property "Voltage" ""
			(at 15.975 305.025 0)
			(layer "B.Fab")
			(hide yes)
			(effects
				(font
					(size 1 1)
					(thickness 0.15)
				)
				(justify mirror)
			)
		)
		(sheetname "DRAM + SRAM")
		(sheetfile "ram.kicad_sch")
		(attr smd)
		(fp_rect
			(start -0.925 0.47)
			(end 0.925 -0.47)
			(stroke
				(width 0.05)
				(type default)
			)
			(fill no)
			(layer "B.CrtYd")
		)
		(fp_line
			(start -0.494 0.25)
			(end 0.504 0.25)
			(stroke
				(width 0.15)
				(type solid)
			)
			(layer "B.Fab")
		)
		(fp_line
			(start 0.504 0.25)
			(end 0.504 -0.248)
			(stroke
				(width 0.15)
				(type solid)
			)
			(layer "B.Fab")
		)
		(fp_line
			(start -0.494 -0.248)
			(end -0.494 0.25)
			(stroke
				(width 0.15)
				(type solid)
			)
			(layer "B.Fab")
		)
		(fp_line
			(start 0.504 -0.248)
			(end -0.494 -0.248)
			(stroke
				(width 0.15)
				(type solid)
			)
			(layer "B.Fab")
		)
		(pad "1" smd roundrect
			(at -0.48 0 270)
			(size 0.59 0.64)
			(layers "B.Cu" "B.Mask" "B.Paste")
			(roundrect_rratio 0.25)
			(net 1 "GND")
			(pintype "passive")
		)
		(pad "2" smd roundrect
			(at 0.48 0 270)
			(size 0.59 0.64)
			(layers "B.Cu" "B.Mask" "B.Paste")
			(roundrect_rratio 0.25)
			(net 7 "+0V675_VTT")
			(pintype "passive")
		)
	)
	(footprint "antmicro-footprints:C_0402_1005Metric"
		(layer "B.Cu")
		(at 197 135.5 180)
		(descr "Capacitor SMD 0402")
		(tags "capacitor SMD 0402")
		(property "Reference" "C70"
			(at -25.15 28.025 0)
			(layer "B.SilkS")
			(effects
				(font
					(size 0.7 0.7)
					(thickness 0.15)
				)
				(justify left bottom mirror)
			)
		)
		(property "Value" "C_100n_0402"
			(at 0 -1.169 0)
			(layer "B.Fab")
			(effects
				(font
					(size 0.7 0.7)
					(thickness 0.15)
				)
				(justify left bottom mirror)
			)
		)
		(property "Description" "SMD Multilayer Ceramic Capacitor, 0.1 µF, 50 V, 0402 [1005 Metric], ± 10%, X5R, GRM Series"
			(at 0 0 180)
			(layer "F.Fab")
			(hide yes)
			(effects
				(font
					(size 1.27 1.27)
					(thickness 0.15)
				)
			)
		)
		(property "Author" "Antmicro"
			(at 394 271 0)
			(layer "B.Fab")
			(hide yes)
			(effects
				(font
					(size 1 1)
					(thickness 0.15)
				)
				(justify mirror)
			)
		)
		(property "Dielectric" "X5R"
			(at 394 271 0)
			(layer "B.Fab")
			(hide yes)
			(effects
				(font
					(size 1 1)
					(thickness 0.15)
				)
				(justify mirror)
			)
		)
		(property "License" "Apache-2.0"
			(at 394 271 0)
			(layer "B.Fab")
			(hide yes)
			(effects
				(font
					(size 1 1)
					(thickness 0.15)
				)
				(justify mirror)
			)
		)
		(property "MPN" "GRM155R61H104KE14D"
			(at 394 271 0)
			(layer "B.Fab")
			(hide yes)
			(effects
				(font
					(size 1 1)
					(thickness 0.15)
				)
				(justify mirror)
			)
		)
		(property "Manufacturer" "Murata"
			(at 394 271 0)
			(layer "B.Fab")
			(hide yes)
			(effects
				(font
					(size 1 1)
					(thickness 0.15)
				)
				(justify mirror)
			)
		)
		(property "Val" "100n"
			(at 394 271 0)
			(layer "B.Fab")
			(hide yes)
			(effects
				(font
					(size 1 1)
					(thickness 0.15)
				)
				(justify mirror)
			)
		)
		(property "Voltage" "50V"
			(at 394 271 0)
			(layer "B.Fab")
			(hide yes)
			(effects
				(font
					(size 1 1)
					(thickness 0.15)
				)
				(justify mirror)
			)
		)
		(sheetname "FPGA Bank 33 & 34")
		(sheetfile "fpga-bank-33-34.kicad_sch")
		(attr smd)
		(fp_rect
			(start -0.925 0.47)
			(end 0.925 -0.47)
			(stroke
				(width 0.05)
				(type default)
			)
			(fill no)
			(layer "B.CrtYd")
		)
		(fp_line
			(start 0.504 0.25)
			(end 0.504 -0.248)
			(stroke
				(width 0.15)
				(type solid)
			)
			(layer "B.Fab")
		)
		(fp_line
			(start 0.504 -0.248)
			(end -0.494 -0.248)
			(stroke
				(width 0.15)
				(type solid)
			)
			(layer "B.Fab")
		)
		(fp_line
			(start -0.494 0.25)
			(end 0.504 0.25)
			(stroke
				(width 0.15)
				(type solid)
			)
			(layer "B.Fab")
		)
		(fp_line
			(start -0.494 -0.248)
			(end -0.494 0.25)
			(stroke
				(width 0.15)
				(type solid)
			)
			(layer "B.Fab")
		)
		(pad "1" smd roundrect
			(at -0.48 0 180)
			(size 0.59 0.64)
			(layers "B.Cu" "B.Mask" "B.Paste")
			(roundrect_rratio 0.25)
			(net 1 "GND")
			(pintype "passive")
		)
		(pad "2" smd roundrect
			(at 0.48 0 180)
			(size 0.59 0.64)
			(layers "B.Cu" "B.Mask" "B.Paste")
			(roundrect_rratio 0.25)
			(net 26 "+1V8")
			(pintype "passive")
		)
	)
	(footprint "antmicro-footprints:R_0402_1005Metric"
		(layer "B.Cu")
		(at 238.899999 84.699999 90)
		(descr "Resistor SMD 0402")
		(tags "resistor SMD 0402")
		(property "Reference" "R125"
			(at -0.725001 0.425001 270)
			(layer "B.SilkS")
			(effects
				(font
					(size 0.7 0.7)
					(thickness 0.15)
				)
				(justify left bottom mirror)
			)
		)
		(property "Value" "R_100R_0402"
			(at 0 -1.4 270)
			(layer "B.Fab")
			(effects
				(font
					(size 0.7 0.7)
					(thickness 0.15)
				)
				(justify left bottom mirror)
			)
		)
		(property "Description" "SMD Chip Resistor, 100 ohm, ± 1%, 62.5 mW, 0402 [1005 Metric], Thick Film, General Purpose"
			(at 0 0 90)
			(layer "F.Fab")
			(hide yes)
			(effects
				(font
					(size 1.27 1.27)
					(thickness 0.15)
				)
			)
		)
		(property "Author" "Antmicro"
			(at 323.599998 -154.2 0)
			(layer "B.Fab")
			(hide yes)
			(effects
				(font
					(size 1 1)
					(thickness 0.15)
				)
				(justify mirror)
			)
		)
		(property "License" "Apache-2.0"
			(at 323.599998 -154.2 0)
			(layer "B.Fab")
			(hide yes)
			(effects
				(font
					(size 1 1)
					(thickness 0.15)
				)
				(justify mirror)
			)
		)
		(property "MPN" "CR0402-FX-1000GLF"
			(at 323.599998 -154.2 0)
			(layer "B.Fab")
			(hide yes)
			(effects
				(font
					(size 1 1)
					(thickness 0.15)
				)
				(justify mirror)
			)
		)
		(property "Manufacturer" "Bourns"
			(at 323.599998 -154.2 0)
			(layer "B.Fab")
			(hide yes)
			(effects
				(font
					(size 1 1)
					(thickness 0.15)
				)
				(justify mirror)
			)
		)
		(property "Tolerance" "1%"
			(at 323.599998 -154.2 0)
			(layer "B.Fab")
			(hide yes)
			(effects
				(font
					(size 1 1)
					(thickness 0.15)
				)
				(justify mirror)
			)
		)
		(property "Val" "100R"
			(at 323.599998 -154.2 0)
			(layer "B.Fab")
			(hide yes)
			(effects
				(font
					(size 1 1)
					(thickness 0.15)
				)
				(justify mirror)
			)
		)
		(sheetname "User GPIO + LED + button + DIP switch")
		(sheetfile "user-gpio.kicad_sch")
		(attr smd)
		(fp_rect
			(start -0.925 0.47)
			(end 0.925 -0.47)
			(stroke
				(width 0.05)
				(type default)
			)
			(fill no)
			(layer "B.CrtYd")
		)
		(fp_rect
			(start -0.5 0.25)
			(end 0.5 -0.25)
			(stroke
				(width 0.15)
				(type solid)
			)
			(fill no)
			(layer "B.Fab")
		)
		(pad "1" smd roundrect
			(at -0.48 0 90)
			(size 0.59 0.64)
			(layers "B.Cu" "B.Mask" "B.Paste")
			(roundrect_rratio 0.25)
			(net 470 "/FPGA Bank 12 & 13/PMOD_B.IO2")
			(pintype "passive")
		)
		(pad "2" smd roundrect
			(at 0.48 0 90)
			(size 0.59 0.64)
			(layers "B.Cu" "B.Mask" "B.Paste")
			(roundrect_rratio 0.25)
			(net 815 "/User GPIO + LED + button + DIP switch/PMOD_B_2")
			(pintype "passive")
		)
	)
	(footprint "antmicro-footprints:C_0402_1005Metric"
		(layer "B.Cu")
		(at 167.149999 148.924999 90)
		(descr "Capacitor SMD 0402")
		(tags "capacitor SMD 0402")
		(property "Reference" "C179"
			(at -0.775001 0.400001 270)
			(layer "B.SilkS")
			(effects
				(font
					(size 0.7 0.7)
					(thickness 0.15)
				)
				(justify left bottom mirror)
			)
		)
		(property "Value" "C_100n_0402"
			(at 0 -1.169 270)
			(layer "B.Fab")
			(effects
				(font
					(size 0.7 0.7)
					(thickness 0.15)
				)
				(justify left bottom mirror)
			)
		)
		(property "Description" "SMD Multilayer Ceramic Capacitor, 0.1 µF, 50 V, 0402 [1005 Metric], ± 10%, X5R, GRM Series"
			(at 0 0 90)
			(layer "F.Fab")
			(hide yes)
			(effects
				(font
					(size 1.27 1.27)
					(thickness 0.15)
				)
			)
		)
		(property "Author" "Antmicro"
			(at 316.074998 -18.225 0)
			(layer "B.Fab")
			(hide yes)
			(effects
				(font
					(size 1 1)
					(thickness 0.15)
				)
				(justify mirror)
			)
		)
		(property "Dielectric" "X5R"
			(at 316.074998 -18.225 0)
			(layer "B.Fab")
			(hide yes)
			(effects
				(font
					(size 1 1)
					(thickness 0.15)
				)
				(justify mirror)
			)
		)
		(property "License" "Apache-2.0"
			(at 316.074998 -18.225 0)
			(layer "B.Fab")
			(hide yes)
			(effects
				(font
					(size 1 1)
					(thickness 0.15)
				)
				(justify mirror)
			)
		)
		(property "MPN" "GRM155R61H104KE14D"
			(at 316.074998 -18.225 0)
			(layer "B.Fab")
			(hide yes)
			(effects
				(font
					(size 1 1)
					(thickness 0.15)
				)
				(justify mirror)
			)
		)
		(property "Manufacturer" "Murata"
			(at 316.074998 -18.225 0)
			(layer "B.Fab")
			(hide yes)
			(effects
				(font
					(size 1 1)
					(thickness 0.15)
				)
				(justify mirror)
			)
		)
		(property "Val" "100n"
			(at 316.074998 -18.225 0)
			(layer "B.Fab")
			(hide yes)
			(effects
				(font
					(size 1 1)
					(thickness 0.15)
				)
				(justify mirror)
			)
		)
		(property "Voltage" "50V"
			(at 316.074998 -18.225 0)
			(layer "B.Fab")
			(hide yes)
			(effects
				(font
					(size 1 1)
					(thickness 0.15)
				)
				(justify mirror)
			)
		)
		(sheetname "DRAM + SRAM")
		(sheetfile "ram.kicad_sch")
		(attr smd)
		(fp_rect
			(start -0.925 0.47)
			(end 0.925 -0.47)
			(stroke
				(width 0.05)
				(type default)
			)
			(fill no)
			(layer "B.CrtYd")
		)
		(fp_line
			(start 0.504 -0.248)
			(end -0.494 -0.248)
			(stroke
				(width 0.15)
				(type solid)
			)
			(layer "B.Fab")
		)
		(fp_line
			(start -0.494 -0.248)
			(end -0.494 0.25)
			(stroke
				(width 0.15)
				(type solid)
			)
			(layer "B.Fab")
		)
		(fp_line
			(start 0.504 0.25)
			(end 0.504 -0.248)
			(stroke
				(width 0.15)
				(type solid)
			)
			(layer "B.Fab")
		)
		(fp_line
			(start -0.494 0.25)
			(end 0.504 0.25)
			(stroke
				(width 0.15)
				(type solid)
			)
			(layer "B.Fab")
		)
		(pad "1" smd roundrect
			(at -0.48 0 90)
			(size 0.59 0.64)
			(layers "B.Cu" "B.Mask" "B.Paste")
			(roundrect_rratio 0.25)
			(net 1 "GND")
			(pintype "passive")
		)
		(pad "2" smd roundrect
			(at 0.48 0 90)
			(size 0.59 0.64)
			(layers "B.Cu" "B.Mask" "B.Paste")
			(roundrect_rratio 0.25)
			(net 25 "+1V35")
			(pintype "passive")
		)
	)
	(footprint "antmicro-footprints:TP_1206_SMD_RCW-0C"
		(layer "B.Cu")
		(at 214.66 172.89 180)
		(property "Reference" "TP10"
			(at -1.165 1.365 0)
			(layer "B.SilkS")
			(effects
				(font
					(size 0.7 0.7)
					(thickness 0.15)
				)
				(justify left bottom mirror)
			)
		)
		(property "Value" "TP_1206_SMD_RCW-0C"
			(at -4.68 -2.25 0)
			(layer "B.Fab")
			(effects
				(font
					(size 0.7 0.7)
					(thickness 0.15)
				)
				(justify left bottom mirror)
			)
		)
		(property "Description" "Circuit Probe Pad, SMD, Test Point, 1206"
			(at 0 0 180)
			(layer "F.Fab")
			(hide yes)
			(effects
				(font
					(size 1.27 1.27)
					(thickness 0.15)
				)
			)
		)
		(property "Author" "Antmicro"
			(at 429.32 345.78 0)
			(layer "B.Fab")
			(hide yes)
			(effects
				(font
					(size 1 1)
					(thickness 0.15)
				)
				(justify mirror)
			)
		)
		(property "License" "Apache-2.0"
			(at 429.32 345.78 0)
			(layer "B.Fab")
			(hide yes)
			(effects
				(font
					(size 1 1)
					(thickness 0.15)
				)
				(justify mirror)
			)
		)
		(property "MPN" "RCW-0C"
			(at 429.32 345.78 0)
			(layer "B.Fab")
			(hide yes)
			(effects
				(font
					(size 1 1)
					(thickness 0.15)
				)
				(justify mirror)
			)
		)
		(property "Manufacturer" "TE Connectivity"
			(at 429.32 345.78 0)
			(layer "B.Fab")
			(hide yes)
			(effects
				(font
					(size 1 1)
					(thickness 0.15)
				)
				(justify mirror)
			)
		)
		(sheetfile "k410t-devboard.kicad_sch")
		(attr smd)
		(fp_line
			(start 1.78 0.981)
			(end 1.78 0.479)
			(stroke
				(width 0.15)
				(type solid)
			)
			(layer "B.SilkS")
		)
		(fp_line
			(start 1.78 0.981)
			(end 1.281 0.981)
			(stroke
				(width 0.15)
				(type solid)
			)
			(layer "B.SilkS")
		)
		(fp_line
			(start 1.78 -0.982)
			(end 1.78 -0.482)
			(stroke
				(width 0.15)
				(type solid)
			)
			(layer "B.SilkS")
		)
		(fp_line
			(start 1.78 -0.982)
			(end 1.281 -0.982)
			(stroke
				(width 0.15)
				(type solid)
			)
			(layer "B.SilkS")
		)
		(fp_line
			(start -1.779 0.981)
			(end -1.279 0.981)
			(stroke
				(width 0.15)
				(type solid)
			)
			(layer "B.SilkS")
		)
		(fp_line
			(start -1.779 0.981)
			(end -1.779 0.479)
			(stroke
				(width 0.15)
				(type solid)
			)
			(layer "B.SilkS")
		)
		(fp_line
			(start -1.779 -0.482)
			(end -1.779 -0.98)
			(stroke
				(width 0.15)
				(type solid)
			)
			(layer "B.SilkS")
		)
		(fp_line
			(start -1.779 -0.98)
			(end -1.279 -0.98)
			(stroke
				(width 0.15)
				(type solid)
			)
			(layer "B.SilkS")
		)
		(fp_rect
			(start -2.101 1.314)
			(end 2.1 -1.312)
			(stroke
				(width 0.05)
				(type solid)
			)
			(fill no)
			(layer "B.CrtYd")
		)
		(fp_rect
			(start -1.601 0.814)
			(end 1.6 -0.812)
			(stroke
				(width 0.15)
				(type solid)
			)
			(fill no)
			(layer "B.Fab")
		)
		(pad "1" smd rect
			(at 0 0 180)
			(size 3.4 1.8)
			(layers "B.Cu" "B.Mask" "B.Paste")
			(net 1 "GND")
			(pinfunction "1")
			(pintype "passive")
		)
	)
	(footprint "antmicro-footprints:C_0402_1005Metric"
		(layer "B.Cu")
		(at 223.625 130.65)
		(descr "Capacitor SMD 0402")
		(tags "capacitor SMD 0402")
		(property "Reference" "C176"
			(at 1.375 -0.45 180)
			(layer "B.SilkS")
			(effects
				(font
					(size 0.7 0.7)
					(thickness 0.15)
				)
				(justify left bottom mirror)
			)
		)
		(property "Value" "C_100n_0402"
			(at 0 -1.169 180)
			(layer "B.Fab")
			(effects
				(font
					(size 0.7 0.7)
					(thickness 0.15)
				)
				(justify left bottom mirror)
			)
		)
		(property "Description" "SMD Multilayer Ceramic Capacitor, 0.1 µF, 50 V, 0402 [1005 Metric], ± 10%, X5R, GRM Series"
			(at 0 0 0)
			(layer "F.Fab")
			(hide yes)
			(effects
				(font
					(size 1.27 1.27)
					(thickness 0.15)
				)
			)
		)
		(property "Author" "Antmicro"
			(at 0 0 0)
			(layer "B.Fab")
			(hide yes)
			(effects
				(font
					(size 1 1)
					(thickness 0.15)
				)
				(justify mirror)
			)
		)
		(property "Dielectric" "X5R"
			(at 0 0 0)
			(layer "B.Fab")
			(hide yes)
			(effects
				(font
					(size 1 1)
					(thickness 0.15)
				)
				(justify mirror)
			)
		)
		(property "License" "Apache-2.0"
			(at 0 0 0)
			(layer "B.Fab")
			(hide yes)
			(effects
				(font
					(size 1 1)
					(thickness 0.15)
				)
				(justify mirror)
			)
		)
		(property "MPN" "GRM155R61H104KE14D"
			(at 0 0 0)
			(layer "B.Fab")
			(hide yes)
			(effects
				(font
					(size 1 1)
					(thickness 0.15)
				)
				(justify mirror)
			)
		)
		(property "Manufacturer" "Murata"
			(at 0 0 0)
			(layer "B.Fab")
			(hide yes)
			(effects
				(font
					(size 1 1)
					(thickness 0.15)
				)
				(justify mirror)
			)
		)
		(property "Val" "100n"
			(at 0 0 0)
			(layer "B.Fab")
			(hide yes)
			(effects
				(font
					(size 1 1)
					(thickness 0.15)
				)
				(justify mirror)
			)
		)
		(property "Voltage" "50V"
			(at 0 0 0)
			(layer "B.Fab")
			(hide yes)
			(effects
				(font
					(size 1 1)
					(thickness 0.15)
				)
				(justify mirror)
			)
		)
		(sheetname "DRAM + SRAM")
		(sheetfile "ram.kicad_sch")
		(attr smd)
		(fp_rect
			(start -0.925 0.47)
			(end 0.925 -0.47)
			(stroke
				(width 0.05)
				(type default)
			)
			(fill no)
			(layer "B.CrtYd")
		)
		(fp_line
			(start -0.494 -0.248)
			(end -0.494 0.25)
			(stroke
				(width 0.15)
				(type solid)
			)
			(layer "B.Fab")
		)
		(fp_line
			(start -0.494 0.25)
			(end 0.504 0.25)
			(stroke
				(width 0.15)
				(type solid)
			)
			(layer "B.Fab")
		)
		(fp_line
			(start 0.504 -0.248)
			(end -0.494 -0.248)
			(stroke
				(width 0.15)
				(type solid)
			)
			(layer "B.Fab")
		)
		(fp_line
			(start 0.504 0.25)
			(end 0.504 -0.248)
			(stroke
				(width 0.15)
				(type solid)
			)
			(layer "B.Fab")
		)
		(pad "1" smd roundrect
			(at -0.48 0)
			(size 0.59 0.64)
			(layers "B.Cu" "B.Mask" "B.Paste")
			(roundrect_rratio 0.25)
			(net 1 "GND")
			(pintype "passive")
		)
		(pad "2" smd roundrect
			(at 0.48 0)
			(size 0.59 0.64)
			(layers "B.Cu" "B.Mask" "B.Paste")
			(roundrect_rratio 0.25)
			(net 24 "+3V3")
			(pintype "passive")
		)
	)
	(footprint "antmicro-footprints:R_0402_1005Metric"
		(layer "B.Cu")
		(at 197.991252 99.25 90)
		(descr "Resistor SMD 0402")
		(tags "resistor SMD 0402")
		(property "Reference" "R240"
			(at -3.8 0.408748 270)
			(layer "B.SilkS")
			(effects
				(font
					(size 0.7 0.7)
					(thickness 0.15)
				)
				(justify left bottom mirror)
			)
		)
		(property "Value" "R_1k_0402"
			(at 0 -1.4 270)
			(layer "B.Fab")
			(effects
				(font
					(size 0.7 0.7)
					(thickness 0.15)
				)
				(justify left bottom mirror)
			)
		)
		(property "Description" "SMD Chip Resistor, 1 kohm, ± 1%, 63 mW, 0402 [1005 Metric], Thick Film, General Purpose"
			(at 0 0 90)
			(layer "F.Fab")
			(hide yes)
			(effects
				(font
					(size 1.27 1.27)
					(thickness 0.15)
				)
			)
		)
		(property "Author" "Antmicro"
			(at 297.241252 -98.741252 0)
			(layer "B.Fab")
			(hide yes)
			(effects
				(font
					(size 1 1)
					(thickness 0.15)
				)
				(justify mirror)
			)
		)
		(property "License" "Apache-2.0"
			(at 297.241252 -98.741252 0)
			(layer "B.Fab")
			(hide yes)
			(effects
				(font
					(size 1 1)
					(thickness 0.15)
				)
				(justify mirror)
			)
		)
		(property "MPN" "CR0402-FX-1001GLF"
			(at 297.241252 -98.741252 0)
			(layer "B.Fab")
			(hide yes)
			(effects
				(font
					(size 1 1)
					(thickness 0.15)
				)
				(justify mirror)
			)
		)
		(property "Manufacturer" "Bourns"
			(at 297.241252 -98.741252 0)
			(layer "B.Fab")
			(hide yes)
			(effects
				(font
					(size 1 1)
					(thickness 0.15)
				)
				(justify mirror)
			)
		)
		(property "Tolerance" "1%"
			(at 297.241252 -98.741252 0)
			(layer "B.Fab")
			(hide yes)
			(effects
				(font
					(size 1 1)
					(thickness 0.15)
				)
				(justify mirror)
			)
		)
		(property "Val" "1k"
			(at 297.241252 -98.741252 0)
			(layer "B.Fab")
			(hide yes)
			(effects
				(font
					(size 1 1)
					(thickness 0.15)
				)
				(justify mirror)
			)
		)
		(sheetname "HDMI + Ethernet")
		(sheetfile "hdmi-ethernet.kicad_sch")
		(attr smd)
		(fp_rect
			(start -0.925 0.47)
			(end 0.925 -0.47)
			(stroke
				(width 0.05)
				(type default)
			)
			(fill no)
			(layer "B.CrtYd")
		)
		(fp_rect
			(start -0.5 0.25)
			(end 0.5 -0.25)
			(stroke
				(width 0.15)
				(type solid)
			)
			(fill no)
			(layer "B.Fab")
		)
		(pad "1" smd roundrect
			(at -0.48 0 90)
			(size 0.59 0.64)
			(layers "B.Cu" "B.Mask" "B.Paste")
			(roundrect_rratio 0.25)
			(net 24 "+3V3")
			(pintype "passive")
		)
		(pad "2" smd roundrect
			(at 0.48 0 90)
			(size 0.59 0.64)
			(layers "B.Cu" "B.Mask" "B.Paste")
			(roundrect_rratio 0.25)
			(net 523 "/FPGA Bank 16 & 17/GBE_RGMII.MDIO")
			(pintype "passive")
		)
	)
	(footprint "antmicro-footprints:C_0603_1608Metric"
		(layer "B.Cu")
		(at 161.8 144.4 -90)
		(descr "Capacitor SMD 0603")
		(tags "capacitor 0603")
		(property "Reference" "C167"
			(at -3.95 -0.375 90)
			(layer "B.SilkS")
			(effects
				(font
					(size 0.7 0.7)
					(thickness 0.15)
				)
				(justify left bottom mirror)
			)
		)
		(property "Value" "C_47u_0603"
			(at 0 -1.6 90)
			(layer "B.Fab")
			(effects
				(font
					(size 0.7 0.7)
					(thickness 0.15)
				)
				(justify left bottom mirror)
			)
		)
		(property "Description" "SMD Multilayer Ceramic Capacitor, 47 µF, 6.3 V, 0603 [1608 Metric], ± 20%, X5R, GRM Series"
			(at 0 0 270)
			(layer "F.Fab")
			(hide yes)
			(effects
				(font
					(size 1.27 1.27)
					(thickness 0.15)
				)
			)
		)
		(property "Author" "Antmicro"
			(at 17.4 306.2 0)
			(layer "B.Fab")
			(hide yes)
			(effects
				(font
					(size 1 1)
					(thickness 0.15)
				)
				(justify mirror)
			)
		)
		(property "Dielectric" ""
			(at 17.4 306.2 0)
			(layer "B.Fab")
			(hide yes)
			(effects
				(font
					(size 1 1)
					(thickness 0.15)
				)
				(justify mirror)
			)
		)
		(property "License" "Apache-2.0"
			(at 17.4 306.2 0)
			(layer "B.Fab")
			(hide yes)
			(effects
				(font
					(size 1 1)
					(thickness 0.15)
				)
				(justify mirror)
			)
		)
		(property "MPN" "GRM188R60J476ME15D"
			(at 17.4 306.2 0)
			(layer "B.Fab")
			(hide yes)
			(effects
				(font
					(size 1 1)
					(thickness 0.15)
				)
				(justify mirror)
			)
		)
		(property "Manufacturer" "Murata"
			(at 17.4 306.2 0)
			(layer "B.Fab")
			(hide yes)
			(effects
				(font
					(size 1 1)
					(thickness 0.15)
				)
				(justify mirror)
			)
		)
		(property "Val" "47u"
			(at 17.4 306.2 0)
			(layer "B.Fab")
			(hide yes)
			(effects
				(font
					(size 1 1)
					(thickness 0.15)
				)
				(justify mirror)
			)
		)
		(property "Voltage" ""
			(at 17.4 306.2 0)
			(layer "B.Fab")
			(hide yes)
			(effects
				(font
					(size 1 1)
					(thickness 0.15)
				)
				(justify mirror)
			)
		)
		(sheetname "DRAM + SRAM")
		(sheetfile "ram.kicad_sch")
		(attr smd)
		(fp_line
			(start -0.15 0.4)
			(end 0.15 0.4)
			(stroke
				(width 0.15)
				(type solid)
			)
			(layer "B.SilkS")
		)
		(fp_line
			(start -0.15 -0.4)
			(end 0.15 -0.4)
			(stroke
				(width 0.15)
				(type solid)
			)
			(layer "B.SilkS")
		)
		(fp_rect
			(start -1.25 0.65)
			(end 1.25 -0.65)
			(stroke
				(width 0.05)
				(type solid)
			)
			(fill no)
			(layer "B.CrtYd")
		)
		(fp_rect
			(start -0.8 0.4)
			(end 0.8 -0.4)
			(stroke
				(width 0.15)
				(type solid)
			)
			(fill no)
			(layer "B.Fab")
		)
		(pad "1" smd roundrect
			(at -0.7 0 270)
			(size 0.8 1)
			(layers "B.Cu" "B.Mask" "B.Paste")
			(roundrect_rratio 0.2)
			(net 1 "GND")
			(pintype "passive")
		)
		(pad "2" smd roundrect
			(at 0.7 0 270)
			(size 0.8 1)
			(layers "B.Cu" "B.Mask" "B.Paste")
			(roundrect_rratio 0.2)
			(net 7 "+0V675_VTT")
			(pintype "passive")
		)
	)
	(footprint "antmicro-footprints:C_0402_1005Metric"
		(layer "B.Cu")
		(at 208 124.5 180)
		(descr "Capacitor SMD 0402")
		(tags "capacitor SMD 0402")
		(property "Reference" "C20"
			(at -1.075 0.45 0)
			(layer "B.SilkS")
			(effects
				(font
					(size 0.7 0.7)
					(thickness 0.15)
				)
				(justify left bottom mirror)
			)
		)
		(property "Value" "C_100n_0402"
			(at 0 -1.169 0)
			(layer "B.Fab")
			(effects
				(font
					(size 0.7 0.7)
					(thickness 0.15)
				)
				(justify left bottom mirror)
			)
		)
		(property "Description" "SMD Multilayer Ceramic Capacitor, 0.1 µF, 50 V, 0402 [1005 Metric], ± 10%, X5R, GRM Series"
			(at 0 0 180)
			(layer "F.Fab")
			(hide yes)
			(effects
				(font
					(size 1.27 1.27)
					(thickness 0.15)
				)
			)
		)
		(property "Author" "Antmicro"
			(at 416 249 0)
			(layer "B.Fab")
			(hide yes)
			(effects
				(font
					(size 1 1)
					(thickness 0.15)
				)
				(justify mirror)
			)
		)
		(property "Dielectric" "X5R"
			(at 416 249 0)
			(layer "B.Fab")
			(hide yes)
			(effects
				(font
					(size 1 1)
					(thickness 0.15)
				)
				(justify mirror)
			)
		)
		(property "License" "Apache-2.0"
			(at 416 249 0)
			(layer "B.Fab")
			(hide yes)
			(effects
				(font
					(size 1 1)
					(thickness 0.15)
				)
				(justify mirror)
			)
		)
		(property "MPN" "GRM155R61H104KE14D"
			(at 416 249 0)
			(layer "B.Fab")
			(hide yes)
			(effects
				(font
					(size 1 1)
					(thickness 0.15)
				)
				(justify mirror)
			)
		)
		(property "Manufacturer" "Murata"
			(at 416 249 0)
			(layer "B.Fab")
			(hide yes)
			(effects
				(font
					(size 1 1)
					(thickness 0.15)
				)
				(justify mirror)
			)
		)
		(property "Val" "100n"
			(at 416 249 0)
			(layer "B.Fab")
			(hide yes)
			(effects
				(font
					(size 1 1)
					(thickness 0.15)
				)
				(justify mirror)
			)
		)
		(property "Voltage" "50V"
			(at 416 249 0)
			(layer "B.Fab")
			(hide yes)
			(effects
				(font
					(size 1 1)
					(thickness 0.15)
				)
				(justify mirror)
			)
		)
		(sheetname "FPGA Bank 14 & 15")
		(sheetfile "fpga-bank-14-15.kicad_sch")
		(attr smd)
		(fp_rect
			(start -0.925 0.47)
			(end 0.925 -0.47)
			(stroke
				(width 0.05)
				(type default)
			)
			(fill no)
			(layer "B.CrtYd")
		)
		(fp_line
			(start 0.504 0.25)
			(end 0.504 -0.248)
			(stroke
				(width 0.15)
				(type solid)
			)
			(layer "B.Fab")
		)
		(fp_line
			(start 0.504 -0.248)
			(end -0.494 -0.248)
			(stroke
				(width 0.15)
				(type solid)
			)
			(layer "B.Fab")
		)
		(fp_line
			(start -0.494 0.25)
			(end 0.504 0.25)
			(stroke
				(width 0.15)
				(type solid)
			)
			(layer "B.Fab")
		)
		(fp_line
			(start -0.494 -0.248)
			(end -0.494 0.25)
			(stroke
				(width 0.15)
				(type solid)
			)
			(layer "B.Fab")
		)
		(pad "1" smd roundrect
			(at -0.48 0 180)
			(size 0.59 0.64)
			(layers "B.Cu" "B.Mask" "B.Paste")
			(roundrect_rratio 0.25)
			(net 1 "GND")
			(pintype "passive")
		)
		(pad "2" smd roundrect
			(at 0.48 0 180)
			(size 0.59 0.64)
			(layers "B.Cu" "B.Mask" "B.Paste")
			(roundrect_rratio 0.25)
			(net 2 "VCC_USR_A")
			(pintype "passive")
		)
	)
	(footprint "antmicro-footprints:C_0603_1608Metric"
		(layer "B.Cu")
		(at 216.1 123.6 90)
		(descr "Capacitor SMD 0603")
		(tags "capacitor 0603")
		(property "Reference" "C6"
			(at -0.8 1.4 90)
			(layer "B.SilkS")
			(effects
				(font
					(size 0.7 0.7)
					(thickness 0.15)
				)
				(justify right bottom mirror)
			)
		)
		(property "Value" "C_47u_0603"
			(at 0 -1.6 90)
			(layer "B.Fab")
			(effects
				(font
					(size 0.7 0.7)
					(thickness 0.15)
				)
				(justify right bottom mirror)
			)
		)
		(property "Description" "SMD Multilayer Ceramic Capacitor, 47 µF, 6.3 V, 0603 [1608 Metric], ± 20%, X5R, GRM Series"
			(at 0 0 90)
			(layer "F.Fab")
			(hide yes)
			(effects
				(font
					(size 1.27 1.27)
					(thickness 0.15)
				)
			)
		)
		(property "Author" "Antmicro"
			(at 339.7 -92.5 0)
			(layer "B.Fab")
			(hide yes)
			(effects
				(font
					(size 1 1)
					(thickness 0.15)
				)
				(justify mirror)
			)
		)
		(property "Dielectric" ""
			(at 339.7 -92.5 0)
			(layer "B.Fab")
			(hide yes)
			(effects
				(font
					(size 1 1)
					(thickness 0.15)
				)
				(justify mirror)
			)
		)
		(property "License" "Apache-2.0"
			(at 339.7 -92.5 0)
			(layer "B.Fab")
			(hide yes)
			(effects
				(font
					(size 1 1)
					(thickness 0.15)
				)
				(justify mirror)
			)
		)
		(property "MPN" "GRM188R60J476ME15D"
			(at 339.7 -92.5 0)
			(layer "B.Fab")
			(hide yes)
			(effects
				(font
					(size 1 1)
					(thickness 0.15)
				)
				(justify mirror)
			)
		)
		(property "Manufacturer" "Murata"
			(at 339.7 -92.5 0)
			(layer "B.Fab")
			(hide yes)
			(effects
				(font
					(size 1 1)
					(thickness 0.15)
				)
				(justify mirror)
			)
		)
		(property "Val" "47u"
			(at 339.7 -92.5 0)
			(layer "B.Fab")
			(hide yes)
			(effects
				(font
					(size 1 1)
					(thickness 0.15)
				)
				(justify mirror)
			)
		)
		(property "Voltage" ""
			(at 339.7 -92.5 0)
			(layer "B.Fab")
			(hide yes)
			(effects
				(font
					(size 1 1)
					(thickness 0.15)
				)
				(justify mirror)
			)
		)
		(sheetname "FPGA Bank 14 & 15")
		(sheetfile "fpga-bank-14-15.kicad_sch")
		(attr smd)
		(fp_line
			(start -0.15 -0.4)
			(end 0.15 -0.4)
			(stroke
				(width 0.15)
				(type solid)
			)
			(layer "B.SilkS")
		)
		(fp_line
			(start -0.15 0.4)
			(end 0.15 0.4)
			(stroke
				(width 0.15)
				(type solid)
			)
			(layer "B.SilkS")
		)
		(fp_rect
			(start -1.25 0.65)
			(end 1.25 -0.65)
			(stroke
				(width 0.05)
				(type solid)
			)
			(fill no)
			(layer "B.CrtYd")
		)
		(fp_rect
			(start -0.8 0.4)
			(end 0.8 -0.4)
			(stroke
				(width 0.15)
				(type solid)
			)
			(fill no)
			(layer "B.Fab")
		)
		(pad "1" smd roundrect
			(at -0.7 0 90)
			(size 0.8 1)
			(layers "B.Cu" "B.Mask" "B.Paste")
			(roundrect_rratio 0.2)
			(net 1 "GND")
			(pintype "passive")
		)
		(pad "2" smd roundrect
			(at 0.7 0 90)
			(size 0.8 1)
			(layers "B.Cu" "B.Mask" "B.Paste")
			(roundrect_rratio 0.2)
			(net 2 "VCC_USR_A")
			(pintype "passive")
		)
	)
	(footprint "antmicro-footprints:C_0201"
		(layer "B.Cu")
		(at 192.3 120.2 -45)
		(descr "Capacitor SMD 0201")
		(tags "capacitor SMD 0201")
		(property "Reference" "C115"
			(at -4.348707 -36.027091 315)
			(unlocked yes)
			(layer "B.SilkS")
			(effects
				(font
					(size 0.7 0.7)
					(thickness 0.15)
				)
				(justify left bottom mirror)
			)
		)
		(property "Value" "C_100n_0201"
			(at 0 -1.399999 135)
			(layer "B.Fab")
			(effects
				(font
					(size 0.7 0.7)
					(thickness 0.15)
				)
				(justify left bottom mirror)
			)
		)
		(property "Description" "SMD Multilayer Ceramic Capacitor, 0.1 µF, 6.3 V, 0201 [0603 Metric], ± 10%, X6S, CC Series"
			(at 0 0 315)
			(layer "F.Fab")
			(hide yes)
			(effects
				(font
					(size 1.27 1.27)
					(thickness 0.15)
				)
			)
		)
		(property "Author" "Antmicro"
			(at -28.670869 171.182399 0)
			(layer "B.Fab")
			(hide yes)
			(effects
				(font
					(size 1 1)
					(thickness 0.15)
				)
				(justify mirror)
			)
		)
		(property "Dielectric" ""
			(at -28.670869 171.182399 0)
			(layer "B.Fab")
			(hide yes)
			(effects
				(font
					(size 1 1)
					(thickness 0.15)
				)
				(justify mirror)
			)
		)
		(property "License" "Apache-2.0"
			(at -28.670869 171.182399 0)
			(layer "B.Fab")
			(hide yes)
			(effects
				(font
					(size 1 1)
					(thickness 0.15)
				)
				(justify mirror)
			)
		)
		(property "MPN" "CC0201KRX6S5BB104"
			(at -28.670869 171.182399 0)
			(layer "B.Fab")
			(hide yes)
			(effects
				(font
					(size 1 1)
					(thickness 0.15)
				)
				(justify mirror)
			)
		)
		(property "Manufacturer" "YAGEO"
			(at -28.670869 171.182399 0)
			(layer "B.Fab")
			(hide yes)
			(effects
				(font
					(size 1 1)
					(thickness 0.15)
				)
				(justify mirror)
			)
		)
		(property "Val" "100n"
			(at -28.670869 171.182399 0)
			(layer "B.Fab")
			(hide yes)
			(effects
				(font
					(size 1 1)
					(thickness 0.15)
				)
				(justify mirror)
			)
		)
		(property "Voltage" ""
			(at -28.670869 171.182399 0)
			(layer "B.Fab")
			(hide yes)
			(effects
				(font
					(size 1 1)
					(thickness 0.15)
				)
				(justify mirror)
			)
		)
		(sheetname "FPGA supply")
		(sheetfile "fpga-supply.kicad_sch")
		(attr smd)
		(fp_poly
			(pts
				(xy -0.7 0.35) (xy 0.7 0.35) (xy 0.7 -0.35) (xy -0.7 -0.35)
			)
			(stroke
				(width 0.05)
				(type default)
			)
			(fill no)
			(layer "B.CrtYd")
		)
		(fp_poly
			(pts
				(xy 0.3 -0.15) (xy -0.301 -0.15) (xy -0.301 0.149) (xy 0.3 0.149)
			)
			(stroke
				(width 0.15)
				(type solid)
			)
			(fill no)
			(layer "B.Fab")
		)
		(pad "" smd roundrect
			(at -0.349 0.002 315)
			(size 0.318 0.36)
			(layers "B.Paste")
			(roundrect_rratio 0.25)
		)
		(pad "" smd roundrect
			(at 0.341 0.002 315)
			(size 0.318 0.36)
			(layers "B.Paste")
			(roundrect_rratio 0.25)
		)
		(pad "1" smd roundrect
			(at -0.321 0.002 315)
			(size 0.46 0.4)
			(layers "B.Cu" "B.Mask")
			(roundrect_rratio 0.25)
			(net 6 "+1V0_MGTAVCC")
			(pintype "passive")
		)
		(pad "2" smd roundrect
			(at 0.32 0.002 315)
			(size 0.46 0.4)
			(layers "B.Cu" "B.Mask")
			(roundrect_rratio 0.25)
			(net 1 "GND")
			(pintype "passive")
		)
	)
	(footprint "antmicro-footprints:C_0603_1608Metric"
		(layer "B.Cu")
		(at 198.025 130)
		(descr "Capacitor SMD 0603")
		(tags "capacitor 0603")
		(property "Reference" "C379"
			(at 23.575 -28.125 0)
			(layer "B.SilkS")
			(effects
				(font
					(size 0.7 0.7)
					(thickness 0.15)
				)
				(justify right bottom mirror)
			)
		)
		(property "Value" "C_47u_0603"
			(at 0 -1.6 0)
			(layer "B.Fab")
			(effects
				(font
					(size 0.7 0.7)
					(thickness 0.15)
				)
				(justify right bottom mirror)
			)
		)
		(property "Description" "SMD Multilayer Ceramic Capacitor, 47 µF, 6.3 V, 0603 [1608 Metric], ± 20%, X5R, GRM Series"
			(at 0 0 0)
			(layer "F.Fab")
			(hide yes)
			(effects
				(font
					(size 1.27 1.27)
					(thickness 0.15)
				)
			)
		)
		(property "Author" "Antmicro"
			(at 0 0 0)
			(layer "B.Fab")
			(hide yes)
			(effects
				(font
					(size 1 1)
					(thickness 0.15)
				)
				(justify mirror)
			)
		)
		(property "Dielectric" ""
			(at 0 0 0)
			(layer "B.Fab")
			(hide yes)
			(effects
				(font
					(size 1 1)
					(thickness 0.15)
				)
				(justify mirror)
			)
		)
		(property "License" "Apache-2.0"
			(at 0 0 0)
			(layer "B.Fab")
			(hide yes)
			(effects
				(font
					(size 1 1)
					(thickness 0.15)
				)
				(justify mirror)
			)
		)
		(property "MPN" "GRM188R60J476ME15D"
			(at 0 0 0)
			(layer "B.Fab")
			(hide yes)
			(effects
				(font
					(size 1 1)
					(thickness 0.15)
				)
				(justify mirror)
			)
		)
		(property "Manufacturer" "Murata"
			(at 0 0 0)
			(layer "B.Fab")
			(hide yes)
			(effects
				(font
					(size 1 1)
					(thickness 0.15)
				)
				(justify mirror)
			)
		)
		(property "Val" "47u"
			(at 0 0 0)
			(layer "B.Fab")
			(hide yes)
			(effects
				(font
					(size 1 1)
					(thickness 0.15)
				)
				(justify mirror)
			)
		)
		(property "Voltage" ""
			(at 0 0 0)
			(layer "B.Fab")
			(hide yes)
			(effects
				(font
					(size 1 1)
					(thickness 0.15)
				)
				(justify mirror)
			)
		)
		(sheetname "FPGA supply")
		(sheetfile "fpga-supply.kicad_sch")
		(attr smd)
		(fp_line
			(start -0.15 -0.4)
			(end 0.15 -0.4)
			(stroke
				(width 0.15)
				(type solid)
			)
			(layer "B.SilkS")
		)
		(fp_line
			(start -0.15 0.4)
			(end 0.15 0.4)
			(stroke
				(width 0.15)
				(type solid)
			)
			(layer "B.SilkS")
		)
		(fp_rect
			(start -1.25 0.65)
			(end 1.25 -0.65)
			(stroke
				(width 0.05)
				(type solid)
			)
			(fill no)
			(layer "B.CrtYd")
		)
		(fp_rect
			(start -0.8 0.4)
			(end 0.8 -0.4)
			(stroke
				(width 0.15)
				(type solid)
			)
			(fill no)
			(layer "B.Fab")
		)
		(pad "1" smd roundrect
			(at -0.7 0)
			(size 0.8 1)
			(layers "B.Cu" "B.Mask" "B.Paste")
			(roundrect_rratio 0.2)
			(net 1 "GND")
			(pintype "passive")
		)
		(pad "2" smd roundrect
			(at 0.7 0)
			(size 0.8 1)
			(layers "B.Cu" "B.Mask" "B.Paste")
			(roundrect_rratio 0.2)
			(net 650 "+1V0")
			(pintype "passive")
		)
	)
	(footprint "antmicro-footprints:R_0402_1005Metric"
		(layer "B.Cu")
		(at 160 185.9 -90)
		(descr "Resistor SMD 0402")
		(tags "resistor SMD 0402")
		(property "Reference" "R293"
			(at -3.6 -0.4 90)
			(layer "B.SilkS")
			(effects
				(font
					(size 0.7 0.7)
					(thickness 0.15)
				)
				(justify left bottom mirror)
			)
		)
		(property "Value" "R_47k_0402"
			(at 0 -1.4 90)
			(layer "B.Fab")
			(effects
				(font
					(size 0.7 0.7)
					(thickness 0.15)
				)
				(justify left bottom mirror)
			)
		)
		(property "Description" "SMD Chip Resistor, 47 kohm, ± 1%, 62.5 mW, 0402 [1005 Metric], Thick Film, General Purpose"
			(at 0 0 270)
			(layer "F.Fab")
			(hide yes)
			(effects
				(font
					(size 1.27 1.27)
					(thickness 0.15)
				)
			)
		)
		(property "Author" "Antmicro"
			(at -25.9 345.9 0)
			(layer "B.Fab")
			(hide yes)
			(effects
				(font
					(size 1 1)
					(thickness 0.15)
				)
				(justify mirror)
			)
		)
		(property "License" "Apache-2.0"
			(at -25.9 345.9 0)
			(layer "B.Fab")
			(hide yes)
			(effects
				(font
					(size 1 1)
					(thickness 0.15)
				)
				(justify mirror)
			)
		)
		(property "MPN" "CR0402-FX-4702GLF"
			(at -25.9 345.9 0)
			(layer "B.Fab")
			(hide yes)
			(effects
				(font
					(size 1 1)
					(thickness 0.15)
				)
				(justify mirror)
			)
		)
		(property "Manufacturer" "Bourns"
			(at -25.9 345.9 0)
			(layer "B.Fab")
			(hide yes)
			(effects
				(font
					(size 1 1)
					(thickness 0.15)
				)
				(justify mirror)
			)
		)
		(property "Tolerance" "1%"
			(at -25.9 345.9 0)
			(layer "B.Fab")
			(hide yes)
			(effects
				(font
					(size 1 1)
					(thickness 0.15)
				)
				(justify mirror)
			)
		)
		(property "Val" "47k"
			(at -25.9 345.9 0)
			(layer "B.Fab")
			(hide yes)
			(effects
				(font
					(size 1 1)
					(thickness 0.15)
				)
				(justify mirror)
			)
		)
		(sheetname "DC-DC Converters")
		(sheetfile "dc-dc.kicad_sch")
		(attr smd)
		(fp_rect
			(start -0.925 0.47)
			(end 0.925 -0.47)
			(stroke
				(width 0.05)
				(type default)
			)
			(fill no)
			(layer "B.CrtYd")
		)
		(fp_rect
			(start -0.5 0.25)
			(end 0.5 -0.25)
			(stroke
				(width 0.15)
				(type solid)
			)
			(fill no)
			(layer "B.Fab")
		)
		(pad "1" smd roundrect
			(at -0.48 0 270)
			(size 0.59 0.64)
			(layers "B.Cu" "B.Mask" "B.Paste")
			(roundrect_rratio 0.25)
			(net 577 "/DC-DC Converters/PB_CTRL.~{PB_CTRL_INT}")
			(pintype "passive")
		)
		(pad "2" smd roundrect
			(at 0.48 0 270)
			(size 0.59 0.64)
			(layers "B.Cu" "B.Mask" "B.Paste")
			(roundrect_rratio 0.25)
			(net 701 "/DC-DC Converters/PB_CTRL_OUT")
			(pintype "passive")
		)
	)
	(footprint "antmicro-footprints:NetTie-2_SMD_Pad0.127mm"
		(layer "B.Cu")
		(at 248.24 126.45 45)
		(descr "Net tie, 2 pin, 0.127mm  SMD pads")
		(tags "net tie")
		(property "Reference" "NT17"
			(at -0.128 1.345 225)
			(layer "B.SilkS")
			(hide yes)
			(effects
				(font
					(size 0.7 0.7)
					(thickness 0.15)
				)
				(justify left bottom mirror)
			)
		)
		(property "Value" "Net-Tie_2"
			(at 0 -1.199 225)
			(layer "B.Fab")
			(effects
				(font
					(size 0.7 0.7)
					(thickness 0.15)
				)
				(justify left bottom mirror)
			)
		)
		(property "Description" "Net tie, 2 pins"
			(at 0 0 45)
			(layer "F.Fab")
			(hide yes)
			(effects
				(font
					(size 1.27 1.27)
					(thickness 0.15)
				)
			)
		)
		(property "Author" "Antmicro"
			(at 162.121465 -138.49584 0)
			(layer "B.Fab")
			(hide yes)
			(effects
				(font
					(size 1 1)
					(thickness 0.15)
				)
				(justify mirror)
			)
		)
		(property "License" "Apache-2.0"
			(at 162.121465 -138.49584 0)
			(layer "B.Fab")
			(hide yes)
			(effects
				(font
					(size 1 1)
					(thickness 0.15)
				)
				(justify mirror)
			)
		)
		(property "MPN" ""
			(at 162.121465 -138.49584 0)
			(layer "B.Fab")
			(hide yes)
			(effects
				(font
					(size 1 1)
					(thickness 0.15)
				)
				(justify mirror)
			)
		)
		(property "Manufacturer" ""
			(at 162.121465 -138.49584 0)
			(layer "B.Fab")
			(hide yes)
			(effects
				(font
					(size 1 1)
					(thickness 0.15)
				)
				(justify mirror)
			)
		)
		(sheetname "FPGA Bank 12 & 13")
		(sheetfile "fpga-bank-12-13.kicad_sch")
		(attr exclude_from_pos_files)
		(net_tie_pad_groups "1, 2")
		(fp_poly
			(pts
				(xy -0.0635 0.0635) (xy 0.0625 0.0635) (xy 0.0625 -0.0635) (xy -0.0635 -0.0635)
			)
			(stroke
				(width 0)
				(type solid)
			)
			(fill yes)
			(layer "B.Cu")
		)
		(pad "1" smd roundrect
			(at -0.127001 0 225)
			(size 0.127 0.127)
			(layers "B.Cu")
			(roundrect_rratio 0.5)
			(chamfer_ratio 0)
			(chamfer top_left bottom_left)
			(net 1330 "/SUP_MCU.RX1")
			(pinfunction "1")
			(pintype "passive")
		)
		(pad "2" smd roundrect
			(at 0.125999 0 45)
			(size 0.127 0.127)
			(layers "B.Cu")
			(roundrect_rratio 0.5)
			(chamfer_ratio 0)
			(chamfer top_left bottom_left)
			(net 54 "/FPGA Bank 12 & 13/UART1.TX")
			(pinfunction "2")
			(pintype "passive")
		)
	)
	(footprint "antmicro-footprints:SOT-23-3"
		(layer "B.Cu")
		(at 223.5 124.8)
		(property "Reference" "Q12"
			(at 0.9 2.6 180)
			(layer "B.SilkS")
			(effects
				(font
					(size 0.7 0.7)
					(thickness 0.15)
				)
				(justify left bottom mirror)
			)
		)
		(property "Value" "IRLML6344TRPBF"
			(at -1.9 -2.7 180)
			(layer "B.Fab")
			(effects
				(font
					(size 0.7 0.7)
					(thickness 0.15)
				)
				(justify left bottom mirror)
			)
		)
		(property "Description" "Power MOSFET, N Channel, 30 V, 5 A, 0.022 ohm, SOT-23, Surface Mount"
			(at 0 0 0)
			(layer "F.Fab")
			(hide yes)
			(effects
				(font
					(size 1.27 1.27)
					(thickness 0.15)
				)
			)
		)
		(property "Author" "Antmicro"
			(at 0 0 0)
			(layer "B.Fab")
			(hide yes)
			(effects
				(font
					(size 1 1)
					(thickness 0.15)
				)
				(justify mirror)
			)
		)
		(property "License" "Apache-2.0"
			(at 0 0 0)
			(layer "B.Fab")
			(hide yes)
			(effects
				(font
					(size 1 1)
					(thickness 0.15)
				)
				(justify mirror)
			)
		)
		(property "MPN" "IRLML6344TRPBF"
			(at 0 0 0)
			(layer "B.Fab")
			(hide yes)
			(effects
				(font
					(size 1 1)
					(thickness 0.15)
				)
				(justify mirror)
			)
		)
		(property "Manufacturer" "Infineon"
			(at 0 0 0)
			(layer "B.Fab")
			(hide yes)
			(effects
				(font
					(size 1 1)
					(thickness 0.15)
				)
				(justify mirror)
			)
		)
		(sheetname "User GPIO + LED + button + DIP switch")
		(sheetfile "user-gpio.kicad_sch")
		(attr smd)
		(fp_line
			(start -1.45 1.35)
			(end -0.85 1.35)
			(stroke
				(width 0.15)
				(type solid)
			)
			(layer "B.SilkS")
		)
		(fp_line
			(start -0.85 1.35)
			(end -0.7 1.5)
			(stroke
				(width 0.15)
				(type solid)
			)
			(layer "B.SilkS")
		)
		(fp_line
			(start -0.7 -1.5)
			(end -0.7 -1.35)
			(stroke
				(width 0.15)
				(type solid)
			)
			(layer "B.SilkS")
		)
		(fp_line
			(start 0.7 -1.5)
			(end -0.7 -1.5)
			(stroke
				(width 0.15)
				(type solid)
			)
			(layer "B.SilkS")
		)
		(fp_line
			(start 0.7 -0.4)
			(end 0.7 -1.5)
			(stroke
				(width 0.15)
				(type solid)
			)
			(layer "B.SilkS")
		)
		(fp_line
			(start 0.7 0.4)
			(end 0.7 1.5)
			(stroke
				(width 0.15)
				(type solid)
			)
			(layer "B.SilkS")
		)
		(fp_line
			(start 0.7 1.5)
			(end -0.7 1.5)
			(stroke
				(width 0.15)
				(type solid)
			)
			(layer "B.SilkS")
		)
		(fp_line
			(start -1.75 -1.4)
			(end -1.75 -0.5)
			(stroke
				(width 0.05)
				(type solid)
			)
			(layer "B.CrtYd")
		)
		(fp_line
			(start -1.75 -0.5)
			(end -0.85 -0.5)
			(stroke
				(width 0.05)
				(type solid)
			)
			(layer "B.CrtYd")
		)
		(fp_line
			(start -1.75 0.5)
			(end -1.75 1.4)
			(stroke
				(width 0.05)
				(type solid)
			)
			(layer "B.CrtYd")
		)
		(fp_line
			(start -0.9 1.4)
			(end -1.75 1.4)
			(stroke
				(width 0.05)
				(type solid)
			)
			(layer "B.CrtYd")
		)
		(fp_line
			(start -0.9 1.6)
			(end -0.9 1.4)
			(stroke
				(width 0.05)
				(type solid)
			)
			(layer "B.CrtYd")
		)
		(fp_line
			(start -0.9 1.6)
			(end 0.825 1.6)
			(stroke
				(width 0.05)
				(type solid)
			)
			(layer "B.CrtYd")
		)
		(fp_line
			(start -0.85 -1.65)
			(end -0.85 -1.4)
			(stroke
				(width 0.05)
				(type solid)
			)
			(layer "B.CrtYd")
		)
		(fp_line
			(start -0.85 -1.4)
			(end -1.75 -1.4)
			(stroke
				(width 0.05)
				(type solid)
			)
			(layer "B.CrtYd")
		)
		(fp_line
			(start -0.85 -0.5)
			(end -0.85 0.5)
			(stroke
				(width 0.05)
				(type solid)
			)
			(layer "B.CrtYd")
		)
		(fp_line
			(start -0.85 0.5)
			(end -1.75 0.5)
			(stroke
				(width 0.05)
				(type solid)
			)
			(layer "B.CrtYd")
		)
		(fp_line
			(start 0.825 0.45)
			(end 1.75 0.45)
			(stroke
				(width 0.05)
				(type solid)
			)
			(layer "B.CrtYd")
		)
		(fp_line
			(start 0.825 1.6)
			(end 0.825 0.45)
			(stroke
				(width 0.05)
				(type solid)
			)
			(layer "B.CrtYd")
		)
		(fp_line
			(start 0.85 -1.65)
			(end -0.85 -1.65)
			(stroke
				(width 0.05)
				(type solid)
			)
			(layer "B.CrtYd")
		)
		(fp_line
			(start 0.85 -0.45)
			(end 0.85 -1.65)
			(stroke
				(width 0.05)
				(type solid)
			)
			(layer "B.CrtYd")
		)
		(fp_line
			(start 1.75 -0.45)
			(end 0.85 -0.45)
			(stroke
				(width 0.05)
				(type solid)
			)
			(layer "B.CrtYd")
		)
		(fp_line
			(start 1.75 0.45)
			(end 1.75 -0.45)
			(stroke
				(width 0.05)
				(type solid)
			)
			(layer "B.CrtYd")
		)
		(fp_line
			(start -0.712 -1.519)
			(end 0.688 -1.519)
			(stroke
				(width 0.15)
				(type solid)
			)
			(layer "B.Fab")
		)
		(fp_line
			(start -0.712 1.325)
			(end -0.712 -1.523)
			(stroke
				(width 0.15)
				(type solid)
			)
			(layer "B.Fab")
		)
		(fp_line
			(start -0.437 1.526)
			(end -0.712 1.325)
			(stroke
				(width 0.15)
				(type solid)
			)
			(layer "B.Fab")
		)
		(fp_line
			(start -0.437 1.526)
			(end 0.688 1.526)
			(stroke
				(width 0.15)
				(type solid)
			)
			(layer "B.Fab")
		)
		(fp_line
			(start 0.688 -1.519)
			(end 0.688 1.52)
			(stroke
				(width 0.15)
				(type solid)
			)
			(layer "B.Fab")
		)
		(pad "1" smd roundrect
			(at -1.1 0.951)
			(size 1 0.6)
			(layers "B.Cu" "B.Mask" "B.Paste")
			(roundrect_rratio 0.15)
			(net 876 "/User GPIO + LED + button + DIP switch/FAN_PWM_CTRL_AON")
			(pinfunction "G")
			(pintype "bidirectional")
		)
		(pad "2" smd roundrect
			(at -1.1 -0.949)
			(size 1 0.6)
			(layers "B.Cu" "B.Mask" "B.Paste")
			(roundrect_rratio 0.15)
			(net 1 "GND")
			(pinfunction "S")
			(pintype "bidirectional")
		)
		(pad "3" smd roundrect
			(at 1.1 0.0005)
			(size 1 0.6)
			(layers "B.Cu" "B.Mask" "B.Paste")
			(roundrect_rratio 0.15)
			(net 801 "/User GPIO + LED + button + DIP switch/FAN_PWM_PIN")
			(pinfunction "D")
			(pintype "bidirectional")
		)
	)
	(footprint "antmicro-footprints:R_0402_1005Metric"
		(layer "B.Cu")
		(at 219.753 149.216 180)
		(descr "Resistor SMD 0402")
		(tags "resistor SMD 0402")
		(property "Reference" "R225"
			(at 0.753 -0.409 0)
			(layer "B.SilkS")
			(effects
				(font
					(size 0.7 0.7)
					(thickness 0.15)
				)
				(justify left bottom mirror)
			)
		)
		(property "Value" "R_2k2_0402"
			(at 0 -1.4 0)
			(layer "B.Fab")
			(effects
				(font
					(size 0.7 0.7)
					(thickness 0.15)
				)
				(justify left bottom mirror)
			)
		)
		(property "Description" "SMD Chip Resistor, 2.2 kohm, ± 1%, 62.5 mW, 0402 [1005 Metric], Thick Film, General Purpose"
			(at 0 0 180)
			(layer "F.Fab")
			(hide yes)
			(effects
				(font
					(size 1.27 1.27)
					(thickness 0.15)
				)
			)
		)
		(property "Author" "Antmicro"
			(at 439.506 298.432 0)
			(layer "B.Fab")
			(hide yes)
			(effects
				(font
					(size 1 1)
					(thickness 0.15)
				)
				(justify mirror)
			)
		)
		(property "DNP" "DNP"
			(at 439.506 298.432 0)
			(layer "B.Fab")
			(hide yes)
			(effects
				(font
					(size 1 1)
					(thickness 0.15)
				)
				(justify mirror)
			)
		)
		(property "License" "Apache-2.0"
			(at 439.506 298.432 0)
			(layer "B.Fab")
			(hide yes)
			(effects
				(font
					(size 1 1)
					(thickness 0.15)
				)
				(justify mirror)
			)
		)
		(property "MPN" "CR0402-FX-2201GLF"
			(at 439.506 298.432 0)
			(layer "B.Fab")
			(hide yes)
			(effects
				(font
					(size 1 1)
					(thickness 0.15)
				)
				(justify mirror)
			)
		)
		(property "Manufacturer" "Bourns"
			(at 439.506 298.432 0)
			(layer "B.Fab")
			(hide yes)
			(effects
				(font
					(size 1 1)
					(thickness 0.15)
				)
				(justify mirror)
			)
		)
		(property "Tolerance" "1%"
			(at 439.506 298.432 0)
			(layer "B.Fab")
			(hide yes)
			(effects
				(font
					(size 1 1)
					(thickness 0.15)
				)
				(justify mirror)
			)
		)
		(property "Val" "2k2"
			(at 439.506 298.432 0)
			(layer "B.Fab")
			(hide yes)
			(effects
				(font
					(size 1 1)
					(thickness 0.15)
				)
				(justify mirror)
			)
		)
		(property "dnp" ""
			(at 439.506 298.432 0)
			(layer "B.Fab")
			(hide yes)
			(effects
				(font
					(size 1 1)
					(thickness 0.15)
				)
				(justify mirror)
			)
		)
		(property "exclude_from_bom" ""
			(at 439.506 298.432 0)
			(layer "B.Fab")
			(hide yes)
			(effects
				(font
					(size 1 1)
					(thickness 0.15)
				)
				(justify mirror)
			)
		)
		(sheetname "HDMI + Ethernet")
		(sheetfile "hdmi-ethernet.kicad_sch")
		(attr smd exclude_from_bom)
		(fp_rect
			(start -0.925 0.47)
			(end 0.925 -0.47)
			(stroke
				(width 0.05)
				(type default)
			)
			(fill no)
			(layer "B.CrtYd")
		)
		(fp_rect
			(start -0.5 0.25)
			(end 0.5 -0.25)
			(stroke
				(width 0.15)
				(type solid)
			)
			(fill no)
			(layer "B.Fab")
		)
		(pad "1" smd roundrect
			(at -0.48 0 180)
			(size 0.59 0.64)
			(layers "B.Cu" "B.Mask" "B.Paste")
			(roundrect_rratio 0.25)
			(net 944 "/HDMI + Ethernet/ETH_PHY_RX_DV")
			(pintype "passive")
		)
		(pad "2" smd roundrect
			(at 0.48 0 180)
			(size 0.59 0.64)
			(layers "B.Cu" "B.Mask" "B.Paste")
			(roundrect_rratio 0.25)
			(net 1 "GND")
			(pintype "passive")
		)
	)
	(footprint "antmicro-footprints:C_0603_1608Metric"
		(layer "B.Cu")
		(at 200 128.775 -90)
		(descr "Capacitor SMD 0603")
		(tags "capacitor 0603")
		(property "Reference" "C376"
			(at -31.05 -25.75 90)
			(layer "B.SilkS")
			(effects
				(font
					(size 0.7 0.7)
					(thickness 0.15)
				)
				(justify left bottom mirror)
			)
		)
		(property "Value" "C_47u_0603"
			(at 0 -1.6 90)
			(layer "B.Fab")
			(effects
				(font
					(size 0.7 0.7)
					(thickness 0.15)
				)
				(justify left bottom mirror)
			)
		)
		(property "Description" "SMD Multilayer Ceramic Capacitor, 47 µF, 6.3 V, 0603 [1608 Metric], ± 20%, X5R, GRM Series"
			(at 0 0 270)
			(layer "F.Fab")
			(hide yes)
			(effects
				(font
					(size 1.27 1.27)
					(thickness 0.15)
				)
			)
		)
		(property "Author" "Antmicro"
			(at 71.225 328.775 0)
			(layer "B.Fab")
			(hide yes)
			(effects
				(font
					(size 1 1)
					(thickness 0.15)
				)
				(justify mirror)
			)
		)
		(property "Dielectric" ""
			(at 71.225 328.775 0)
			(layer "B.Fab")
			(hide yes)
			(effects
				(font
					(size 1 1)
					(thickness 0.15)
				)
				(justify mirror)
			)
		)
		(property "License" "Apache-2.0"
			(at 71.225 328.775 0)
			(layer "B.Fab")
			(hide yes)
			(effects
				(font
					(size 1 1)
					(thickness 0.15)
				)
				(justify mirror)
			)
		)
		(property "MPN" "GRM188R60J476ME15D"
			(at 71.225 328.775 0)
			(layer "B.Fab")
			(hide yes)
			(effects
				(font
					(size 1 1)
					(thickness 0.15)
				)
				(justify mirror)
			)
		)
		(property "Manufacturer" "Murata"
			(at 71.225 328.775 0)
			(layer "B.Fab")
			(hide yes)
			(effects
				(font
					(size 1 1)
					(thickness 0.15)
				)
				(justify mirror)
			)
		)
		(property "Val" "47u"
			(at 71.225 328.775 0)
			(layer "B.Fab")
			(hide yes)
			(effects
				(font
					(size 1 1)
					(thickness 0.15)
				)
				(justify mirror)
			)
		)
		(property "Voltage" ""
			(at 71.225 328.775 0)
			(layer "B.Fab")
			(hide yes)
			(effects
				(font
					(size 1 1)
					(thickness 0.15)
				)
				(justify mirror)
			)
		)
		(sheetname "FPGA supply")
		(sheetfile "fpga-supply.kicad_sch")
		(attr smd)
		(fp_line
			(start -0.15 0.4)
			(end 0.15 0.4)
			(stroke
				(width 0.15)
				(type solid)
			)
			(layer "B.SilkS")
		)
		(fp_line
			(start -0.15 -0.4)
			(end 0.15 -0.4)
			(stroke
				(width 0.15)
				(type solid)
			)
			(layer "B.SilkS")
		)
		(fp_rect
			(start -1.25 0.65)
			(end 1.25 -0.65)
			(stroke
				(width 0.05)
				(type solid)
			)
			(fill no)
			(layer "B.CrtYd")
		)
		(fp_rect
			(start -0.8 0.4)
			(end 0.8 -0.4)
			(stroke
				(width 0.15)
				(type solid)
			)
			(fill no)
			(layer "B.Fab")
		)
		(pad "1" smd roundrect
			(at -0.7 0 270)
			(size 0.8 1)
			(layers "B.Cu" "B.Mask" "B.Paste")
			(roundrect_rratio 0.2)
			(net 1 "GND")
			(pintype "passive")
		)
		(pad "2" smd roundrect
			(at 0.7 0 270)
			(size 0.8 1)
			(layers "B.Cu" "B.Mask" "B.Paste")
			(roundrect_rratio 0.2)
			(net 650 "+1V0")
			(pintype "passive")
		)
	)
	(footprint "antmicro-footprints:C_0402_1005Metric"
		(layer "B.Cu")
		(at 190.275 136.05 -90)
		(descr "Capacitor SMD 0402")
		(tags "capacitor SMD 0402")
		(property "Reference" "C10"
			(at -30.025 -21.925 90)
			(layer "B.SilkS")
			(effects
				(font
					(size 0.7 0.7)
					(thickness 0.15)
				)
				(justify left bottom mirror)
			)
		)
		(property "Value" "C_100n_0402"
			(at 0 -1.169 90)
			(layer "B.Fab")
			(effects
				(font
					(size 0.7 0.7)
					(thickness 0.15)
				)
				(justify left bottom mirror)
			)
		)
		(property "Description" "SMD Multilayer Ceramic Capacitor, 0.1 µF, 50 V, 0402 [1005 Metric], ± 10%, X5R, GRM Series"
			(at 0 0 270)
			(layer "F.Fab")
			(hide yes)
			(effects
				(font
					(size 1.27 1.27)
					(thickness 0.15)
				)
			)
		)
		(property "Author" "Antmicro"
			(at 54.225 326.325 0)
			(layer "B.Fab")
			(hide yes)
			(effects
				(font
					(size 1 1)
					(thickness 0.15)
				)
				(justify mirror)
			)
		)
		(property "Dielectric" "X5R"
			(at 54.225 326.325 0)
			(layer "B.Fab")
			(hide yes)
			(effects
				(font
					(size 1 1)
					(thickness 0.15)
				)
				(justify mirror)
			)
		)
		(property "License" "Apache-2.0"
			(at 54.225 326.325 0)
			(layer "B.Fab")
			(hide yes)
			(effects
				(font
					(size 1 1)
					(thickness 0.15)
				)
				(justify mirror)
			)
		)
		(property "MPN" "GRM155R61H104KE14D"
			(at 54.225 326.325 0)
			(layer "B.Fab")
			(hide yes)
			(effects
				(font
					(size 1 1)
					(thickness 0.15)
				)
				(justify mirror)
			)
		)
		(property "Manufacturer" "Murata"
			(at 54.225 326.325 0)
			(layer "B.Fab")
			(hide yes)
			(effects
				(font
					(size 1 1)
					(thickness 0.15)
				)
				(justify mirror)
			)
		)
		(property "Val" "100n"
			(at 54.225 326.325 0)
			(layer "B.Fab")
			(hide yes)
			(effects
				(font
					(size 1 1)
					(thickness 0.15)
				)
				(justify mirror)
			)
		)
		(property "Voltage" "50V"
			(at 54.225 326.325 0)
			(layer "B.Fab")
			(hide yes)
			(effects
				(font
					(size 1 1)
					(thickness 0.15)
				)
				(justify mirror)
			)
		)
		(sheetname "FPGA Config")
		(sheetfile "fpga-config.kicad_sch")
		(attr smd)
		(fp_rect
			(start -0.925 0.47)
			(end 0.925 -0.47)
			(stroke
				(width 0.05)
				(type default)
			)
			(fill no)
			(layer "B.CrtYd")
		)
		(fp_line
			(start -0.494 0.25)
			(end 0.504 0.25)
			(stroke
				(width 0.15)
				(type solid)
			)
			(layer "B.Fab")
		)
		(fp_line
			(start 0.504 0.25)
			(end 0.504 -0.248)
			(stroke
				(width 0.15)
				(type solid)
			)
			(layer "B.Fab")
		)
		(fp_line
			(start -0.494 -0.248)
			(end -0.494 0.25)
			(stroke
				(width 0.15)
				(type solid)
			)
			(layer "B.Fab")
		)
		(fp_line
			(start 0.504 -0.248)
			(end -0.494 -0.248)
			(stroke
				(width 0.15)
				(type solid)
			)
			(layer "B.Fab")
		)
		(pad "1" smd roundrect
			(at -0.48 0 270)
			(size 0.59 0.64)
			(layers "B.Cu" "B.Mask" "B.Paste")
			(roundrect_rratio 0.25)
			(net 1 "GND")
			(pintype "passive")
		)
		(pad "2" smd roundrect
			(at 0.48 0 270)
			(size 0.59 0.64)
			(layers "B.Cu" "B.Mask" "B.Paste")
			(roundrect_rratio 0.25)
			(net 24 "+3V3")
			(pintype "passive")
		)
	)
	(footprint "antmicro-footprints:Coax_Conn_U.FL"
		(layer "B.Cu")
		(at 220.44 136.3 90)
		(descr "https://media.digikey.com/pdf/Data%20Sheets/Hirose%20PDFs/UFL%20Series.pdf")
		(property "Reference" "J3"
			(at -2.16 2.19 270)
			(layer "B.SilkS")
			(effects
				(font
					(size 0.7 0.7)
					(thickness 0.15)
				)
				(justify left bottom mirror)
			)
		)
		(property "Value" "U_FL-R-SMT-1"
			(at -4.13 -2.52 270)
			(layer "B.Fab")
			(effects
				(font
					(size 0.7 0.7)
					(thickness 0.15)
				)
				(justify left bottom mirror)
			)
		)
		(property "Description" "U.FL (UMCC) Connector Receptacle, Male Pin 50Ohm Surface Mount Solder"
			(at 0 0 90)
			(layer "F.Fab")
			(hide yes)
			(effects
				(font
					(size 1.27 1.27)
					(thickness 0.15)
				)
			)
		)
		(property "Author" "Antmicro"
			(at 356.74 -84.14 0)
			(layer "B.Fab")
			(hide yes)
			(effects
				(font
					(size 1 1)
					(thickness 0.15)
				)
				(justify mirror)
			)
		)
		(property "License" "Apache-2.0"
			(at 356.74 -84.14 0)
			(layer "B.Fab")
			(hide yes)
			(effects
				(font
					(size 1 1)
					(thickness 0.15)
				)
				(justify mirror)
			)
		)
		(property "MPN" "U.FL-R-SMT-1(10)"
			(at 356.74 -84.14 0)
			(layer "B.Fab")
			(hide yes)
			(effects
				(font
					(size 1 1)
					(thickness 0.15)
				)
				(justify mirror)
			)
		)
		(property "Manufacturer" "Hirose Electric"
			(at 356.74 -84.14 0)
			(layer "B.Fab")
			(hide yes)
			(effects
				(font
					(size 1 1)
					(thickness 0.15)
				)
				(justify mirror)
			)
		)
		(sheetname "Clocks")
		(sheetfile "clocks.kicad_sch")
		(attr smd)
		(fp_line
			(start 1.588 -1.648)
			(end 1.088 -1.648)
			(stroke
				(width 0.15)
				(type solid)
			)
			(layer "B.SilkS")
		)
		(fp_line
			(start 1.588 -1.648)
			(end 1.588 -1.325)
			(stroke
				(width 0.15)
				(type solid)
			)
			(layer "B.SilkS")
		)
		(fp_line
			(start -1.613 -1.648)
			(end -1.113 -1.648)
			(stroke
				(width 0.15)
				(type solid)
			)
			(layer "B.SilkS")
		)
		(fp_line
			(start -1.613 -1.648)
			(end -1.613 -1.325)
			(stroke
				(width 0.15)
				(type solid)
			)
			(layer "B.SilkS")
		)
		(fp_line
			(start 1.588 1.651)
			(end 1.588 1.325)
			(stroke
				(width 0.15)
				(type solid)
			)
			(layer "B.SilkS")
		)
		(fp_line
			(start 1.588 1.651)
			(end 1.088 1.651)
			(stroke
				(width 0.15)
				(type solid)
			)
			(layer "B.SilkS")
		)
		(fp_line
			(start -1.613 1.651)
			(end -1.613 1.325)
			(stroke
				(width 0.15)
				(type solid)
			)
			(layer "B.SilkS")
		)
		(fp_line
			(start -1.613 1.651)
			(end -1.113 1.651)
			(stroke
				(width 0.15)
				(type solid)
			)
			(layer "B.SilkS")
		)
		(fp_rect
			(start -2 2.051)
			(end 1.999 -2.05)
			(stroke
				(width 0.05)
				(type solid)
			)
			(fill no)
			(layer "B.CrtYd")
		)
		(fp_line
			(start 1.487 -1.55)
			(end 1.487 1.551)
			(stroke
				(width 0.15)
				(type solid)
			)
			(layer "B.Fab")
		)
		(fp_line
			(start -1.512 -1.55)
			(end 1.487 -1.55)
			(stroke
				(width 0.15)
				(type solid)
			)
			(layer "B.Fab")
		)
		(fp_line
			(start -1.512 -1.55)
			(end -1.512 1.551)
			(stroke
				(width 0.15)
				(type solid)
			)
			(layer "B.Fab")
		)
		(fp_line
			(start -1.512 1.551)
			(end 1.487 1.551)
			(stroke
				(width 0.15)
				(type solid)
			)
			(layer "B.Fab")
		)
		(pad "1" smd rect
			(at -0.012 -1.499 90)
			(size 1 1.05)
			(layers "B.Cu" "B.Mask" "B.Paste")
			(net 1244 "/PLL.CLK0")
			(pintype "passive")
		)
		(pad "SH1" smd rect
			(at 1.463 0 90)
			(size 1.05 2.2)
			(layers "B.Cu" "B.Mask" "B.Paste")
			(net 1 "GND")
			(pintype "passive")
		)
		(pad "SH2" smd rect
			(at -1.488 0 90)
			(size 1.05 2.2)
			(layers "B.Cu" "B.Mask" "B.Paste")
			(net 1 "GND")
			(pintype "passive")
		)
		(zone
			(net 0)
			(net_name "")
			(layer "B.Cu")
			(hatch edge 0.508)
			(connect_pads
				(clearance 0)
			)
			(min_thickness 0.254)
			(filled_areas_thickness no)
			(keepout
				(tracks not_allowed)
				(vias not_allowed)
				(pads not_allowed)
				(copperpour not_allowed)
				(footprints not_allowed)
			)
			(placement
				(enabled no)
				(sheetname "")
			)
			(fill
				(thermal_gap 0.508)
				(thermal_bridge_width 0.508)
			)
			(polygon
				(pts
					(xy 219.48 135.37) (xy 219.48 137.25) (xy 221.54 137.25) (xy 221.54 135.37)
				)
			)
		)
	)
	(footprint "antmicro-footprints:R_0402_1005Metric"
		(layer "B.Cu")
		(at 202.2 92.7 -90)
		(descr "Resistor SMD 0402")
		(tags "resistor SMD 0402")
		(property "Reference" "R215"
			(at -0.9 -2.4 90)
			(layer "B.SilkS")
			(effects
				(font
					(size 0.7 0.7)
					(thickness 0.15)
				)
				(justify left bottom mirror)
			)
		)
		(property "Value" "R_2k2_0402"
			(at 0 -1.4 90)
			(layer "B.Fab")
			(effects
				(font
					(size 0.7 0.7)
					(thickness 0.15)
				)
				(justify left bottom mirror)
			)
		)
		(property "Description" "SMD Chip Resistor, 2.2 kohm, ± 1%, 62.5 mW, 0402 [1005 Metric], Thick Film, General Purpose"
			(at 0 0 270)
			(layer "F.Fab")
			(hide yes)
			(effects
				(font
					(size 1.27 1.27)
					(thickness 0.15)
				)
			)
		)
		(property "Author" "Antmicro"
			(at 109.5 294.9 0)
			(layer "B.Fab")
			(hide yes)
			(effects
				(font
					(size 1 1)
					(thickness 0.15)
				)
				(justify mirror)
			)
		)
		(property "DNP" "DNP"
			(at 109.5 294.9 0)
			(layer "B.Fab")
			(hide yes)
			(effects
				(font
					(size 1 1)
					(thickness 0.15)
				)
				(justify mirror)
			)
		)
		(property "License" "Apache-2.0"
			(at 109.5 294.9 0)
			(layer "B.Fab")
			(hide yes)
			(effects
				(font
					(size 1 1)
					(thickness 0.15)
				)
				(justify mirror)
			)
		)
		(property "MPN" "CR0402-FX-2201GLF"
			(at 109.5 294.9 0)
			(layer "B.Fab")
			(hide yes)
			(effects
				(font
					(size 1 1)
					(thickness 0.15)
				)
				(justify mirror)
			)
		)
		(property "Manufacturer" "Bourns"
			(at 109.5 294.9 0)
			(layer "B.Fab")
			(hide yes)
			(effects
				(font
					(size 1 1)
					(thickness 0.15)
				)
				(justify mirror)
			)
		)
		(property "Tolerance" "1%"
			(at 109.5 294.9 0)
			(layer "B.Fab")
			(hide yes)
			(effects
				(font
					(size 1 1)
					(thickness 0.15)
				)
				(justify mirror)
			)
		)
		(property "Val" "2k2"
			(at 109.5 294.9 0)
			(layer "B.Fab")
			(hide yes)
			(effects
				(font
					(size 1 1)
					(thickness 0.15)
				)
				(justify mirror)
			)
		)
		(property "dnp" ""
			(at 109.5 294.9 0)
			(layer "B.Fab")
			(hide yes)
			(effects
				(font
					(size 1 1)
					(thickness 0.15)
				)
				(justify mirror)
			)
		)
		(property "exclude_from_bom" ""
			(at 109.5 294.9 0)
			(layer "B.Fab")
			(hide yes)
			(effects
				(font
					(size 1 1)
					(thickness 0.15)
				)
				(justify mirror)
			)
		)
		(sheetname "HDMI + Ethernet")
		(sheetfile "hdmi-ethernet.kicad_sch")
		(attr smd exclude_from_bom)
		(fp_rect
			(start -0.925 0.47)
			(end 0.925 -0.47)
			(stroke
				(width 0.05)
				(type default)
			)
			(fill no)
			(layer "B.CrtYd")
		)
		(fp_rect
			(start -0.5 0.25)
			(end 0.5 -0.25)
			(stroke
				(width 0.15)
				(type solid)
			)
			(fill no)
			(layer "B.Fab")
		)
		(pad "1" smd roundrect
			(at -0.48 0 270)
			(size 0.59 0.64)
			(layers "B.Cu" "B.Mask" "B.Paste")
			(roundrect_rratio 0.25)
			(net 851 "/HDMI + Ethernet/GBE_LED_LINK-")
			(pintype "passive")
		)
		(pad "2" smd roundrect
			(at 0.48 0 270)
			(size 0.59 0.64)
			(layers "B.Cu" "B.Mask" "B.Paste")
			(roundrect_rratio 0.25)
			(net 1 "GND")
			(pintype "passive")
		)
	)
	(footprint "antmicro-footprints:R_0402_1005Metric"
		(layer "B.Cu")
		(at 191.9 79.8 90)
		(descr "Resistor SMD 0402")
		(tags "resistor SMD 0402")
		(property "Reference" "R146"
			(at -0.725 0.4 270)
			(layer "B.SilkS")
			(effects
				(font
					(size 0.7 0.7)
					(thickness 0.15)
				)
				(justify left bottom mirror)
			)
		)
		(property "Value" "R_100R_0402"
			(at 0 -1.4 270)
			(layer "B.Fab")
			(effects
				(font
					(size 0.7 0.7)
					(thickness 0.15)
				)
				(justify left bottom mirror)
			)
		)
		(property "Description" "SMD Chip Resistor, 100 ohm, ± 1%, 62.5 mW, 0402 [1005 Metric], Thick Film, General Purpose"
			(at 0 0 90)
			(layer "F.Fab")
			(hide yes)
			(effects
				(font
					(size 1.27 1.27)
					(thickness 0.15)
				)
			)
		)
		(property "Author" "Antmicro"
			(at 271.7 -112.1 0)
			(layer "B.Fab")
			(hide yes)
			(effects
				(font
					(size 1 1)
					(thickness 0.15)
				)
				(justify mirror)
			)
		)
		(property "License" "Apache-2.0"
			(at 271.7 -112.1 0)
			(layer "B.Fab")
			(hide yes)
			(effects
				(font
					(size 1 1)
					(thickness 0.15)
				)
				(justify mirror)
			)
		)
		(property "MPN" "CR0402-FX-1000GLF"
			(at 271.7 -112.1 0)
			(layer "B.Fab")
			(hide yes)
			(effects
				(font
					(size 1 1)
					(thickness 0.15)
				)
				(justify mirror)
			)
		)
		(property "Manufacturer" "Bourns"
			(at 271.7 -112.1 0)
			(layer "B.Fab")
			(hide yes)
			(effects
				(font
					(size 1 1)
					(thickness 0.15)
				)
				(justify mirror)
			)
		)
		(property "Tolerance" "1%"
			(at 271.7 -112.1 0)
			(layer "B.Fab")
			(hide yes)
			(effects
				(font
					(size 1 1)
					(thickness 0.15)
				)
				(justify mirror)
			)
		)
		(property "Val" "100R"
			(at 271.7 -112.1 0)
			(layer "B.Fab")
			(hide yes)
			(effects
				(font
					(size 1 1)
					(thickness 0.15)
				)
				(justify mirror)
			)
		)
		(sheetname "User GPIO + LED + button + DIP switch")
		(sheetfile "user-gpio.kicad_sch")
		(attr smd)
		(fp_rect
			(start -0.925 0.47)
			(end 0.925 -0.47)
			(stroke
				(width 0.05)
				(type default)
			)
			(fill no)
			(layer "B.CrtYd")
		)
		(fp_rect
			(start -0.5 0.25)
			(end 0.5 -0.25)
			(stroke
				(width 0.15)
				(type solid)
			)
			(fill no)
			(layer "B.Fab")
		)
		(pad "1" smd roundrect
			(at -0.48 0 90)
			(size 0.59 0.64)
			(layers "B.Cu" "B.Mask" "B.Paste")
			(roundrect_rratio 0.25)
			(net 492 "/FPGA Bank 12 & 13/CW_HEADER.IO3")
			(pintype "passive")
		)
		(pad "2" smd roundrect
			(at 0.48 0 90)
			(size 0.59 0.64)
			(layers "B.Cu" "B.Mask" "B.Paste")
			(roundrect_rratio 0.25)
			(net 831 "/User GPIO + LED + button + DIP switch/CW_20PIN_IO3")
			(pintype "passive")
		)
	)
	(footprint "antmicro-footprints:C_0603_1608Metric"
		(layer "B.Cu")
		(at 200 147 90)
		(descr "Capacitor SMD 0603")
		(tags "capacitor 0603")
		(property "Reference" "C387"
			(at -3.85 0.375 90)
			(layer "B.SilkS")
			(effects
				(font
					(size 0.7 0.7)
					(thickness 0.15)
				)
				(justify right bottom mirror)
			)
		)
		(property "Value" "C_47u_0603"
			(at 0 -1.6 90)
			(layer "B.Fab")
			(effects
				(font
					(size 0.7 0.7)
					(thickness 0.15)
				)
				(justify right bottom mirror)
			)
		)
		(property "Description" "SMD Multilayer Ceramic Capacitor, 47 µF, 6.3 V, 0603 [1608 Metric], ± 20%, X5R, GRM Series"
			(at 0 0 90)
			(layer "F.Fab")
			(hide yes)
			(effects
				(font
					(size 1.27 1.27)
					(thickness 0.15)
				)
			)
		)
		(property "Author" "Antmicro"
			(at 347 -53 0)
			(layer "B.Fab")
			(hide yes)
			(effects
				(font
					(size 1 1)
					(thickness 0.15)
				)
				(justify mirror)
			)
		)
		(property "Dielectric" ""
			(at 347 -53 0)
			(layer "B.Fab")
			(hide yes)
			(effects
				(font
					(size 1 1)
					(thickness 0.15)
				)
				(justify mirror)
			)
		)
		(property "License" "Apache-2.0"
			(at 347 -53 0)
			(layer "B.Fab")
			(hide yes)
			(effects
				(font
					(size 1 1)
					(thickness 0.15)
				)
				(justify mirror)
			)
		)
		(property "MPN" "GRM188R60J476ME15D"
			(at 347 -53 0)
			(layer "B.Fab")
			(hide yes)
			(effects
				(font
					(size 1 1)
					(thickness 0.15)
				)
				(justify mirror)
			)
		)
		(property "Manufacturer" "Murata"
			(at 347 -53 0)
			(layer "B.Fab")
			(hide yes)
			(effects
				(font
					(size 1 1)
					(thickness 0.15)
				)
				(justify mirror)
			)
		)
		(property "Val" "47u"
			(at 347 -53 0)
			(layer "B.Fab")
			(hide yes)
			(effects
				(font
					(size 1 1)
					(thickness 0.15)
				)
				(justify mirror)
			)
		)
		(property "Voltage" ""
			(at 347 -53 0)
			(layer "B.Fab")
			(hide yes)
			(effects
				(font
					(size 1 1)
					(thickness 0.15)
				)
				(justify mirror)
			)
		)
		(sheetname "FPGA supply")
		(sheetfile "fpga-supply.kicad_sch")
		(attr smd)
		(fp_line
			(start -0.15 -0.4)
			(end 0.15 -0.4)
			(stroke
				(width 0.15)
				(type solid)
			)
			(layer "B.SilkS")
		)
		(fp_line
			(start -0.15 0.4)
			(end 0.15 0.4)
			(stroke
				(width 0.15)
				(type solid)
			)
			(layer "B.SilkS")
		)
		(fp_rect
			(start -1.25 0.65)
			(end 1.25 -0.65)
			(stroke
				(width 0.05)
				(type solid)
			)
			(fill no)
			(layer "B.CrtYd")
		)
		(fp_rect
			(start -0.8 0.4)
			(end 0.8 -0.4)
			(stroke
				(width 0.15)
				(type solid)
			)
			(fill no)
			(layer "B.Fab")
		)
		(pad "1" smd roundrect
			(at -0.7 0 90)
			(size 0.8 1)
			(layers "B.Cu" "B.Mask" "B.Paste")
			(roundrect_rratio 0.2)
			(net 1 "GND")
			(pintype "passive")
		)
		(pad "2" smd roundrect
			(at 0.7 0 90)
			(size 0.8 1)
			(layers "B.Cu" "B.Mask" "B.Paste")
			(roundrect_rratio 0.2)
			(net 650 "+1V0")
			(pintype "passive")
		)
	)
	(footprint "antmicro-footprints:C_0402_1005Metric"
		(layer "B.Cu")
		(at 186.5 187.5 180)
		(descr "Capacitor SMD 0402")
		(tags "capacitor SMD 0402")
		(property "Reference" "C321"
			(at -1.475 -1.275 0)
			(layer "B.SilkS")
			(effects
				(font
					(size 0.7 0.7)
					(thickness 0.15)
				)
				(justify left bottom mirror)
			)
		)
		(property "Value" "C_1u_0402"
			(at 0 -1.4 0)
			(layer "B.Fab")
			(effects
				(font
					(size 0.7 0.7)
					(thickness 0.15)
				)
				(justify left bottom mirror)
			)
		)
		(property "Description" "SMD Multilayer Ceramic Capacitor, 1 µF, 10 V, 0402 [1005 Metric], ± 10%, X6S, C"
			(at 0 0 180)
			(layer "F.Fab")
			(hide yes)
			(effects
				(font
					(size 1.27 1.27)
					(thickness 0.15)
				)
			)
		)
		(property "Author" "Antmicro"
			(at 373 375 0)
			(layer "B.Fab")
			(hide yes)
			(effects
				(font
					(size 1 1)
					(thickness 0.15)
				)
				(justify mirror)
			)
		)
		(property "Dielectric" ""
			(at 373 375 0)
			(layer "B.Fab")
			(hide yes)
			(effects
				(font
					(size 1 1)
					(thickness 0.15)
				)
				(justify mirror)
			)
		)
		(property "License" "Apache-2.0"
			(at 373 375 0)
			(layer "B.Fab")
			(hide yes)
			(effects
				(font
					(size 1 1)
					(thickness 0.15)
				)
				(justify mirror)
			)
		)
		(property "MPN" "C1005X6S1A105K050BC"
			(at 373 375 0)
			(layer "B.Fab")
			(hide yes)
			(effects
				(font
					(size 1 1)
					(thickness 0.15)
				)
				(justify mirror)
			)
		)
		(property "Manufacturer" "TDK"
			(at 373 375 0)
			(layer "B.Fab")
			(hide yes)
			(effects
				(font
					(size 1 1)
					(thickness 0.15)
				)
				(justify mirror)
			)
		)
		(property "Val" "1u"
			(at 373 375 0)
			(layer "B.Fab")
			(hide yes)
			(effects
				(font
					(size 1 1)
					(thickness 0.15)
				)
				(justify mirror)
			)
		)
		(property "Voltage" ""
			(at 373 375 0)
			(layer "B.Fab")
			(hide yes)
			(effects
				(font
					(size 1 1)
					(thickness 0.15)
				)
				(justify mirror)
			)
		)
		(sheetname "DC-DC Converters")
		(sheetfile "dc-dc.kicad_sch")
		(attr smd)
		(fp_rect
			(start -0.925 0.47)
			(end 0.925 -0.47)
			(stroke
				(width 0.05)
				(type default)
			)
			(fill no)
			(layer "B.CrtYd")
		)
		(fp_line
			(start 0.504 0.25)
			(end 0.504 -0.248)
			(stroke
				(width 0.15)
				(type solid)
			)
			(layer "B.Fab")
		)
		(fp_line
			(start 0.504 -0.248)
			(end -0.494 -0.248)
			(stroke
				(width 0.15)
				(type solid)
			)
			(layer "B.Fab")
		)
		(fp_line
			(start -0.494 0.25)
			(end 0.504 0.25)
			(stroke
				(width 0.15)
				(type solid)
			)
			(layer "B.Fab")
		)
		(fp_line
			(start -0.494 -0.248)
			(end -0.494 0.25)
			(stroke
				(width 0.15)
				(type solid)
			)
			(layer "B.Fab")
		)
		(pad "1" smd roundrect
			(at -0.48 0 180)
			(size 0.59 0.64)
			(layers "B.Cu" "B.Mask" "B.Paste")
			(roundrect_rratio 0.25)
			(net 1 "GND")
			(pintype "passive")
		)
		(pad "2" smd roundrect
			(at 0.48 0 180)
			(size 0.59 0.64)
			(layers "B.Cu" "B.Mask" "B.Paste")
			(roundrect_rratio 0.25)
			(net 37 "+3V3_AON")
			(pintype "passive")
		)
	)
	(footprint "antmicro-footprints:C_0402_1005Metric"
		(layer "B.Cu")
		(at 214.5 124 -90)
		(descr "Capacitor SMD 0402")
		(tags "capacitor SMD 0402")
		(property "Reference" "C32"
			(at -1.1 0.525 90)
			(layer "B.SilkS")
			(effects
				(font
					(size 0.7 0.7)
					(thickness 0.15)
				)
				(justify left bottom mirror)
			)
		)
		(property "Value" "C_100n_0402"
			(at 0 -1.169 90)
			(layer "B.Fab")
			(effects
				(font
					(size 0.7 0.7)
					(thickness 0.15)
				)
				(justify left bottom mirror)
			)
		)
		(property "Description" "SMD Multilayer Ceramic Capacitor, 0.1 µF, 50 V, 0402 [1005 Metric], ± 10%, X5R, GRM Series"
			(at 0 0 270)
			(layer "F.Fab")
			(hide yes)
			(effects
				(font
					(size 1.27 1.27)
					(thickness 0.15)
				)
			)
		)
		(property "Author" "Antmicro"
			(at 90.5 338.5 0)
			(layer "B.Fab")
			(hide yes)
			(effects
				(font
					(size 1 1)
					(thickness 0.15)
				)
				(justify mirror)
			)
		)
		(property "Dielectric" "X5R"
			(at 90.5 338.5 0)
			(layer "B.Fab")
			(hide yes)
			(effects
				(font
					(size 1 1)
					(thickness 0.15)
				)
				(justify mirror)
			)
		)
		(property "License" "Apache-2.0"
			(at 90.5 338.5 0)
			(layer "B.Fab")
			(hide yes)
			(effects
				(font
					(size 1 1)
					(thickness 0.15)
				)
				(justify mirror)
			)
		)
		(property "MPN" "GRM155R61H104KE14D"
			(at 90.5 338.5 0)
			(layer "B.Fab")
			(hide yes)
			(effects
				(font
					(size 1 1)
					(thickness 0.15)
				)
				(justify mirror)
			)
		)
		(property "Manufacturer" "Murata"
			(at 90.5 338.5 0)
			(layer "B.Fab")
			(hide yes)
			(effects
				(font
					(size 1 1)
					(thickness 0.15)
				)
				(justify mirror)
			)
		)
		(property "Val" "100n"
			(at 90.5 338.5 0)
			(layer "B.Fab")
			(hide yes)
			(effects
				(font
					(size 1 1)
					(thickness 0.15)
				)
				(justify mirror)
			)
		)
		(property "Voltage" "50V"
			(at 90.5 338.5 0)
			(layer "B.Fab")
			(hide yes)
			(effects
				(font
					(size 1 1)
					(thickness 0.15)
				)
				(justify mirror)
			)
		)
		(sheetname "FPGA Bank 14 & 15")
		(sheetfile "fpga-bank-14-15.kicad_sch")
		(attr smd)
		(fp_rect
			(start -0.925 0.47)
			(end 0.925 -0.47)
			(stroke
				(width 0.05)
				(type default)
			)
			(fill no)
			(layer "B.CrtYd")
		)
		(fp_line
			(start -0.494 0.25)
			(end 0.504 0.25)
			(stroke
				(width 0.15)
				(type solid)
			)
			(layer "B.Fab")
		)
		(fp_line
			(start 0.504 0.25)
			(end 0.504 -0.248)
			(stroke
				(width 0.15)
				(type solid)
			)
			(layer "B.Fab")
		)
		(fp_line
			(start -0.494 -0.248)
			(end -0.494 0.25)
			(stroke
				(width 0.15)
				(type solid)
			)
			(layer "B.Fab")
		)
		(fp_line
			(start 0.504 -0.248)
			(end -0.494 -0.248)
			(stroke
				(width 0.15)
				(type solid)
			)
			(layer "B.Fab")
		)
		(pad "1" smd roundrect
			(at -0.48 0 270)
			(size 0.59 0.64)
			(layers "B.Cu" "B.Mask" "B.Paste")
			(roundrect_rratio 0.25)
			(net 1 "GND")
			(pintype "passive")
		)
		(pad "2" smd roundrect
			(at 0.48 0 270)
			(size 0.59 0.64)
			(layers "B.Cu" "B.Mask" "B.Paste")
			(roundrect_rratio 0.25)
			(net 2 "VCC_USR_A")
			(pintype "passive")
		)
	)
	(footprint "antmicro-footprints:C_0201"
		(layer "B.Cu")
		(at 202.65 133.5 -90)
		(descr "Capacitor SMD 0201")
		(tags "capacitor SMD 0201")
		(property "Reference" "C141"
			(at -29.85 -27.025 90)
			(layer "B.SilkS")
			(effects
				(font
					(size 0.7 0.7)
					(thickness 0.15)
				)
				(justify left bottom mirror)
			)
		)
		(property "Value" "C_100n_0201"
			(at 0 -1.4 90)
			(layer "B.Fab")
			(effects
				(font
					(size 0.7 0.7)
					(thickness 0.15)
				)
				(justify left bottom mirror)
			)
		)
		(property "Description" "SMD Multilayer Ceramic Capacitor, 0.1 µF, 6.3 V, 0201 [0603 Metric], ± 10%, X6S, CC Series"
			(at 0 0 270)
			(layer "F.Fab")
			(hide yes)
			(effects
				(font
					(size 1.27 1.27)
					(thickness 0.15)
				)
			)
		)
		(property "Author" "Antmicro"
			(at 69.15 336.15 0)
			(layer "B.Fab")
			(hide yes)
			(effects
				(font
					(size 1 1)
					(thickness 0.15)
				)
				(justify mirror)
			)
		)
		(property "Dielectric" ""
			(at 69.15 336.15 0)
			(layer "B.Fab")
			(hide yes)
			(effects
				(font
					(size 1 1)
					(thickness 0.15)
				)
				(justify mirror)
			)
		)
		(property "License" "Apache-2.0"
			(at 69.15 336.15 0)
			(layer "B.Fab")
			(hide yes)
			(effects
				(font
					(size 1 1)
					(thickness 0.15)
				)
				(justify mirror)
			)
		)
		(property "MPN" "CC0201KRX6S5BB104"
			(at 69.15 336.15 0)
			(layer "B.Fab")
			(hide yes)
			(effects
				(font
					(size 1 1)
					(thickness 0.15)
				)
				(justify mirror)
			)
		)
		(property "Manufacturer" "YAGEO"
			(at 69.15 336.15 0)
			(layer "B.Fab")
			(hide yes)
			(effects
				(font
					(size 1 1)
					(thickness 0.15)
				)
				(justify mirror)
			)
		)
		(property "Val" "100n"
			(at 69.15 336.15 0)
			(layer "B.Fab")
			(hide yes)
			(effects
				(font
					(size 1 1)
					(thickness 0.15)
				)
				(justify mirror)
			)
		)
		(property "Voltage" ""
			(at 69.15 336.15 0)
			(layer "B.Fab")
			(hide yes)
			(effects
				(font
					(size 1 1)
					(thickness 0.15)
				)
				(justify mirror)
			)
		)
		(sheetname "FPGA supply")
		(sheetfile "fpga-supply.kicad_sch")
		(attr smd)
		(fp_rect
			(start -0.7 0.35)
			(end 0.7 -0.35)
			(stroke
				(width 0.05)
				(type default)
			)
			(fill no)
			(layer "B.CrtYd")
		)
		(fp_rect
			(start 0.3 -0.15)
			(end -0.301 0.149)
			(stroke
				(width 0.15)
				(type solid)
			)
			(fill no)
			(layer "B.Fab")
		)
		(pad "" smd roundrect
			(at -0.349 0.002 270)
			(size 0.318 0.36)
			(layers "B.Paste")
			(roundrect_rratio 0.25)
		)
		(pad "" smd roundrect
			(at 0.341 0.002 270)
			(size 0.318 0.36)
			(layers "B.Paste")
			(roundrect_rratio 0.25)
		)
		(pad "1" smd roundrect
			(at -0.321 0.002 270)
			(size 0.46 0.4)
			(layers "B.Cu" "B.Mask")
			(roundrect_rratio 0.25)
			(net 1 "GND")
			(pintype "passive")
		)
		(pad "2" smd roundrect
			(at 0.32 0.002 270)
			(size 0.46 0.4)
			(layers "B.Cu" "B.Mask")
			(roundrect_rratio 0.25)
			(net 650 "+1V0")
			(pintype "passive")
		)
	)
	(footprint "antmicro-footprints:C_0402_1005Metric"
		(layer "B.Cu")
		(at 202.5 123 90)
		(descr "Capacitor SMD 0402")
		(tags "capacitor SMD 0402")
		(property "Reference" "C92"
			(at 31.075 27.025 270)
			(layer "B.SilkS")
			(effects
				(font
					(size 0.7 0.7)
					(thickness 0.15)
				)
				(justify left bottom mirror)
			)
		)
		(property "Value" "C_100n_0402"
			(at 0 -1.169 270)
			(layer "B.Fab")
			(effects
				(font
					(size 0.7 0.7)
					(thickness 0.15)
				)
				(justify left bottom mirror)
			)
		)
		(property "Description" "SMD Multilayer Ceramic Capacitor, 0.1 µF, 50 V, 0402 [1005 Metric], ± 10%, X5R, GRM Series"
			(at 0 0 90)
			(layer "F.Fab")
			(hide yes)
			(effects
				(font
					(size 1.27 1.27)
					(thickness 0.15)
				)
			)
		)
		(property "Author" "Antmicro"
			(at 325.5 -79.5 0)
			(layer "B.Fab")
			(hide yes)
			(effects
				(font
					(size 1 1)
					(thickness 0.15)
				)
				(justify mirror)
			)
		)
		(property "Dielectric" "X5R"
			(at 325.5 -79.5 0)
			(layer "B.Fab")
			(hide yes)
			(effects
				(font
					(size 1 1)
					(thickness 0.15)
				)
				(justify mirror)
			)
		)
		(property "License" "Apache-2.0"
			(at 325.5 -79.5 0)
			(layer "B.Fab")
			(hide yes)
			(effects
				(font
					(size 1 1)
					(thickness 0.15)
				)
				(justify mirror)
			)
		)
		(property "MPN" "GRM155R61H104KE14D"
			(at 325.5 -79.5 0)
			(layer "B.Fab")
			(hide yes)
			(effects
				(font
					(size 1 1)
					(thickness 0.15)
				)
				(justify mirror)
			)
		)
		(property "Manufacturer" "Murata"
			(at 325.5 -79.5 0)
			(layer "B.Fab")
			(hide yes)
			(effects
				(font
					(size 1 1)
					(thickness 0.15)
				)
				(justify mirror)
			)
		)
		(property "Val" "100n"
			(at 325.5 -79.5 0)
			(layer "B.Fab")
			(hide yes)
			(effects
				(font
					(size 1 1)
					(thickness 0.15)
				)
				(justify mirror)
			)
		)
		(property "Voltage" "50V"
			(at 325.5 -79.5 0)
			(layer "B.Fab")
			(hide yes)
			(effects
				(font
					(size 1 1)
					(thickness 0.15)
				)
				(justify mirror)
			)
		)
		(sheetname "FPGA Bank 16 & 17")
		(sheetfile "fpga-bank-16-17.kicad_sch")
		(attr smd)
		(fp_rect
			(start -0.925 0.47)
			(end 0.925 -0.47)
			(stroke
				(width 0.05)
				(type default)
			)
			(fill no)
			(layer "B.CrtYd")
		)
		(fp_line
			(start 0.504 -0.248)
			(end -0.494 -0.248)
			(stroke
				(width 0.15)
				(type solid)
			)
			(layer "B.Fab")
		)
		(fp_line
			(start -0.494 -0.248)
			(end -0.494 0.25)
			(stroke
				(width 0.15)
				(type solid)
			)
			(layer "B.Fab")
		)
		(fp_line
			(start 0.504 0.25)
			(end 0.504 -0.248)
			(stroke
				(width 0.15)
				(type solid)
			)
			(layer "B.Fab")
		)
		(fp_line
			(start -0.494 0.25)
			(end 0.504 0.25)
			(stroke
				(width 0.15)
				(type solid)
			)
			(layer "B.Fab")
		)
		(pad "1" smd roundrect
			(at -0.48 0 90)
			(size 0.59 0.64)
			(layers "B.Cu" "B.Mask" "B.Paste")
			(roundrect_rratio 0.25)
			(net 1 "GND")
			(pintype "passive")
		)
		(pad "2" smd roundrect
			(at 0.48 0 90)
			(size 0.59 0.64)
			(layers "B.Cu" "B.Mask" "B.Paste")
			(roundrect_rratio 0.25)
			(net 24 "+3V3")
			(pintype "passive")
		)
	)
	(footprint "antmicro-footprints:C_0402_1005Metric"
		(layer "B.Cu")
		(at 198 117.5 180)
		(descr "Capacitor SMD 0402")
		(tags "capacitor SMD 0402")
		(property "Reference" "C93"
			(at -0.8 0.45 0)
			(layer "B.SilkS")
			(effects
				(font
					(size 0.7 0.7)
					(thickness 0.15)
				)
				(justify left bottom mirror)
			)
		)
		(property "Value" "C_100n_0402"
			(at 0 -1.169 0)
			(layer "B.Fab")
			(effects
				(font
					(size 0.7 0.7)
					(thickness 0.15)
				)
				(justify left bottom mirror)
			)
		)
		(property "Description" "SMD Multilayer Ceramic Capacitor, 0.1 µF, 50 V, 0402 [1005 Metric], ± 10%, X5R, GRM Series"
			(at 0 0 180)
			(layer "F.Fab")
			(hide yes)
			(effects
				(font
					(size 1.27 1.27)
					(thickness 0.15)
				)
			)
		)
		(property "Author" "Antmicro"
			(at 396 235 0)
			(layer "B.Fab")
			(hide yes)
			(effects
				(font
					(size 1 1)
					(thickness 0.15)
				)
				(justify mirror)
			)
		)
		(property "Dielectric" "X5R"
			(at 396 235 0)
			(layer "B.Fab")
			(hide yes)
			(effects
				(font
					(size 1 1)
					(thickness 0.15)
				)
				(justify mirror)
			)
		)
		(property "License" "Apache-2.0"
			(at 396 235 0)
			(layer "B.Fab")
			(hide yes)
			(effects
				(font
					(size 1 1)
					(thickness 0.15)
				)
				(justify mirror)
			)
		)
		(property "MPN" "GRM155R61H104KE14D"
			(at 396 235 0)
			(layer "B.Fab")
			(hide yes)
			(effects
				(font
					(size 1 1)
					(thickness 0.15)
				)
				(justify mirror)
			)
		)
		(property "Manufacturer" "Murata"
			(at 396 235 0)
			(layer "B.Fab")
			(hide yes)
			(effects
				(font
					(size 1 1)
					(thickness 0.15)
				)
				(justify mirror)
			)
		)
		(property "Val" "100n"
			(at 396 235 0)
			(layer "B.Fab")
			(hide yes)
			(effects
				(font
					(size 1 1)
					(thickness 0.15)
				)
				(justify mirror)
			)
		)
		(property "Voltage" "50V"
			(at 396 235 0)
			(layer "B.Fab")
			(hide yes)
			(effects
				(font
					(size 1 1)
					(thickness 0.15)
				)
				(justify mirror)
			)
		)
		(sheetname "FPGA Bank 18 & 32")
		(sheetfile "fpga-bank-18-32.kicad_sch")
		(attr smd)
		(fp_rect
			(start -0.925 0.47)
			(end 0.925 -0.47)
			(stroke
				(width 0.05)
				(type default)
			)
			(fill no)
			(layer "B.CrtYd")
		)
		(fp_line
			(start 0.504 0.25)
			(end 0.504 -0.248)
			(stroke
				(width 0.15)
				(type solid)
			)
			(layer "B.Fab")
		)
		(fp_line
			(start 0.504 -0.248)
			(end -0.494 -0.248)
			(stroke
				(width 0.15)
				(type solid)
			)
			(layer "B.Fab")
		)
		(fp_line
			(start -0.494 0.25)
			(end 0.504 0.25)
			(stroke
				(width 0.15)
				(type solid)
			)
			(layer "B.Fab")
		)
		(fp_line
			(start -0.494 -0.248)
			(end -0.494 0.25)
			(stroke
				(width 0.15)
				(type solid)
			)
			(layer "B.Fab")
		)
		(pad "1" smd roundrect
			(at -0.48 0 180)
			(size 0.59 0.64)
			(layers "B.Cu" "B.Mask" "B.Paste")
			(roundrect_rratio 0.25)
			(net 1 "GND")
			(pintype "passive")
		)
		(pad "2" smd roundrect
			(at 0.48 0 180)
			(size 0.59 0.64)
			(layers "B.Cu" "B.Mask" "B.Paste")
			(roundrect_rratio 0.25)
			(net 24 "+3V3")
			(pintype "passive")
		)
	)
	(footprint "antmicro-footprints:R_Array_4x0201_Panasonic_EXB18V"
		(layer "B.Cu")
		(at 255.2 73.4 180)
		(property "Reference" "R132"
			(at 1.475 0.75 0)
			(layer "B.SilkS")
			(effects
				(font
					(size 0.7 0.7)
					(thickness 0.15)
				)
				(justify right bottom mirror)
			)
		)
		(property "Value" "4x10k_0201_array"
			(at -1.1 -1.8 0)
			(layer "B.Fab")
			(effects
				(font
					(size 0.7 0.7)
					(thickness 0.15)
				)
				(justify left bottom mirror)
			)
		)
		(property "Description" "Fixed Network Resistor, 10 kohm, Isolated, 4 Resistors, 0502 [1406 Metric], Flat, ± 5%"
			(at 0 0 180)
			(layer "F.Fab")
			(hide yes)
			(effects
				(font
					(size 1.27 1.27)
					(thickness 0.15)
				)
			)
		)
		(property "Author" "Antmicro"
			(at 510.4 146.8 0)
			(layer "B.Fab")
			(hide yes)
			(effects
				(font
					(size 1 1)
					(thickness 0.15)
				)
				(justify mirror)
			)
		)
		(property "License" "Apache-2.0"
			(at 510.4 146.8 0)
			(layer "B.Fab")
			(hide yes)
			(effects
				(font
					(size 1 1)
					(thickness 0.15)
				)
				(justify mirror)
			)
		)
		(property "MPN" "EXB-18V103JX"
			(at 510.4 146.8 0)
			(layer "B.Fab")
			(hide yes)
			(effects
				(font
					(size 1 1)
					(thickness 0.15)
				)
				(justify mirror)
			)
		)
		(property "Manufacturer" "Panasonic"
			(at 510.4 146.8 0)
			(layer "B.Fab")
			(hide yes)
			(effects
				(font
					(size 1 1)
					(thickness 0.15)
				)
				(justify mirror)
			)
		)
		(property "Val" "4x10k_0201"
			(at 510.4 146.8 0)
			(layer "B.Fab")
			(hide yes)
			(effects
				(font
					(size 1 1)
					(thickness 0.15)
				)
				(justify mirror)
			)
		)
		(sheetname "User GPIO + LED + button + DIP switch")
		(sheetfile "user-gpio.kicad_sch")
		(attr smd)
		(fp_line
			(start 0.8 0.45)
			(end 0.8 -0.45)
			(stroke
				(width 0.12)
				(type solid)
			)
			(layer "B.SilkS")
		)
		(fp_line
			(start -0.8 0.45)
			(end -0.8 -0.45)
			(stroke
				(width 0.12)
				(type solid)
			)
			(layer "B.SilkS")
		)
		(fp_rect
			(start -0.898 0.66)
			(end 0.898 -0.65)
			(stroke
				(width 0.05)
				(type solid)
			)
			(fill no)
			(layer "B.CrtYd")
		)
		(pad "1" smd roundrect
			(at -0.6 -0.298 180)
			(size 0.2 0.4)
			(layers "B.Cu" "B.Mask" "B.Paste")
			(roundrect_rratio 0.25)
			(net 1308 "/USER_IO.DIP_SW3")
			(pinfunction "R1.1")
			(pintype "passive")
		)
		(pad "2" smd roundrect
			(at -0.202 -0.298 180)
			(size 0.2 0.4)
			(layers "B.Cu" "B.Mask" "B.Paste")
			(roundrect_rratio 0.25)
			(net 1309 "/USER_IO.DIP_SW2")
			(pinfunction "R2.1")
			(pintype "passive")
		)
		(pad "3" smd roundrect
			(at 0.2 -0.298 180)
			(size 0.2 0.4)
			(layers "B.Cu" "B.Mask" "B.Paste")
			(roundrect_rratio 0.25)
			(net 1310 "/USER_IO.DIP_SW1")
			(pinfunction "R3.1")
			(pintype "passive")
		)
		(pad "4" smd roundrect
			(at 0.598 -0.298 180)
			(size 0.2 0.4)
			(layers "B.Cu" "B.Mask" "B.Paste")
			(roundrect_rratio 0.25)
			(net 1311 "/USER_IO.DIP_SW0")
			(pinfunction "R4.1")
			(pintype "passive")
		)
		(pad "5" smd roundrect
			(at 0.598 0.3 180)
			(size 0.2 0.4)
			(layers "B.Cu" "B.Mask" "B.Paste")
			(roundrect_rratio 0.25)
			(net 26 "+1V8")
			(pinfunction "R4.2")
			(pintype "passive")
		)
		(pad "6" smd roundrect
			(at 0.2 0.3 180)
			(size 0.2 0.4)
			(layers "B.Cu" "B.Mask" "B.Paste")
			(roundrect_rratio 0.25)
			(net 26 "+1V8")
			(pinfunction "R3.2")
			(pintype "passive")
		)
		(pad "7" smd roundrect
			(at -0.202 0.3 180)
			(size 0.2 0.4)
			(layers "B.Cu" "B.Mask" "B.Paste")
			(roundrect_rratio 0.25)
			(net 26 "+1V8")
			(pinfunction "R2.2")
			(pintype "passive")
		)
		(pad "8" smd roundrect
			(at -0.6 0.3 180)
			(size 0.2 0.4)
			(layers "B.Cu" "B.Mask" "B.Paste")
			(roundrect_rratio 0.25)
			(net 26 "+1V8")
			(pinfunction "R1.2")
			(pintype "passive")
		)
	)
	(footprint "antmicro-footprints:C_0402_1005Metric"
		(layer "B.Cu")
		(at 194.775 127.825)
		(descr "Capacitor SMD 0402")
		(tags "capacitor SMD 0402")
		(property "Reference" "C134"
			(at 24.475 -28.775 180)
			(layer "B.SilkS")
			(effects
				(font
					(size 0.7 0.7)
					(thickness 0.15)
				)
				(justify left bottom mirror)
			)
		)
		(property "Value" "C_100n_0402"
			(at 0 -1.169 180)
			(layer "B.Fab")
			(effects
				(font
					(size 0.7 0.7)
					(thickness 0.15)
				)
				(justify left bottom mirror)
			)
		)
		(property "Description" "SMD Multilayer Ceramic Capacitor, 0.1 µF, 50 V, 0402 [1005 Metric], ± 10%, X5R, GRM Series"
			(at 0 0 0)
			(layer "F.Fab")
			(hide yes)
			(effects
				(font
					(size 1.27 1.27)
					(thickness 0.15)
				)
			)
		)
		(property "Author" "Antmicro"
			(at 0 0 0)
			(layer "B.Fab")
			(hide yes)
			(effects
				(font
					(size 1 1)
					(thickness 0.15)
				)
				(justify mirror)
			)
		)
		(property "Dielectric" "X5R"
			(at 0 0 0)
			(layer "B.Fab")
			(hide yes)
			(effects
				(font
					(size 1 1)
					(thickness 0.15)
				)
				(justify mirror)
			)
		)
		(property "License" "Apache-2.0"
			(at 0 0 0)
			(layer "B.Fab")
			(hide yes)
			(effects
				(font
					(size 1 1)
					(thickness 0.15)
				)
				(justify mirror)
			)
		)
		(property "MPN" "GRM155R61H104KE14D"
			(at 0 0 0)
			(layer "B.Fab")
			(hide yes)
			(effects
				(font
					(size 1 1)
					(thickness 0.15)
				)
				(justify mirror)
			)
		)
		(property "Manufacturer" "Murata"
			(at 0 0 0)
			(layer "B.Fab")
			(hide yes)
			(effects
				(font
					(size 1 1)
					(thickness 0.15)
				)
				(justify mirror)
			)
		)
		(property "Val" "100n"
			(at 0 0 0)
			(layer "B.Fab")
			(hide yes)
			(effects
				(font
					(size 1 1)
					(thickness 0.15)
				)
				(justify mirror)
			)
		)
		(property "Voltage" "50V"
			(at 0 0 0)
			(layer "B.Fab")
			(hide yes)
			(effects
				(font
					(size 1 1)
					(thickness 0.15)
				)
				(justify mirror)
			)
		)
		(sheetname "FPGA supply")
		(sheetfile "fpga-supply.kicad_sch")
		(attr smd)
		(fp_rect
			(start -0.925 0.47)
			(end 0.925 -0.47)
			(stroke
				(width 0.05)
				(type default)
			)
			(fill no)
			(layer "B.CrtYd")
		)
		(fp_line
			(start -0.494 -0.248)
			(end -0.494 0.25)
			(stroke
				(width 0.15)
				(type solid)
			)
			(layer "B.Fab")
		)
		(fp_line
			(start -0.494 0.25)
			(end 0.504 0.25)
			(stroke
				(width 0.15)
				(type solid)
			)
			(layer "B.Fab")
		)
		(fp_line
			(start 0.504 -0.248)
			(end -0.494 -0.248)
			(stroke
				(width 0.15)
				(type solid)
			)
			(layer "B.Fab")
		)
		(fp_line
			(start 0.504 0.25)
			(end 0.504 -0.248)
			(stroke
				(width 0.15)
				(type solid)
			)
			(layer "B.Fab")
		)
		(pad "1" smd roundrect
			(at -0.48 0)
			(size 0.59 0.64)
			(layers "B.Cu" "B.Mask" "B.Paste")
			(roundrect_rratio 0.25)
			(net 1 "GND")
			(pintype "passive")
		)
		(pad "2" smd roundrect
			(at 0.48 0)
			(size 0.59 0.64)
			(layers "B.Cu" "B.Mask" "B.Paste")
			(roundrect_rratio 0.25)
			(net 650 "+1V0")
			(pintype "passive")
		)
	)
	(footprint "antmicro-footprints:R_0402_1005Metric_EIA"
		(layer "B.Cu")
		(at 191 137.5)
		(descr "Resistor SMD 0402 (1005 Metric), square (rectangular) end terminal, IPC_7351 nominal, (Body size source: IPC-SM-782 page 76, https://www.pcb-3d.com/wordpress/wp-content/uploads/ipc-sm-782a_amendment_1_and_2.pdf)")
		(tags "resistor 0402")
		(property "Reference" "R340"
			(at 2.8 2.275 180)
			(layer "B.SilkS")
			(effects
				(font
					(size 0.7 0.7)
					(thickness 0.15)
				)
				(justify left bottom mirror)
			)
		)
		(property "Value" "R_80R6_0402_EIA"
			(at 0 -1.169 180)
			(layer "B.Fab")
			(effects
				(font
					(size 0.7 0.7)
					(thickness 0.15)
				)
				(justify left bottom mirror)
			)
		)
		(property "Description" "SMD Chip Resistor, 80.6 ohm, ± 1%, 62.5 mW, 0402 [1005 Metric], Thick Film, General Purpose"
			(at 0 0 0)
			(layer "F.Fab")
			(hide yes)
			(effects
				(font
					(size 1.27 1.27)
					(thickness 0.15)
				)
			)
		)
		(property "Author" "Antmicro"
			(at 0 0 0)
			(layer "B.Fab")
			(hide yes)
			(effects
				(font
					(size 1 1)
					(thickness 0.15)
				)
				(justify mirror)
			)
		)
		(property "License" "Apache-2.0"
			(at 0 0 0)
			(layer "B.Fab")
			(hide yes)
			(effects
				(font
					(size 1 1)
					(thickness 0.15)
				)
				(justify mirror)
			)
		)
		(property "MPN" "MC00625W0402180R6"
			(at 0 0 0)
			(layer "B.Fab")
			(hide yes)
			(effects
				(font
					(size 1 1)
					(thickness 0.15)
				)
				(justify mirror)
			)
		)
		(property "Manufacturer" "Multicomp Pro"
			(at 0 0 0)
			(layer "B.Fab")
			(hide yes)
			(effects
				(font
					(size 1 1)
					(thickness 0.15)
				)
				(justify mirror)
			)
		)
		(property "Tolerance" "1%"
			(at 0 0 0)
			(layer "B.Fab")
			(hide yes)
			(effects
				(font
					(size 1 1)
					(thickness 0.15)
				)
				(justify mirror)
			)
		)
		(property "Val" "80R6"
			(at 0 0 0)
			(layer "B.Fab")
			(hide yes)
			(effects
				(font
					(size 1 1)
					(thickness 0.15)
				)
				(justify mirror)
			)
		)
		(sheetname "FPGA Bank 33 & 34")
		(sheetfile "fpga-bank-33-34.kicad_sch")
		(attr smd)
		(fp_rect
			(start -0.95 0.45)
			(end 0.95 -0.45)
			(stroke
				(width 0.05)
				(type default)
			)
			(fill no)
			(layer "B.CrtYd")
		)
		(fp_line
			(start -0.5 -0.249)
			(end -0.5 0.25)
			(stroke
				(width 0.15)
				(type solid)
			)
			(layer "B.Fab")
		)
		(fp_line
			(start -0.5 0.25)
			(end 0.499 0.25)
			(stroke
				(width 0.15)
				(type solid)
			)
			(layer "B.Fab")
		)
		(fp_line
			(start 0.499 -0.249)
			(end -0.5 -0.249)
			(stroke
				(width 0.15)
				(type solid)
			)
			(layer "B.Fab")
		)
		(fp_line
			(start 0.499 0.25)
			(end 0.499 -0.249)
			(stroke
				(width 0.15)
				(type solid)
			)
			(layer "B.Fab")
		)
		(pad "1" smd roundrect
			(at -0.5 0 270)
			(size 0.6 0.6)
			(layers "B.Cu" "B.Mask" "B.Paste")
			(roundrect_rratio 0.25)
			(net 568 "/FPGA Bank 33 & 34/DDR_VRP")
			(pintype "passive")
		)
		(pad "2" smd roundrect
			(at 0.499 0)
			(size 0.6 0.6)
			(layers "B.Cu" "B.Mask" "B.Paste")
			(roundrect_rratio 0.25)
			(net 25 "+1V35")
			(pintype "passive")
		)
	)
	(footprint "antmicro-footprints:C_0402_1005Metric"
		(layer "B.Cu")
		(at 263.501 181.75 180)
		(descr "Capacitor SMD 0402")
		(tags "capacitor SMD 0402")
		(property "Reference" "C190"
			(at -1.349 -1.25 0)
			(layer "B.SilkS")
			(effects
				(font
					(size 0.7 0.7)
					(thickness 0.15)
				)
				(justify left bottom mirror)
			)
		)
		(property "Value" "C_100n_0402"
			(at 0 -1.4 0)
			(layer "B.Fab")
			(effects
				(font
					(size 0.7 0.7)
					(thickness 0.15)
				)
				(justify left bottom mirror)
			)
		)
		(property "Description" "SMD Multilayer Ceramic Capacitor, 0.1 µF, 50 V, 0402 [1005 Metric], ± 10%, X5R, GRM Series"
			(at 0 0 180)
			(layer "F.Fab")
			(hide yes)
			(effects
				(font
					(size 1.27 1.27)
					(thickness 0.15)
				)
			)
		)
		(property "Author" "Antmicro"
			(at 527.002 363.5 0)
			(layer "B.Fab")
			(hide yes)
			(effects
				(font
					(size 1 1)
					(thickness 0.15)
				)
				(justify mirror)
			)
		)
		(property "Dielectric" "X5R"
			(at 527.002 363.5 0)
			(layer "B.Fab")
			(hide yes)
			(effects
				(font
					(size 1 1)
					(thickness 0.15)
				)
				(justify mirror)
			)
		)
		(property "License" "Apache-2.0"
			(at 527.002 363.5 0)
			(layer "B.Fab")
			(hide yes)
			(effects
				(font
					(size 1 1)
					(thickness 0.15)
				)
				(justify mirror)
			)
		)
		(property "MPN" "GRM155R61H104KE14D"
			(at 527.002 363.5 0)
			(layer "B.Fab")
			(hide yes)
			(effects
				(font
					(size 1 1)
					(thickness 0.15)
				)
				(justify mirror)
			)
		)
		(property "Manufacturer" "Murata"
			(at 527.002 363.5 0)
			(layer "B.Fab")
			(hide yes)
			(effects
				(font
					(size 1 1)
					(thickness 0.15)
				)
				(justify mirror)
			)
		)
		(property "Val" "100n"
			(at 527.002 363.5 0)
			(layer "B.Fab")
			(hide yes)
			(effects
				(font
					(size 1 1)
					(thickness 0.15)
				)
				(justify mirror)
			)
		)
		(property "Voltage" "50V"
			(at 527.002 363.5 0)
			(layer "B.Fab")
			(hide yes)
			(effects
				(font
					(size 1 1)
					(thickness 0.15)
				)
				(justify mirror)
			)
		)
		(sheetname "Power supply")
		(sheetfile "power-supply.kicad_sch")
		(attr smd)
		(fp_rect
			(start -0.925 0.47)
			(end 0.925 -0.47)
			(stroke
				(width 0.05)
				(type default)
			)
			(fill no)
			(layer "B.CrtYd")
		)
		(fp_line
			(start 0.504 0.25)
			(end 0.504 -0.248)
			(stroke
				(width 0.15)
				(type solid)
			)
			(layer "B.Fab")
		)
		(fp_line
			(start 0.504 -0.248)
			(end -0.494 -0.248)
			(stroke
				(width 0.15)
				(type solid)
			)
			(layer "B.Fab")
		)
		(fp_line
			(start -0.494 0.25)
			(end 0.504 0.25)
			(stroke
				(width 0.15)
				(type solid)
			)
			(layer "B.Fab")
		)
		(fp_line
			(start -0.494 -0.248)
			(end -0.494 0.25)
			(stroke
				(width 0.15)
				(type solid)
			)
			(layer "B.Fab")
		)
		(pad "1" smd roundrect
			(at -0.48 0 180)
			(size 0.59 0.64)
			(layers "B.Cu" "B.Mask" "B.Paste")
			(roundrect_rratio 0.25)
			(net 1 "GND")
			(pintype "passive")
		)
		(pad "2" smd roundrect
			(at 0.48 0 180)
			(size 0.59 0.64)
			(layers "B.Cu" "B.Mask" "B.Paste")
			(roundrect_rratio 0.25)
			(net 4 "/Power supply/DC_IN")
			(pintype "passive")
		)
	)
	(footprint "antmicro-footprints:SOT-886"
		(layer "B.Cu")
		(at 258.751 123.15 180)
		(property "Reference" "U48"
			(at -1.099 0.8 0)
			(layer "B.SilkS")
			(effects
				(font
					(size 0.7 0.7)
					(thickness 0.15)
				)
				(justify left bottom mirror)
			)
		)
		(property "Value" "74LVC1T45GM"
			(at -2.492 -1.647 0)
			(layer "B.Fab")
			(effects
				(font
					(size 0.7 0.7)
					(thickness 0.15)
				)
				(justify left bottom mirror)
			)
		)
		(property "Description" "Transceiver, Translating, 74LVC1T45, 74LVC Family, 1.2V to 5.5V Supply, XSON-6"
			(at 0 0 180)
			(layer "F.Fab")
			(hide yes)
			(effects
				(font
					(size 1.27 1.27)
					(thickness 0.15)
				)
			)
		)
		(property "Author" "Antmicro"
			(at 517.502 246.3 0)
			(layer "B.Fab")
			(hide yes)
			(effects
				(font
					(size 1 1)
					(thickness 0.15)
				)
				(justify mirror)
			)
		)
		(property "License" "Apache-2.0"
			(at 517.502 246.3 0)
			(layer "B.Fab")
			(hide yes)
			(effects
				(font
					(size 1 1)
					(thickness 0.15)
				)
				(justify mirror)
			)
		)
		(property "MPN" "74LVC1T45GM-Q100X"
			(at 517.502 246.3 0)
			(layer "B.Fab")
			(hide yes)
			(effects
				(font
					(size 1 1)
					(thickness 0.15)
				)
				(justify mirror)
			)
		)
		(property "Manufacturer" "Nexperia"
			(at 517.502 246.3 0)
			(layer "B.Fab")
			(hide yes)
			(effects
				(font
					(size 1 1)
					(thickness 0.15)
				)
				(justify mirror)
			)
		)
		(sheetname "USB PHY")
		(sheetfile "usb-phy.kicad_sch")
		(attr smd)
		(fp_line
			(start 0.858 0.491)
			(end 0.858 -0.509)
			(stroke
				(width 0.15)
				(type solid)
			)
			(layer "B.SilkS")
		)
		(fp_line
			(start -0.843 0.491)
			(end -0.843 -0.183)
			(stroke
				(width 0.15)
				(type solid)
			)
			(layer "B.SilkS")
		)
		(fp_circle
			(center -0.493 -0.847)
			(end -0.443 -0.847)
			(stroke
				(width 0.15)
				(type solid)
			)
			(fill yes)
			(layer "B.SilkS")
		)
		(fp_rect
			(start -1.23 1)
			(end 1.22 -0.99)
			(stroke
				(width 0.05)
				(type solid)
			)
			(fill no)
			(layer "B.CrtYd")
		)
		(fp_line
			(start 0.858 0.616)
			(end 0.858 -0.634)
			(stroke
				(width 0.15)
				(type solid)
			)
			(layer "B.Fab")
		)
		(fp_line
			(start 0.858 -0.634)
			(end -0.843 -0.634)
			(stroke
				(width 0.15)
				(type solid)
			)
			(layer "B.Fab")
		)
		(fp_line
			(start -0.843 0.616)
			(end 0.858 0.616)
			(stroke
				(width 0.15)
				(type solid)
			)
			(layer "B.Fab")
		)
		(fp_line
			(start -0.843 0.616)
			(end -0.843 -0.634)
			(stroke
				(width 0.15)
				(type solid)
			)
			(layer "B.Fab")
		)
		(fp_line
			(start -0.843 -0.434)
			(end -0.644 -0.634)
			(stroke
				(width 0.15)
				(type solid)
			)
			(layer "B.Fab")
		)
		(pad "1" smd rect
			(at -0.493 -0.347 180)
			(size 0.27 0.325)
			(layers "B.Cu" "B.Mask" "B.Paste")
			(net 707 "/USB PHY/FTDI_3V3")
			(pinfunction "VCCA")
			(pintype "power_in")
			(solder_mask_margin 0.05)
		)
		(pad "2" smd rect
			(at 0.005 -0.347 180)
			(size 0.27 0.325)
			(layers "B.Cu" "B.Mask" "B.Paste")
			(net 1 "GND")
			(pinfunction "GND")
			(pintype "power_in")
			(solder_mask_margin 0.05)
		)
		(pad "3" smd rect
			(at 0.505 -0.347 180)
			(size 0.27 0.325)
			(layers "B.Cu" "B.Mask" "B.Paste")
			(net 1020 "/USB PHY/FTDI_JTAG_RST")
			(pinfunction "A")
			(pintype "bidirectional")
			(solder_mask_margin 0.05)
		)
		(pad "4" smd rect
			(at 0.505 0.33)
			(size 0.27 0.325)
			(layers "B.Cu" "B.Mask" "B.Paste")
			(net 431 "/FPGA Config/JTAG.RST")
			(pinfunction "B")
			(pintype "bidirectional")
			(solder_mask_margin 0.05)
		)
		(pad "5" smd rect
			(at 0.005 0.33)
			(size 0.27 0.325)
			(layers "B.Cu" "B.Mask" "B.Paste")
			(net 707 "/USB PHY/FTDI_3V3")
			(pinfunction "DIR")
			(pintype "input")
			(solder_mask_margin 0.05)
		)
		(pad "6" smd rect
			(at -0.493 0.33)
			(size 0.27 0.325)
			(layers "B.Cu" "B.Mask" "B.Paste")
			(net 24 "+3V3")
			(pinfunction "VCCB")
			(pintype "power_in")
			(solder_mask_margin 0.05)
		)
	)
	(footprint "antmicro-footprints:R_0402_1005Metric"
		(layer "B.Cu")
		(at 170 146.575 180)
		(descr "Resistor SMD 0402")
		(tags "resistor SMD 0402")
		(property "Reference" "R32"
			(at -3.025 -0.45 0)
			(layer "B.SilkS")
			(effects
				(font
					(size 0.7 0.7)
					(thickness 0.15)
				)
				(justify left bottom mirror)
			)
		)
		(property "Value" "R_100R_0402"
			(at 0 -1.4 0)
			(layer "B.Fab")
			(effects
				(font
					(size 0.7 0.7)
					(thickness 0.15)
				)
				(justify left bottom mirror)
			)
		)
		(property "Description" "SMD Chip Resistor, 100 ohm, ± 1%, 62.5 mW, 0402 [1005 Metric], Thick Film, General Purpose"
			(at 0 0 180)
			(layer "F.Fab")
			(hide yes)
			(effects
				(font
					(size 1.27 1.27)
					(thickness 0.15)
				)
			)
		)
		(property "Author" "Antmicro"
			(at 340 293.15 0)
			(layer "B.Fab")
			(hide yes)
			(effects
				(font
					(size 1 1)
					(thickness 0.15)
				)
				(justify mirror)
			)
		)
		(property "License" "Apache-2.0"
			(at 340 293.15 0)
			(layer "B.Fab")
			(hide yes)
			(effects
				(font
					(size 1 1)
					(thickness 0.15)
				)
				(justify mirror)
			)
		)
		(property "MPN" "CR0402-FX-1000GLF"
			(at 340 293.15 0)
			(layer "B.Fab")
			(hide yes)
			(effects
				(font
					(size 1 1)
					(thickness 0.15)
				)
				(justify mirror)
			)
		)
		(property "Manufacturer" "Bourns"
			(at 340 293.15 0)
			(layer "B.Fab")
			(hide yes)
			(effects
				(font
					(size 1 1)
					(thickness 0.15)
				)
				(justify mirror)
			)
		)
		(property "Tolerance" "1%"
			(at 340 293.15 0)
			(layer "B.Fab")
			(hide yes)
			(effects
				(font
					(size 1 1)
					(thickness 0.15)
				)
				(justify mirror)
			)
		)
		(property "Val" "100R"
			(at 340 293.15 0)
			(layer "B.Fab")
			(hide yes)
			(effects
				(font
					(size 1 1)
					(thickness 0.15)
				)
				(justify mirror)
			)
		)
		(sheetname "DRAM + SRAM")
		(sheetfile "ram.kicad_sch")
		(attr smd)
		(fp_rect
			(start -0.925 0.47)
			(end 0.925 -0.47)
			(stroke
				(width 0.05)
				(type default)
			)
			(fill no)
			(layer "B.CrtYd")
		)
		(fp_rect
			(start -0.5 0.25)
			(end 0.5 -0.25)
			(stroke
				(width 0.15)
				(type solid)
			)
			(fill no)
			(layer "B.Fab")
		)
		(pad "1" smd roundrect
			(at -0.48 0 180)
			(size 0.59 0.64)
			(layers "B.Cu" "B.Mask" "B.Paste")
			(roundrect_rratio 0.25)
			(net 551 "/DRAM + SRAM/DDR.CK_P")
			(pintype "passive")
		)
		(pad "2" smd roundrect
			(at 0.48 0 180)
			(size 0.59 0.64)
			(layers "B.Cu" "B.Mask" "B.Paste")
			(roundrect_rratio 0.25)
			(net 552 "/DRAM + SRAM/DDR.CK_N")
			(pintype "passive")
		)
	)
	(footprint "antmicro-footprints:R_0402_1005Metric"
		(layer "B.Cu")
		(at 181.05 170.63 -90)
		(descr "Resistor SMD 0402")
		(tags "resistor SMD 0402")
		(property "Reference" "R295"
			(at 0.77 -0.375 90)
			(layer "B.SilkS")
			(effects
				(font
					(size 0.7 0.7)
					(thickness 0.15)
				)
				(justify left bottom mirror)
			)
		)
		(property "Value" "R_0R_0402"
			(at 0 -1.4 90)
			(layer "B.Fab")
			(effects
				(font
					(size 0.7 0.7)
					(thickness 0.15)
				)
				(justify left bottom mirror)
			)
		)
		(property "Description" "SMD Chip Resistor, Jumper, 0 ohm, 100 mW, 0402 [1005 Metric], Thick Film, General Purpose"
			(at 0 0 270)
			(layer "F.Fab")
			(hide yes)
			(effects
				(font
					(size 1.27 1.27)
					(thickness 0.15)
				)
			)
		)
		(property "Author" "Antmicro"
			(at 10.42 351.68 0)
			(layer "B.Fab")
			(hide yes)
			(effects
				(font
					(size 1 1)
					(thickness 0.15)
				)
				(justify mirror)
			)
		)
		(property "Current" "1A"
			(at 10.42 351.68 0)
			(layer "B.Fab")
			(hide yes)
			(effects
				(font
					(size 1 1)
					(thickness 0.15)
				)
				(justify mirror)
			)
		)
		(property "DNP" "DNP"
			(at 10.42 351.68 0)
			(layer "B.Fab")
			(hide yes)
			(effects
				(font
					(size 1 1)
					(thickness 0.15)
				)
				(justify mirror)
			)
		)
		(property "License" "Apache-2.0"
			(at 10.42 351.68 0)
			(layer "B.Fab")
			(hide yes)
			(effects
				(font
					(size 1 1)
					(thickness 0.15)
				)
				(justify mirror)
			)
		)
		(property "MPN" "ERJ2GE0R00X"
			(at 10.42 351.68 0)
			(layer "B.Fab")
			(hide yes)
			(effects
				(font
					(size 1 1)
					(thickness 0.15)
				)
				(justify mirror)
			)
		)
		(property "Manufacturer" "Panasonic"
			(at 10.42 351.68 0)
			(layer "B.Fab")
			(hide yes)
			(effects
				(font
					(size 1 1)
					(thickness 0.15)
				)
				(justify mirror)
			)
		)
		(property "Tolerance" ""
			(at 10.42 351.68 0)
			(layer "B.Fab")
			(hide yes)
			(effects
				(font
					(size 1 1)
					(thickness 0.15)
				)
				(justify mirror)
			)
		)
		(property "Val" "0R"
			(at 10.42 351.68 0)
			(layer "B.Fab")
			(hide yes)
			(effects
				(font
					(size 1 1)
					(thickness 0.15)
				)
				(justify mirror)
			)
		)
		(property "dnp" ""
			(at 10.42 351.68 0)
			(layer "B.Fab")
			(hide yes)
			(effects
				(font
					(size 1 1)
					(thickness 0.15)
				)
				(justify mirror)
			)
		)
		(property "exclude_from_bom" ""
			(at 10.42 351.68 0)
			(layer "B.Fab")
			(hide yes)
			(effects
				(font
					(size 1 1)
					(thickness 0.15)
				)
				(justify mirror)
			)
		)
		(sheetname "DC-DC Converters")
		(sheetfile "dc-dc.kicad_sch")
		(attr smd exclude_from_bom)
		(fp_rect
			(start -0.925 0.47)
			(end 0.925 -0.47)
			(stroke
				(width 0.05)
				(type default)
			)
			(fill no)
			(layer "B.CrtYd")
		)
		(fp_rect
			(start -0.5 0.25)
			(end 0.5 -0.25)
			(stroke
				(width 0.15)
				(type solid)
			)
			(fill no)
			(layer "B.Fab")
		)
		(pad "1" smd roundrect
			(at -0.48 0 270)
			(size 0.59 0.64)
			(layers "B.Cu" "B.Mask" "B.Paste")
			(roundrect_rratio 0.25)
			(net 957 "/DC-DC Converters/FB6")
			(pintype "passive")
		)
		(pad "2" smd roundrect
			(at 0.48 0 270)
			(size 0.59 0.64)
			(layers "B.Cu" "B.Mask" "B.Paste")
			(roundrect_rratio 0.25)
			(net 958 "/DC-DC Converters/FB5")
			(pintype "passive")
		)
	)
	(footprint "antmicro-footprints:SC70-3"
		(layer "B.Cu")
		(at 240.55 142.05 90)
		(property "Reference" "Q17"
			(at 0.725 -1.376 270)
			(layer "B.SilkS")
			(effects
				(font
					(size 0.7 0.7)
					(thickness 0.15)
				)
				(justify left bottom mirror)
			)
		)
		(property "Value" "BSS138PW"
			(at 0 -2.3 270)
			(layer "B.Fab")
			(effects
				(font
					(size 0.7 0.7)
					(thickness 0.15)
				)
				(justify left bottom mirror)
			)
		)
		(property "Description" "Power MOSFET, N Channel, 60 V, 320 mA, 0.9 ohm, SOT-323, Surface Mount"
			(at 0 0 90)
			(layer "F.Fab")
			(hide yes)
			(effects
				(font
					(size 1.27 1.27)
					(thickness 0.15)
				)
			)
		)
		(property "Author" "Antmicro"
			(at 382.6 -98.5 0)
			(layer "B.Fab")
			(hide yes)
			(effects
				(font
					(size 1 1)
					(thickness 0.15)
				)
				(justify mirror)
			)
		)
		(property "License" "Apache-2.0"
			(at 382.6 -98.5 0)
			(layer "B.Fab")
			(hide yes)
			(effects
				(font
					(size 1 1)
					(thickness 0.15)
				)
				(justify mirror)
			)
		)
		(property "MPN" "BSS138PW"
			(at 382.6 -98.5 0)
			(layer "B.Fab")
			(hide yes)
			(effects
				(font
					(size 1 1)
					(thickness 0.15)
				)
				(justify mirror)
			)
		)
		(property "Manufacturer" "Nexperia"
			(at 382.6 -98.5 0)
			(layer "B.Fab")
			(hide yes)
			(effects
				(font
					(size 1 1)
					(thickness 0.15)
				)
				(justify mirror)
			)
		)
		(sheetname "USB PHY")
		(sheetfile "usb-phy.kicad_sch")
		(attr smd)
		(fp_line
			(start -0.3 -1)
			(end 0.627 -1.001)
			(stroke
				(width 0.15)
				(type solid)
			)
			(layer "B.SilkS")
		)
		(fp_line
			(start 0.627 -0.6)
			(end 0.627 -1.001)
			(stroke
				(width 0.15)
				(type solid)
			)
			(layer "B.SilkS")
		)
		(fp_line
			(start 0.627 0.6)
			(end 0.627 0.999)
			(stroke
				(width 0.15)
				(type solid)
			)
			(layer "B.SilkS")
		)
		(fp_line
			(start -0.3 1)
			(end 0.627 0.999)
			(stroke
				(width 0.15)
				(type solid)
			)
			(layer "B.SilkS")
		)
		(fp_line
			(start 0.9 -1.3)
			(end -0.9 -1.3)
			(stroke
				(width 0.05)
				(type solid)
			)
			(layer "B.CrtYd")
		)
		(fp_line
			(start -0.9 -1.3)
			(end -0.9 -1)
			(stroke
				(width 0.05)
				(type solid)
			)
			(layer "B.CrtYd")
		)
		(fp_line
			(start -0.9 -1)
			(end -1.4 -1)
			(stroke
				(width 0.05)
				(type solid)
			)
			(layer "B.CrtYd")
		)
		(fp_line
			(start -1.4 -1)
			(end -1.4 1)
			(stroke
				(width 0.05)
				(type solid)
			)
			(layer "B.CrtYd")
		)
		(fp_line
			(start 1.4 -0.4)
			(end 0.9 -0.4)
			(stroke
				(width 0.05)
				(type solid)
			)
			(layer "B.CrtYd")
		)
		(fp_line
			(start 0.9 -0.4)
			(end 0.9 -1.3)
			(stroke
				(width 0.05)
				(type solid)
			)
			(layer "B.CrtYd")
		)
		(fp_line
			(start 1.4 0.4)
			(end 1.4 -0.4)
			(stroke
				(width 0.05)
				(type solid)
			)
			(layer "B.CrtYd")
		)
		(fp_line
			(start 0.9 0.4)
			(end 1.4 0.4)
			(stroke
				(width 0.05)
				(type solid)
			)
			(layer "B.CrtYd")
		)
		(fp_line
			(start -0.9 1)
			(end -1.4 1)
			(stroke
				(width 0.05)
				(type solid)
			)
			(layer "B.CrtYd")
		)
		(fp_line
			(start 0.9 1.3)
			(end 0.9 0.4)
			(stroke
				(width 0.05)
				(type solid)
			)
			(layer "B.CrtYd")
		)
		(fp_line
			(start -0.9 1.3)
			(end -0.9 1)
			(stroke
				(width 0.05)
				(type solid)
			)
			(layer "B.CrtYd")
		)
		(fp_line
			(start -0.9 1.3)
			(end 0.9 1.3)
			(stroke
				(width 0.05)
				(type solid)
			)
			(layer "B.CrtYd")
		)
		(fp_rect
			(start -0.623 0.999)
			(end 0.627 -1.001)
			(stroke
				(width 0.15)
				(type solid)
			)
			(fill no)
			(layer "B.Fab")
		)
		(pad "1" smd rect
			(at -1.051 0.65)
			(size 0.6 0.6)
			(layers "B.Cu" "B.Mask" "B.Paste")
			(net 343 "Net-(Q17-G)")
			(pinfunction "G")
			(pintype "passive")
		)
		(pad "2" smd rect
			(at -1.051 -0.65)
			(size 0.6 0.6)
			(layers "B.Cu" "B.Mask" "B.Paste")
			(net 1 "GND")
			(pinfunction "S")
			(pintype "passive")
		)
		(pad "3" smd rect
			(at 1.05 0)
			(size 0.6 0.6)
			(layers "B.Cu" "B.Mask" "B.Paste")
			(net 878 "/USB PHY/~{BDBUS3}")
			(pinfunction "D")
			(pintype "passive")
		)
	)
	(footprint "antmicro-footprints:R_0603_1608Metric"
		(layer "B.Cu")
		(at 250.401 170.3)
		(descr "Resistor SMD 0603")
		(tags "resistor SMD 0603")
		(property "Reference" "R262"
			(at 1.309 1.4 180)
			(layer "B.SilkS")
			(effects
				(font
					(size 0.7 0.7)
					(thickness 0.15)
				)
				(justify left bottom mirror)
			)
		)
		(property "Value" "R_220R_0603"
			(at 0 -1.6 180)
			(layer "B.Fab")
			(effects
				(font
					(size 0.7 0.7)
					(thickness 0.15)
				)
				(justify left bottom mirror)
			)
		)
		(property "Description" "SMD Chip Resistor, 220 ohm, ± 1%, 100 mW, 0603 [1608 Metric], Thick Film, General Purpose"
			(at 0 0 0)
			(layer "F.Fab")
			(hide yes)
			(effects
				(font
					(size 1.27 1.27)
					(thickness 0.15)
				)
			)
		)
		(property "Author" "Antmicro"
			(at 0 0 0)
			(layer "B.Fab")
			(hide yes)
			(effects
				(font
					(size 1 1)
					(thickness 0.15)
				)
				(justify mirror)
			)
		)
		(property "License" "Apache-2.0"
			(at 0 0 0)
			(layer "B.Fab")
			(hide yes)
			(effects
				(font
					(size 1 1)
					(thickness 0.15)
				)
				(justify mirror)
			)
		)
		(property "MPN" "CR0603-FX-2200ELF"
			(at 0 0 0)
			(layer "B.Fab")
			(hide yes)
			(effects
				(font
					(size 1 1)
					(thickness 0.15)
				)
				(justify mirror)
			)
		)
		(property "Manufacturer" "Bourns"
			(at 0 0 0)
			(layer "B.Fab")
			(hide yes)
			(effects
				(font
					(size 1 1)
					(thickness 0.15)
				)
				(justify mirror)
			)
		)
		(property "Tolerance" "1%"
			(at 0 0 0)
			(layer "B.Fab")
			(hide yes)
			(effects
				(font
					(size 1 1)
					(thickness 0.15)
				)
				(justify mirror)
			)
		)
		(property "Val" "220R"
			(at 0 0 0)
			(layer "B.Fab")
			(hide yes)
			(effects
				(font
					(size 1 1)
					(thickness 0.15)
				)
				(justify mirror)
			)
		)
		(sheetname "HDMI + Ethernet")
		(sheetfile "hdmi-ethernet.kicad_sch")
		(attr smd)
		(fp_line
			(start -0.15 -0.4)
			(end 0.15 -0.4)
			(stroke
				(width 0.15)
				(type solid)
			)
			(layer "B.SilkS")
		)
		(fp_line
			(start -0.15 0.4)
			(end 0.15 0.4)
			(stroke
				(width 0.15)
				(type solid)
			)
			(layer "B.SilkS")
		)
		(fp_rect
			(start -1.25 0.65)
			(end 1.25 -0.65)
			(stroke
				(width 0.05)
				(type solid)
			)
			(fill no)
			(layer "B.CrtYd")
		)
		(fp_rect
			(start -0.8 0.4)
			(end 0.8 -0.4)
			(stroke
				(width 0.15)
				(type solid)
			)
			(fill no)
			(layer "B.Fab")
		)
		(pad "1" smd roundrect
			(at -0.7 0)
			(size 0.8 1)
			(layers "B.Cu" "B.Mask" "B.Paste")
			(roundrect_rratio 0.2)
			(net 849 "/HDMI + Ethernet/GBE_LED_LINK+")
			(pintype "passive")
		)
		(pad "2" smd roundrect
			(at 0.7 0)
			(size 0.8 1)
			(layers "B.Cu" "B.Mask" "B.Paste")
			(roundrect_rratio 0.2)
			(net 24 "+3V3")
			(pintype "passive")
		)
	)
	(footprint "antmicro-footprints:R_0402_1005Metric"
		(layer "B.Cu")
		(at 227.1 155.2 180)
		(descr "Resistor SMD 0402")
		(tags "resistor SMD 0402")
		(property "Reference" "R230"
			(at 0.725 -0.375 0)
			(layer "B.SilkS")
			(effects
				(font
					(size 0.7 0.7)
					(thickness 0.15)
				)
				(justify left bottom mirror)
			)
		)
		(property "Value" "R_2k2_0402"
			(at 0 -1.4 0)
			(layer "B.Fab")
			(effects
				(font
					(size 0.7 0.7)
					(thickness 0.15)
				)
				(justify left bottom mirror)
			)
		)
		(property "Description" "SMD Chip Resistor, 2.2 kohm, ± 1%, 62.5 mW, 0402 [1005 Metric], Thick Film, General Purpose"
			(at 0 0 180)
			(layer "F.Fab")
			(hide yes)
			(effects
				(font
					(size 1.27 1.27)
					(thickness 0.15)
				)
			)
		)
		(property "Author" "Antmicro"
			(at 454.2 310.4 0)
			(layer "B.Fab")
			(hide yes)
			(effects
				(font
					(size 1 1)
					(thickness 0.15)
				)
				(justify mirror)
			)
		)
		(property "License" "Apache-2.0"
			(at 454.2 310.4 0)
			(layer "B.Fab")
			(hide yes)
			(effects
				(font
					(size 1 1)
					(thickness 0.15)
				)
				(justify mirror)
			)
		)
		(property "MPN" "CR0402-FX-2201GLF"
			(at 454.2 310.4 0)
			(layer "B.Fab")
			(hide yes)
			(effects
				(font
					(size 1 1)
					(thickness 0.15)
				)
				(justify mirror)
			)
		)
		(property "Manufacturer" "Bourns"
			(at 454.2 310.4 0)
			(layer "B.Fab")
			(hide yes)
			(effects
				(font
					(size 1 1)
					(thickness 0.15)
				)
				(justify mirror)
			)
		)
		(property "Tolerance" "1%"
			(at 454.2 310.4 0)
			(layer "B.Fab")
			(hide yes)
			(effects
				(font
					(size 1 1)
					(thickness 0.15)
				)
				(justify mirror)
			)
		)
		(property "Val" "2k2"
			(at 454.2 310.4 0)
			(layer "B.Fab")
			(hide yes)
			(effects
				(font
					(size 1 1)
					(thickness 0.15)
				)
				(justify mirror)
			)
		)
		(sheetname "HDMI + Ethernet")
		(sheetfile "hdmi-ethernet.kicad_sch")
		(attr smd)
		(fp_rect
			(start -0.925 0.47)
			(end 0.925 -0.47)
			(stroke
				(width 0.05)
				(type default)
			)
			(fill no)
			(layer "B.CrtYd")
		)
		(fp_rect
			(start -0.5 0.25)
			(end 0.5 -0.25)
			(stroke
				(width 0.15)
				(type solid)
			)
			(fill no)
			(layer "B.Fab")
		)
		(pad "1" smd roundrect
			(at -0.48 0 180)
			(size 0.59 0.64)
			(layers "B.Cu" "B.Mask" "B.Paste")
			(roundrect_rratio 0.25)
			(net 846 "/HDMI + Ethernet/ETH_LED_SPD-")
			(pintype "passive")
		)
		(pad "2" smd roundrect
			(at 0.48 0 180)
			(size 0.59 0.64)
			(layers "B.Cu" "B.Mask" "B.Paste")
			(roundrect_rratio 0.25)
			(net 1 "GND")
			(pintype "passive")
		)
	)
	(footprint "antmicro-footprints:R_0402_1005Metric"
		(layer "B.Cu")
		(at 266.001 125.7)
		(descr "Resistor SMD 0402")
		(tags "resistor SMD 0402")
		(property "Reference" "R171"
			(at -0.901 0.675 180)
			(layer "B.SilkS")
			(effects
				(font
					(size 0.7 0.7)
					(thickness 0.15)
				)
				(justify left bottom mirror)
			)
		)
		(property "Value" "R_1k5_0402"
			(at 0 -1.4 180)
			(layer "B.Fab")
			(effects
				(font
					(size 0.7 0.7)
					(thickness 0.15)
				)
				(justify left bottom mirror)
			)
		)
		(property "Description" "SMD Chip Resistor, 1.5 kohm, ± 1%, 62.5 mW, 0402 [1005 Metric], Thick Film, General Purpose"
			(at 0 0 0)
			(layer "F.Fab")
			(hide yes)
			(effects
				(font
					(size 1.27 1.27)
					(thickness 0.15)
				)
			)
		)
		(property "Author" "Antmicro"
			(at 0 0 0)
			(layer "B.Fab")
			(hide yes)
			(effects
				(font
					(size 1 1)
					(thickness 0.15)
				)
				(justify mirror)
			)
		)
		(property "License" "Apache-2.0"
			(at 0 0 0)
			(layer "B.Fab")
			(hide yes)
			(effects
				(font
					(size 1 1)
					(thickness 0.15)
				)
				(justify mirror)
			)
		)
		(property "MPN" "CR0402-FX-1501GLF"
			(at 0 0 0)
			(layer "B.Fab")
			(hide yes)
			(effects
				(font
					(size 1 1)
					(thickness 0.15)
				)
				(justify mirror)
			)
		)
		(property "Manufacturer" "Bourns"
			(at 0 0 0)
			(layer "B.Fab")
			(hide yes)
			(effects
				(font
					(size 1 1)
					(thickness 0.15)
				)
				(justify mirror)
			)
		)
		(property "Tolerance" "1%"
			(at 0 0 0)
			(layer "B.Fab")
			(hide yes)
			(effects
				(font
					(size 1 1)
					(thickness 0.15)
				)
				(justify mirror)
			)
		)
		(property "Val" "1k5"
			(at 0 0 0)
			(layer "B.Fab")
			(hide yes)
			(effects
				(font
					(size 1 1)
					(thickness 0.15)
				)
				(justify mirror)
			)
		)
		(sheetname "USB PHY")
		(sheetfile "usb-phy.kicad_sch")
		(attr smd)
		(fp_rect
			(start -0.925 0.47)
			(end 0.925 -0.47)
			(stroke
				(width 0.05)
				(type default)
			)
			(fill no)
			(layer "B.CrtYd")
		)
		(fp_rect
			(start -0.5 0.25)
			(end 0.5 -0.25)
			(stroke
				(width 0.15)
				(type solid)
			)
			(fill no)
			(layer "B.Fab")
		)
		(pad "1" smd roundrect
			(at -0.48 0)
			(size 0.59 0.64)
			(layers "B.Cu" "B.Mask" "B.Paste")
			(roundrect_rratio 0.25)
			(net 842 "/USB PHY/USB_USR_CONN_D+")
			(pintype "passive")
		)
		(pad "2" smd roundrect
			(at 0.48 0)
			(size 0.59 0.64)
			(layers "B.Cu" "B.Mask" "B.Paste")
			(roundrect_rratio 0.25)
			(net 926 "/USB PHY/USB_USR_VPU")
			(pintype "passive")
		)
	)
	(footprint "antmicro-footprints:C_0201"
		(layer "B.Cu")
		(at 202.65 131.6 -90)
		(descr "Capacitor SMD 0201")
		(tags "capacitor SMD 0201")
		(property "Reference" "C135"
			(at -30.65 -27 90)
			(layer "B.SilkS")
			(effects
				(font
					(size 0.7 0.7)
					(thickness 0.15)
				)
				(justify left bottom mirror)
			)
		)
		(property "Value" "C_100n_0201"
			(at 0 -1.4 90)
			(layer "B.Fab")
			(effects
				(font
					(size 0.7 0.7)
					(thickness 0.15)
				)
				(justify left bottom mirror)
			)
		)
		(property "Description" "SMD Multilayer Ceramic Capacitor, 0.1 µF, 6.3 V, 0201 [0603 Metric], ± 10%, X6S, CC Series"
			(at 0 0 270)
			(layer "F.Fab")
			(hide yes)
			(effects
				(font
					(size 1.27 1.27)
					(thickness 0.15)
				)
			)
		)
		(property "Author" "Antmicro"
			(at 71.05 334.25 0)
			(layer "B.Fab")
			(hide yes)
			(effects
				(font
					(size 1 1)
					(thickness 0.15)
				)
				(justify mirror)
			)
		)
		(property "Dielectric" ""
			(at 71.05 334.25 0)
			(layer "B.Fab")
			(hide yes)
			(effects
				(font
					(size 1 1)
					(thickness 0.15)
				)
				(justify mirror)
			)
		)
		(property "License" "Apache-2.0"
			(at 71.05 334.25 0)
			(layer "B.Fab")
			(hide yes)
			(effects
				(font
					(size 1 1)
					(thickness 0.15)
				)
				(justify mirror)
			)
		)
		(property "MPN" "CC0201KRX6S5BB104"
			(at 71.05 334.25 0)
			(layer "B.Fab")
			(hide yes)
			(effects
				(font
					(size 1 1)
					(thickness 0.15)
				)
				(justify mirror)
			)
		)
		(property "Manufacturer" "YAGEO"
			(at 71.05 334.25 0)
			(layer "B.Fab")
			(hide yes)
			(effects
				(font
					(size 1 1)
					(thickness 0.15)
				)
				(justify mirror)
			)
		)
		(property "Val" "100n"
			(at 71.05 334.25 0)
			(layer "B.Fab")
			(hide yes)
			(effects
				(font
					(size 1 1)
					(thickness 0.15)
				)
				(justify mirror)
			)
		)
		(property "Voltage" ""
			(at 71.05 334.25 0)
			(layer "B.Fab")
			(hide yes)
			(effects
				(font
					(size 1 1)
					(thickness 0.15)
				)
				(justify mirror)
			)
		)
		(sheetname "FPGA supply")
		(sheetfile "fpga-supply.kicad_sch")
		(attr smd)
		(fp_rect
			(start -0.7 0.35)
			(end 0.7 -0.35)
			(stroke
				(width 0.05)
				(type default)
			)
			(fill no)
			(layer "B.CrtYd")
		)
		(fp_rect
			(start 0.3 -0.15)
			(end -0.301 0.149)
			(stroke
				(width 0.15)
				(type solid)
			)
			(fill no)
			(layer "B.Fab")
		)
		(pad "" smd roundrect
			(at -0.349 0.002 270)
			(size 0.318 0.36)
			(layers "B.Paste")
			(roundrect_rratio 0.25)
		)
		(pad "" smd roundrect
			(at 0.341 0.002 270)
			(size 0.318 0.36)
			(layers "B.Paste")
			(roundrect_rratio 0.25)
		)
		(pad "1" smd roundrect
			(at -0.321 0.002 270)
			(size 0.46 0.4)
			(layers "B.Cu" "B.Mask")
			(roundrect_rratio 0.25)
			(net 1 "GND")
			(pintype "passive")
		)
		(pad "2" smd roundrect
			(at 0.32 0.002 270)
			(size 0.46 0.4)
			(layers "B.Cu" "B.Mask")
			(roundrect_rratio 0.25)
			(net 650 "+1V0")
			(pintype "passive")
		)
	)
	(footprint "antmicro-footprints:R_0402_1005Metric"
		(layer "B.Cu")
		(at 203.101 74.233 -90)
		(descr "Resistor SMD 0402")
		(tags "resistor SMD 0402")
		(property "Reference" "R3"
			(at 0.742 -0.399 90)
			(layer "B.SilkS")
			(effects
				(font
					(size 0.7 0.7)
					(thickness 0.15)
				)
				(justify left bottom mirror)
			)
		)
		(property "Value" "R_10k_0402"
			(at 0 -1.4 90)
			(layer "B.Fab")
			(effects
				(font
					(size 0.7 0.7)
					(thickness 0.15)
				)
				(justify left bottom mirror)
			)
		)
		(property "Description" "SMD Chip Resistor, 10 kohm, ± 1%, 62.5 mW, 0402 [1005 Metric], Thick Film, General Purpose"
			(at 0 0 270)
			(layer "F.Fab")
			(hide yes)
			(effects
				(font
					(size 1.27 1.27)
					(thickness 0.15)
				)
			)
		)
		(property "Author" "Antmicro"
			(at 128.868 277.334 0)
			(layer "B.Fab")
			(hide yes)
			(effects
				(font
					(size 1 1)
					(thickness 0.15)
				)
				(justify mirror)
			)
		)
		(property "DNP" "DNP"
			(at 128.868 277.334 0)
			(layer "B.Fab")
			(hide yes)
			(effects
				(font
					(size 1 1)
					(thickness 0.15)
				)
				(justify mirror)
			)
		)
		(property "License" "Apache-2.0"
			(at 128.868 277.334 0)
			(layer "B.Fab")
			(hide yes)
			(effects
				(font
					(size 1 1)
					(thickness 0.15)
				)
				(justify mirror)
			)
		)
		(property "MPN" "CR0402-FX-1002GLF"
			(at 128.868 277.334 0)
			(layer "B.Fab")
			(hide yes)
			(effects
				(font
					(size 1 1)
					(thickness 0.15)
				)
				(justify mirror)
			)
		)
		(property "Manufacturer" "Bourns"
			(at 128.868 277.334 0)
			(layer "B.Fab")
			(hide yes)
			(effects
				(font
					(size 1 1)
					(thickness 0.15)
				)
				(justify mirror)
			)
		)
		(property "Tolerance" "1%"
			(at 128.868 277.334 0)
			(layer "B.Fab")
			(hide yes)
			(effects
				(font
					(size 1 1)
					(thickness 0.15)
				)
				(justify mirror)
			)
		)
		(property "Val" "10k"
			(at 128.868 277.334 0)
			(layer "B.Fab")
			(hide yes)
			(effects
				(font
					(size 1 1)
					(thickness 0.15)
				)
				(justify mirror)
			)
		)
		(property "dnp" ""
			(at 128.868 277.334 0)
			(layer "B.Fab")
			(hide yes)
			(effects
				(font
					(size 1 1)
					(thickness 0.15)
				)
				(justify mirror)
			)
		)
		(property "exclude_from_bom" ""
			(at 128.868 277.334 0)
			(layer "B.Fab")
			(hide yes)
			(effects
				(font
					(size 1 1)
					(thickness 0.15)
				)
				(justify mirror)
			)
		)
		(sheetname "FPGA Config")
		(sheetfile "fpga-config.kicad_sch")
		(attr smd exclude_from_bom)
		(fp_rect
			(start -0.925 0.47)
			(end 0.925 -0.47)
			(stroke
				(width 0.05)
				(type default)
			)
			(fill no)
			(layer "B.CrtYd")
		)
		(fp_rect
			(start -0.5 0.25)
			(end 0.5 -0.25)
			(stroke
				(width 0.15)
				(type solid)
			)
			(fill no)
			(layer "B.Fab")
		)
		(pad "1" smd roundrect
			(at -0.48 0 270)
			(size 0.59 0.64)
			(layers "B.Cu" "B.Mask" "B.Paste")
			(roundrect_rratio 0.25)
			(net 24 "+3V3")
			(pintype "passive")
		)
		(pad "2" smd roundrect
			(at 0.48 0 270)
			(size 0.59 0.64)
			(layers "B.Cu" "B.Mask" "B.Paste")
			(roundrect_rratio 0.25)
			(net 299 "/FPGA Config/MODE1")
			(pintype "passive")
		)
	)
	(footprint "antmicro-footprints:R_0402_1005Metric"
		(layer "B.Cu")
		(at 180.05 175.2625 -90)
		(descr "Resistor SMD 0402")
		(tags "resistor SMD 0402")
		(property "Reference" "R319"
			(at 0.7125 -0.375 90)
			(layer "B.SilkS")
			(effects
				(font
					(size 0.7 0.7)
					(thickness 0.15)
				)
				(justify left bottom mirror)
			)
		)
		(property "Value" "R_0R_0402"
			(at 0 -1.4 90)
			(layer "B.Fab")
			(effects
				(font
					(size 0.7 0.7)
					(thickness 0.15)
				)
				(justify left bottom mirror)
			)
		)
		(property "Description" "SMD Chip Resistor, Jumper, 0 ohm, 100 mW, 0402 [1005 Metric], Thick Film, General Purpose"
			(at 0 0 270)
			(layer "F.Fab")
			(hide yes)
			(effects
				(font
					(size 1.27 1.27)
					(thickness 0.15)
				)
			)
		)
		(property "Author" "Antmicro"
			(at 4.7875 355.3125 0)
			(layer "B.Fab")
			(hide yes)
			(effects
				(font
					(size 1 1)
					(thickness 0.15)
				)
				(justify mirror)
			)
		)
		(property "Current" "1A"
			(at 4.7875 355.3125 0)
			(layer "B.Fab")
			(hide yes)
			(effects
				(font
					(size 1 1)
					(thickness 0.15)
				)
				(justify mirror)
			)
		)
		(property "DNP" "DNP"
			(at 4.7875 355.3125 0)
			(layer "B.Fab")
			(hide yes)
			(effects
				(font
					(size 1 1)
					(thickness 0.15)
				)
				(justify mirror)
			)
		)
		(property "License" "Apache-2.0"
			(at 4.7875 355.3125 0)
			(layer "B.Fab")
			(hide yes)
			(effects
				(font
					(size 1 1)
					(thickness 0.15)
				)
				(justify mirror)
			)
		)
		(property "MPN" "ERJ2GE0R00X"
			(at 4.7875 355.3125 0)
			(layer "B.Fab")
			(hide yes)
			(effects
				(font
					(size 1 1)
					(thickness 0.15)
				)
				(justify mirror)
			)
		)
		(property "Manufacturer" "Panasonic"
			(at 4.7875 355.3125 0)
			(layer "B.Fab")
			(hide yes)
			(effects
				(font
					(size 1 1)
					(thickness 0.15)
				)
				(justify mirror)
			)
		)
		(property "Tolerance" ""
			(at 4.7875 355.3125 0)
			(layer "B.Fab")
			(hide yes)
			(effects
				(font
					(size 1 1)
					(thickness 0.15)
				)
				(justify mirror)
			)
		)
		(property "Val" "0R"
			(at 4.7875 355.3125 0)
			(layer "B.Fab")
			(hide yes)
			(effects
				(font
					(size 1 1)
					(thickness 0.15)
				)
				(justify mirror)
			)
		)
		(property "dnp" ""
			(at 4.7875 355.3125 0)
			(layer "B.Fab")
			(hide yes)
			(effects
				(font
					(size 1 1)
					(thickness 0.15)
				)
				(justify mirror)
			)
		)
		(property "exclude_from_bom" ""
			(at 4.7875 355.3125 0)
			(layer "B.Fab")
			(hide yes)
			(effects
				(font
					(size 1 1)
					(thickness 0.15)
				)
				(justify mirror)
			)
		)
		(sheetname "DC-DC Converters")
		(sheetfile "dc-dc.kicad_sch")
		(attr smd exclude_from_bom)
		(fp_rect
			(start -0.925 0.47)
			(end 0.925 -0.47)
			(stroke
				(width 0.05)
				(type default)
			)
			(fill no)
			(layer "B.CrtYd")
		)
		(fp_rect
			(start -0.5 0.25)
			(end 0.5 -0.25)
			(stroke
				(width 0.15)
				(type solid)
			)
			(fill no)
			(layer "B.Fab")
		)
		(pad "1" smd roundrect
			(at -0.48 0 270)
			(size 0.59 0.64)
			(layers "B.Cu" "B.Mask" "B.Paste")
			(roundrect_rratio 0.25)
			(net 964 "/DC-DC Converters/FB7")
			(pintype "passive")
		)
		(pad "2" smd roundrect
			(at 0.48 0 270)
			(size 0.59 0.64)
			(layers "B.Cu" "B.Mask" "B.Paste")
			(roundrect_rratio 0.25)
			(net 1214 "/DC-DC Converters/SENSE_5V_P")
			(pintype "passive")
		)
	)
	(footprint "antmicro-footprints:R_0402_1005Metric"
		(layer "B.Cu")
		(at 193.1 79.8 90)
		(descr "Resistor SMD 0402")
		(tags "resistor SMD 0402")
		(property "Reference" "R147"
			(at -0.725 0.4 270)
			(layer "B.SilkS")
			(effects
				(font
					(size 0.7 0.7)
					(thickness 0.15)
				)
				(justify left bottom mirror)
			)
		)
		(property "Value" "R_100R_0402"
			(at 0 -1.4 270)
			(layer "B.Fab")
			(effects
				(font
					(size 0.7 0.7)
					(thickness 0.15)
				)
				(justify left bottom mirror)
			)
		)
		(property "Description" "SMD Chip Resistor, 100 ohm, ± 1%, 62.5 mW, 0402 [1005 Metric], Thick Film, General Purpose"
			(at 0 0 90)
			(layer "F.Fab")
			(hide yes)
			(effects
				(font
					(size 1.27 1.27)
					(thickness 0.15)
				)
			)
		)
		(property "Author" "Antmicro"
			(at 272.9 -113.3 0)
			(layer "B.Fab")
			(hide yes)
			(effects
				(font
					(size 1 1)
					(thickness 0.15)
				)
				(justify mirror)
			)
		)
		(property "License" "Apache-2.0"
			(at 272.9 -113.3 0)
			(layer "B.Fab")
			(hide yes)
			(effects
				(font
					(size 1 1)
					(thickness 0.15)
				)
				(justify mirror)
			)
		)
		(property "MPN" "CR0402-FX-1000GLF"
			(at 272.9 -113.3 0)
			(layer "B.Fab")
			(hide yes)
			(effects
				(font
					(size 1 1)
					(thickness 0.15)
				)
				(justify mirror)
			)
		)
		(property "Manufacturer" "Bourns"
			(at 272.9 -113.3 0)
			(layer "B.Fab")
			(hide yes)
			(effects
				(font
					(size 1 1)
					(thickness 0.15)
				)
				(justify mirror)
			)
		)
		(property "Tolerance" "1%"
			(at 272.9 -113.3 0)
			(layer "B.Fab")
			(hide yes)
			(effects
				(font
					(size 1 1)
					(thickness 0.15)
				)
				(justify mirror)
			)
		)
		(property "Val" "100R"
			(at 272.9 -113.3 0)
			(layer "B.Fab")
			(hide yes)
			(effects
				(font
					(size 1 1)
					(thickness 0.15)
				)
				(justify mirror)
			)
		)
		(sheetname "User GPIO + LED + button + DIP switch")
		(sheetfile "user-gpio.kicad_sch")
		(attr smd)
		(fp_rect
			(start -0.925 0.47)
			(end 0.925 -0.47)
			(stroke
				(width 0.05)
				(type default)
			)
			(fill no)
			(layer "B.CrtYd")
		)
		(fp_rect
			(start -0.5 0.25)
			(end 0.5 -0.25)
			(stroke
				(width 0.15)
				(type solid)
			)
			(fill no)
			(layer "B.Fab")
		)
		(pad "1" smd roundrect
			(at -0.48 0 90)
			(size 0.59 0.64)
			(layers "B.Cu" "B.Mask" "B.Paste")
			(roundrect_rratio 0.25)
			(net 493 "/FPGA Bank 12 & 13/CW_HEADER.IO4")
			(pintype "passive")
		)
		(pad "2" smd roundrect
			(at 0.48 0 90)
			(size 0.59 0.64)
			(layers "B.Cu" "B.Mask" "B.Paste")
			(roundrect_rratio 0.25)
			(net 1145 "/User GPIO + LED + button + DIP switch/CW_20PIN_IO4")
			(pintype "passive")
		)
	)
	(footprint "antmicro-footprints:C_0201"
		(layer "B.Cu")
		(at 189.8 123.5 180)
		(descr "Capacitor SMD 0201")
		(tags "capacitor SMD 0201")
		(property "Reference" "C152"
			(at 0.525 -0.35 0)
			(layer "B.SilkS")
			(effects
				(font
					(size 0.7 0.7)
					(thickness 0.15)
				)
				(justify left bottom mirror)
			)
		)
		(property "Value" "C_100n_0201"
			(at 0 -1.4 0)
			(layer "B.Fab")
			(effects
				(font
					(size 0.7 0.7)
					(thickness 0.15)
				)
				(justify left bottom mirror)
			)
		)
		(property "Description" "SMD Multilayer Ceramic Capacitor, 0.1 µF, 6.3 V, 0201 [0603 Metric], ± 10%, X6S, CC Series"
			(at 0 0 180)
			(layer "F.Fab")
			(hide yes)
			(effects
				(font
					(size 1.27 1.27)
					(thickness 0.15)
				)
			)
		)
		(property "Author" "Antmicro"
			(at 379.6 247 0)
			(layer "B.Fab")
			(hide yes)
			(effects
				(font
					(size 1 1)
					(thickness 0.15)
				)
				(justify mirror)
			)
		)
		(property "Dielectric" ""
			(at 379.6 247 0)
			(layer "B.Fab")
			(hide yes)
			(effects
				(font
					(size 1 1)
					(thickness 0.15)
				)
				(justify mirror)
			)
		)
		(property "License" "Apache-2.0"
			(at 379.6 247 0)
			(layer "B.Fab")
			(hide yes)
			(effects
				(font
					(size 1 1)
					(thickness 0.15)
				)
				(justify mirror)
			)
		)
		(property "MPN" "CC0201KRX6S5BB104"
			(at 379.6 247 0)
			(layer "B.Fab")
			(hide yes)
			(effects
				(font
					(size 1 1)
					(thickness 0.15)
				)
				(justify mirror)
			)
		)
		(property "Manufacturer" "YAGEO"
			(at 379.6 247 0)
			(layer "B.Fab")
			(hide yes)
			(effects
				(font
					(size 1 1)
					(thickness 0.15)
				)
				(justify mirror)
			)
		)
		(property "Val" "100n"
			(at 379.6 247 0)
			(layer "B.Fab")
			(hide yes)
			(effects
				(font
					(size 1 1)
					(thickness 0.15)
				)
				(justify mirror)
			)
		)
		(property "Voltage" ""
			(at 379.6 247 0)
			(layer "B.Fab")
			(hide yes)
			(effects
				(font
					(size 1 1)
					(thickness 0.15)
				)
				(justify mirror)
			)
		)
		(sheetname "FPGA supply")
		(sheetfile "fpga-supply.kicad_sch")
		(attr smd)
		(fp_rect
			(start -0.7 0.35)
			(end 0.7 -0.35)
			(stroke
				(width 0.05)
				(type default)
			)
			(fill no)
			(layer "B.CrtYd")
		)
		(fp_rect
			(start 0.3 -0.15)
			(end -0.301 0.149)
			(stroke
				(width 0.15)
				(type solid)
			)
			(fill no)
			(layer "B.Fab")
		)
		(pad "" smd roundrect
			(at -0.349 0.002 180)
			(size 0.318 0.36)
			(layers "B.Paste")
			(roundrect_rratio 0.25)
		)
		(pad "" smd roundrect
			(at 0.341 0.002 180)
			(size 0.318 0.36)
			(layers "B.Paste")
			(roundrect_rratio 0.25)
		)
		(pad "1" smd roundrect
			(at -0.321 0.002 180)
			(size 0.46 0.4)
			(layers "B.Cu" "B.Mask")
			(roundrect_rratio 0.25)
			(net 1 "GND")
			(pintype "passive")
		)
		(pad "2" smd roundrect
			(at 0.32 0.002 180)
			(size 0.46 0.4)
			(layers "B.Cu" "B.Mask")
			(roundrect_rratio 0.25)
			(net 8 "+1V2_MGTAVTT")
			(pintype "passive")
		)
	)
	(footprint "antmicro-footprints:R_0402_1005Metric"
		(layer "B.Cu")
		(at 221.715 149.216)
		(descr "Resistor SMD 0402")
		(tags "resistor SMD 0402")
		(property "Reference" "R228"
			(at 0.96 2.334 180)
			(layer "B.SilkS")
			(effects
				(font
					(size 0.7 0.7)
					(thickness 0.15)
				)
				(justify left bottom mirror)
			)
		)
		(property "Value" "R_2k2_0402"
			(at 0 -1.4 180)
			(layer "B.Fab")
			(effects
				(font
					(size 0.7 0.7)
					(thickness 0.15)
				)
				(justify left bottom mirror)
			)
		)
		(property "Description" "SMD Chip Resistor, 2.2 kohm, ± 1%, 62.5 mW, 0402 [1005 Metric], Thick Film, General Purpose"
			(at 0 0 0)
			(layer "F.Fab")
			(hide yes)
			(effects
				(font
					(size 1.27 1.27)
					(thickness 0.15)
				)
			)
		)
		(property "Author" "Antmicro"
			(at 0 0 0)
			(layer "B.Fab")
			(hide yes)
			(effects
				(font
					(size 1 1)
					(thickness 0.15)
				)
				(justify mirror)
			)
		)
		(property "DNP" "DNP"
			(at 0 0 0)
			(layer "B.Fab")
			(hide yes)
			(effects
				(font
					(size 1 1)
					(thickness 0.15)
				)
				(justify mirror)
			)
		)
		(property "License" "Apache-2.0"
			(at 0 0 0)
			(layer "B.Fab")
			(hide yes)
			(effects
				(font
					(size 1 1)
					(thickness 0.15)
				)
				(justify mirror)
			)
		)
		(property "MPN" "CR0402-FX-2201GLF"
			(at 0 0 0)
			(layer "B.Fab")
			(hide yes)
			(effects
				(font
					(size 1 1)
					(thickness 0.15)
				)
				(justify mirror)
			)
		)
		(property "Manufacturer" "Bourns"
			(at 0 0 0)
			(layer "B.Fab")
			(hide yes)
			(effects
				(font
					(size 1 1)
					(thickness 0.15)
				)
				(justify mirror)
			)
		)
		(property "Tolerance" "1%"
			(at 0 0 0)
			(layer "B.Fab")
			(hide yes)
			(effects
				(font
					(size 1 1)
					(thickness 0.15)
				)
				(justify mirror)
			)
		)
		(property "Val" "2k2"
			(at 0 0 0)
			(layer "B.Fab")
			(hide yes)
			(effects
				(font
					(size 1 1)
					(thickness 0.15)
				)
				(justify mirror)
			)
		)
		(property "dnp" ""
			(at 0 0 0)
			(layer "B.Fab")
			(hide yes)
			(effects
				(font
					(size 1 1)
					(thickness 0.15)
				)
				(justify mirror)
			)
		)
		(property "exclude_from_bom" ""
			(at 0 0 0)
			(layer "B.Fab")
			(hide yes)
			(effects
				(font
					(size 1 1)
					(thickness 0.15)
				)
				(justify mirror)
			)
		)
		(sheetname "HDMI + Ethernet")
		(sheetfile "hdmi-ethernet.kicad_sch")
		(attr smd exclude_from_bom)
		(fp_rect
			(start -0.925 0.47)
			(end 0.925 -0.47)
			(stroke
				(width 0.05)
				(type default)
			)
			(fill no)
			(layer "B.CrtYd")
		)
		(fp_rect
			(start -0.5 0.25)
			(end 0.5 -0.25)
			(stroke
				(width 0.15)
				(type solid)
			)
			(fill no)
			(layer "B.Fab")
		)
		(pad "1" smd roundrect
			(at -0.48 0)
			(size 0.59 0.64)
			(layers "B.Cu" "B.Mask" "B.Paste")
			(roundrect_rratio 0.25)
			(net 947 "/HDMI + Ethernet/ETH_PHY_RXER")
			(pintype "passive")
		)
		(pad "2" smd roundrect
			(at 0.48 0)
			(size 0.59 0.64)
			(layers "B.Cu" "B.Mask" "B.Paste")
			(roundrect_rratio 0.25)
			(net 1 "GND")
			(pintype "passive")
		)
	)
	(footprint "antmicro-footprints:R_0402_1005Metric"
		(layer "B.Cu")
		(at 220.6 124.8)
		(descr "Resistor SMD 0402")
		(tags "resistor SMD 0402")
		(property "Reference" "R19"
			(at 1.325 -2.5 180)
			(layer "B.SilkS")
			(effects
				(font
					(size 0.7 0.7)
					(thickness 0.15)
				)
				(justify left bottom mirror)
			)
		)
		(property "Value" "R_0R_0402"
			(at 0 -1.4 180)
			(layer "B.Fab")
			(effects
				(font
					(size 0.7 0.7)
					(thickness 0.15)
				)
				(justify left bottom mirror)
			)
		)
		(property "Description" "SMD Chip Resistor, Jumper, 0 ohm, 100 mW, 0402 [1005 Metric], Thick Film, General Purpose"
			(at 0 0 0)
			(layer "F.Fab")
			(hide yes)
			(effects
				(font
					(size 1.27 1.27)
					(thickness 0.15)
				)
			)
		)
		(property "Author" "Antmicro"
			(at 0 0 0)
			(layer "B.Fab")
			(hide yes)
			(effects
				(font
					(size 1 1)
					(thickness 0.15)
				)
				(justify mirror)
			)
		)
		(property "Current" "1A"
			(at 0 0 0)
			(layer "B.Fab")
			(hide yes)
			(effects
				(font
					(size 1 1)
					(thickness 0.15)
				)
				(justify mirror)
			)
		)
		(property "License" "Apache-2.0"
			(at 0 0 0)
			(layer "B.Fab")
			(hide yes)
			(effects
				(font
					(size 1 1)
					(thickness 0.15)
				)
				(justify mirror)
			)
		)
		(property "MPN" "ERJ2GE0R00X"
			(at 0 0 0)
			(layer "B.Fab")
			(hide yes)
			(effects
				(font
					(size 1 1)
					(thickness 0.15)
				)
				(justify mirror)
			)
		)
		(property "Manufacturer" "Panasonic"
			(at 0 0 0)
			(layer "B.Fab")
			(hide yes)
			(effects
				(font
					(size 1 1)
					(thickness 0.15)
				)
				(justify mirror)
			)
		)
		(property "Tolerance" ""
			(at 0 0 0)
			(layer "B.Fab")
			(hide yes)
			(effects
				(font
					(size 1 1)
					(thickness 0.15)
				)
				(justify mirror)
			)
		)
		(property "Val" "0R"
			(at 0 0 0)
			(layer "B.Fab")
			(hide yes)
			(effects
				(font
					(size 1 1)
					(thickness 0.15)
				)
				(justify mirror)
			)
		)
		(sheetname "User GPIO + LED + button + DIP switch")
		(sheetfile "user-gpio.kicad_sch")
		(attr smd)
		(fp_rect
			(start -0.925 0.47)
			(end 0.925 -0.47)
			(stroke
				(width 0.05)
				(type default)
			)
			(fill no)
			(layer "B.CrtYd")
		)
		(fp_rect
			(start -0.5 0.25)
			(end 0.5 -0.25)
			(stroke
				(width 0.15)
				(type solid)
			)
			(fill no)
			(layer "B.Fab")
		)
		(pad "1" smd roundrect
			(at -0.48 0)
			(size 0.59 0.64)
			(layers "B.Cu" "B.Mask" "B.Paste")
			(roundrect_rratio 0.25)
			(net 1350 "/SUP_MCU.FAN_PWM")
			(pintype "passive")
		)
		(pad "2" smd roundrect
			(at 0.48 0)
			(size 0.59 0.64)
			(layers "B.Cu" "B.Mask" "B.Paste")
			(roundrect_rratio 0.25)
			(net 876 "/User GPIO + LED + button + DIP switch/FAN_PWM_CTRL_AON")
			(pintype "passive")
		)
	)
	(footprint "antmicro-footprints:C_0805_2012Metric"
		(layer "B.Cu")
		(at 224.725 161.05 -90)
		(descr "Capacitor SMD 0805")
		(tags "capacitor SMD 0805")
		(property "Reference" "C198"
			(at -1.5 1.15 90)
			(layer "B.SilkS")
			(effects
				(font
					(size 0.7 0.7)
					(thickness 0.15)
				)
				(justify left bottom mirror)
			)
		)
		(property "Value" "C_100n_100V_0805"
			(at 0 -1.947 90)
			(layer "B.Fab")
			(effects
				(font
					(size 0.7 0.7)
					(thickness 0.15)
				)
				(justify left bottom mirror)
			)
		)
		(property "Description" "SMT Multilayer Ceramic Capacitor, 0.1 µF, 100 V, 0805 [2012 Metric], ± 10%, X7R, CL"
			(at 0 0 270)
			(layer "F.Fab")
			(hide yes)
			(effects
				(font
					(size 1.27 1.27)
					(thickness 0.15)
				)
			)
		)
		(property "Author" "Antmicro"
			(at 63.675 385.775 0)
			(layer "B.Fab")
			(hide yes)
			(effects
				(font
					(size 1 1)
					(thickness 0.15)
				)
				(justify mirror)
			)
		)
		(property "Dielectric" "X7R"
			(at 63.675 385.775 0)
			(layer "B.Fab")
			(hide yes)
			(effects
				(font
					(size 1 1)
					(thickness 0.15)
				)
				(justify mirror)
			)
		)
		(property "License" "Apache-2.0"
			(at 63.675 385.775 0)
			(layer "B.Fab")
			(hide yes)
			(effects
				(font
					(size 1 1)
					(thickness 0.15)
				)
				(justify mirror)
			)
		)
		(property "MPN" "CL21B104KCFNNNE"
			(at 63.675 385.775 0)
			(layer "B.Fab")
			(hide yes)
			(effects
				(font
					(size 1 1)
					(thickness 0.15)
				)
				(justify mirror)
			)
		)
		(property "Manufacturer" "Samsung Electro-Mechanics"
			(at 63.675 385.775 0)
			(layer "B.Fab")
			(hide yes)
			(effects
				(font
					(size 1 1)
					(thickness 0.15)
				)
				(justify mirror)
			)
		)
		(property "Val" "100n"
			(at 63.675 385.775 0)
			(layer "B.Fab")
			(hide yes)
			(effects
				(font
					(size 1 1)
					(thickness 0.15)
				)
				(justify mirror)
			)
		)
		(property "Voltage" "100V"
			(at 63.675 385.775 0)
			(layer "B.Fab")
			(hide yes)
			(effects
				(font
					(size 1 1)
					(thickness 0.15)
				)
				(justify mirror)
			)
		)
		(sheetname "Power supply")
		(sheetfile "power-supply.kicad_sch")
		(attr smd)
		(fp_line
			(start -0.3 0.7)
			(end 0.3 0.7)
			(stroke
				(width 0.15)
				(type solid)
			)
			(layer "B.SilkS")
		)
		(fp_line
			(start -0.3 -0.7)
			(end 0.3 -0.7)
			(stroke
				(width 0.15)
				(type solid)
			)
			(layer "B.SilkS")
		)
		(fp_rect
			(start 1.95 0.9)
			(end -1.95 -0.9)
			(stroke
				(width 0.05)
				(type default)
			)
			(fill no)
			(layer "B.CrtYd")
		)
		(fp_rect
			(start -0.95 0.675)
			(end 0.95 -0.675)
			(stroke
				(width 0.15)
				(type solid)
			)
			(fill no)
			(layer "B.Fab")
		)
		(pad "1" smd roundrect
			(at -1.1 0 270)
			(size 1.2 1.3)
			(layers "B.Cu" "B.Mask" "B.Paste")
			(roundrect_rratio 0.25)
			(net 700 "/Power supply/USB_PD_VBUS")
			(pintype "passive")
		)
		(pad "2" smd roundrect
			(at 1.1 0 270)
			(size 1.2 1.3)
			(layers "B.Cu" "B.Mask" "B.Paste")
			(roundrect_rratio 0.25)
			(net 1227 "Net-(C198-Pad2)")
			(pintype "passive")
		)
	)
	(footprint "antmicro-footprints:C_0402_1005Metric"
		(layer "B.Cu")
		(at 251.501 161.6 -90)
		(descr "Capacitor SMD 0402")
		(tags "capacitor SMD 0402")
		(property "Reference" "C283"
			(at -1.375 -5.999 90)
			(layer "B.SilkS")
			(effects
				(font
					(size 0.7 0.7)
					(thickness 0.15)
				)
				(justify left bottom mirror)
			)
		)
		(property "Value" "C_100n_0402"
			(at 0 -1.169 90)
			(layer "B.Fab")
			(effects
				(font
					(size 0.7 0.7)
					(thickness 0.15)
				)
				(justify left bottom mirror)
			)
		)
		(property "Description" "SMD Multilayer Ceramic Capacitor, 0.1 µF, 50 V, 0402 [1005 Metric], ± 10%, X5R, GRM Series"
			(at 0 0 270)
			(layer "F.Fab")
			(hide yes)
			(effects
				(font
					(size 1.27 1.27)
					(thickness 0.15)
				)
			)
		)
		(property "Author" "Antmicro"
			(at 89.901 413.101 0)
			(layer "B.Fab")
			(hide yes)
			(effects
				(font
					(size 1 1)
					(thickness 0.15)
				)
				(justify mirror)
			)
		)
		(property "Dielectric" "X5R"
			(at 89.901 413.101 0)
			(layer "B.Fab")
			(hide yes)
			(effects
				(font
					(size 1 1)
					(thickness 0.15)
				)
				(justify mirror)
			)
		)
		(property "License" "Apache-2.0"
			(at 89.901 413.101 0)
			(layer "B.Fab")
			(hide yes)
			(effects
				(font
					(size 1 1)
					(thickness 0.15)
				)
				(justify mirror)
			)
		)
		(property "MPN" "GRM155R61H104KE14D"
			(at 89.901 413.101 0)
			(layer "B.Fab")
			(hide yes)
			(effects
				(font
					(size 1 1)
					(thickness 0.15)
				)
				(justify mirror)
			)
		)
		(property "Manufacturer" "Murata"
			(at 89.901 413.101 0)
			(layer "B.Fab")
			(hide yes)
			(effects
				(font
					(size 1 1)
					(thickness 0.15)
				)
				(justify mirror)
			)
		)
		(property "Val" "100n"
			(at 89.901 413.101 0)
			(layer "B.Fab")
			(hide yes)
			(effects
				(font
					(size 1 1)
					(thickness 0.15)
				)
				(justify mirror)
			)
		)
		(property "Voltage" "50V"
			(at 89.901 413.101 0)
			(layer "B.Fab")
			(hide yes)
			(effects
				(font
					(size 1 1)
					(thickness 0.15)
				)
				(justify mirror)
			)
		)
		(sheetname "HDMI + Ethernet")
		(sheetfile "hdmi-ethernet.kicad_sch")
		(attr smd)
		(fp_rect
			(start -0.925 0.47)
			(end 0.925 -0.47)
			(stroke
				(width 0.05)
				(type default)
			)
			(fill no)
			(layer "B.CrtYd")
		)
		(fp_line
			(start -0.494 0.25)
			(end 0.504 0.25)
			(stroke
				(width 0.15)
				(type solid)
			)
			(layer "B.Fab")
		)
		(fp_line
			(start 0.504 0.25)
			(end 0.504 -0.248)
			(stroke
				(width 0.15)
				(type solid)
			)
			(layer "B.Fab")
		)
		(fp_line
			(start -0.494 -0.248)
			(end -0.494 0.25)
			(stroke
				(width 0.15)
				(type solid)
			)
			(layer "B.Fab")
		)
		(fp_line
			(start 0.504 -0.248)
			(end -0.494 -0.248)
			(stroke
				(width 0.15)
				(type solid)
			)
			(layer "B.Fab")
		)
		(pad "1" smd roundrect
			(at -0.48 0 270)
			(size 0.59 0.64)
			(layers "B.Cu" "B.Mask" "B.Paste")
			(roundrect_rratio 0.25)
			(net 1 "GND")
			(pintype "passive")
		)
		(pad "2" smd roundrect
			(at 0.48 0 270)
			(size 0.59 0.64)
			(layers "B.Cu" "B.Mask" "B.Paste")
			(roundrect_rratio 0.25)
			(net 721 "/HDMI + Ethernet/ETH_3V3")
			(pintype "passive")
		)
	)
	(footprint "antmicro-footprints:C_0402_1005Metric"
		(layer "B.Cu")
		(at 194.475 133.2)
		(descr "Capacitor SMD 0402")
		(tags "capacitor SMD 0402")
		(property "Reference" "C55"
			(at 24.175 -28.075 180)
			(layer "B.SilkS")
			(effects
				(font
					(size 0.7 0.7)
					(thickness 0.15)
				)
				(justify left bottom mirror)
			)
		)
		(property "Value" "C_100n_0402"
			(at 0 -1.169 180)
			(layer "B.Fab")
			(effects
				(font
					(size 0.7 0.7)
					(thickness 0.15)
				)
				(justify left bottom mirror)
			)
		)
		(property "Description" "SMD Multilayer Ceramic Capacitor, 0.1 µF, 50 V, 0402 [1005 Metric], ± 10%, X5R, GRM Series"
			(at 0 0 0)
			(layer "F.Fab")
			(hide yes)
			(effects
				(font
					(size 1.27 1.27)
					(thickness 0.15)
				)
			)
		)
		(property "Author" "Antmicro"
			(at 0 0 0)
			(layer "B.Fab")
			(hide yes)
			(effects
				(font
					(size 1 1)
					(thickness 0.15)
				)
				(justify mirror)
			)
		)
		(property "Dielectric" "X5R"
			(at 0 0 0)
			(layer "B.Fab")
			(hide yes)
			(effects
				(font
					(size 1 1)
					(thickness 0.15)
				)
				(justify mirror)
			)
		)
		(property "License" "Apache-2.0"
			(at 0 0 0)
			(layer "B.Fab")
			(hide yes)
			(effects
				(font
					(size 1 1)
					(thickness 0.15)
				)
				(justify mirror)
			)
		)
		(property "MPN" "GRM155R61H104KE14D"
			(at 0 0 0)
			(layer "B.Fab")
			(hide yes)
			(effects
				(font
					(size 1 1)
					(thickness 0.15)
				)
				(justify mirror)
			)
		)
		(property "Manufacturer" "Murata"
			(at 0 0 0)
			(layer "B.Fab")
			(hide yes)
			(effects
				(font
					(size 1 1)
					(thickness 0.15)
				)
				(justify mirror)
			)
		)
		(property "Val" "100n"
			(at 0 0 0)
			(layer "B.Fab")
			(hide yes)
			(effects
				(font
					(size 1 1)
					(thickness 0.15)
				)
				(justify mirror)
			)
		)
		(property "Voltage" "50V"
			(at 0 0 0)
			(layer "B.Fab")
			(hide yes)
			(effects
				(font
					(size 1 1)
					(thickness 0.15)
				)
				(justify mirror)
			)
		)
		(sheetname "FPGA supply")
		(sheetfile "fpga-supply.kicad_sch")
		(attr smd)
		(fp_rect
			(start -0.925 0.47)
			(end 0.925 -0.47)
			(stroke
				(width 0.05)
				(type default)
			)
			(fill no)
			(layer "B.CrtYd")
		)
		(fp_line
			(start -0.494 -0.248)
			(end -0.494 0.25)
			(stroke
				(width 0.15)
				(type solid)
			)
			(layer "B.Fab")
		)
		(fp_line
			(start -0.494 0.25)
			(end 0.504 0.25)
			(stroke
				(width 0.15)
				(type solid)
			)
			(layer "B.Fab")
		)
		(fp_line
			(start 0.504 -0.248)
			(end -0.494 -0.248)
			(stroke
				(width 0.15)
				(type solid)
			)
			(layer "B.Fab")
		)
		(fp_line
			(start 0.504 0.25)
			(end 0.504 -0.248)
			(stroke
				(width 0.15)
				(type solid)
			)
			(layer "B.Fab")
		)
		(pad "1" smd roundrect
			(at -0.48 0)
			(size 0.59 0.64)
			(layers "B.Cu" "B.Mask" "B.Paste")
			(roundrect_rratio 0.25)
			(net 1 "GND")
			(pintype "passive")
		)
		(pad "2" smd roundrect
			(at 0.48 0)
			(size 0.59 0.64)
			(layers "B.Cu" "B.Mask" "B.Paste")
			(roundrect_rratio 0.25)
			(net 26 "+1V8")
			(pintype "passive")
		)
	)
	(footprint "antmicro-footprints:R_0402_1005Metric"
		(layer "B.Cu")
		(at 159.515001 83.635001)
		(descr "Resistor SMD 0402")
		(tags "resistor SMD 0402")
		(property "Reference" "R276"
			(at -0.765001 0.389999 180)
			(layer "B.SilkS")
			(effects
				(font
					(size 0.7 0.7)
					(thickness 0.15)
				)
				(justify left bottom mirror)
			)
		)
		(property "Value" "R_33R_0402"
			(at 0 -1.4 180)
			(layer "B.Fab")
			(effects
				(font
					(size 0.7 0.7)
					(thickness 0.15)
				)
				(justify left bottom mirror)
			)
		)
		(property "Description" "SMD Chip Resistor, 33 ohm, ± 1%, 62.5 mW, 0402 [1005 Metric], Thick Film, General Purpose"
			(at 0 0 0)
			(layer "F.Fab")
			(hide yes)
			(effects
				(font
					(size 1.27 1.27)
					(thickness 0.15)
				)
			)
		)
		(property "Author" "Antmicro"
			(at 0 0 0)
			(layer "B.Fab")
			(hide yes)
			(effects
				(font
					(size 1 1)
					(thickness 0.15)
				)
				(justify mirror)
			)
		)
		(property "License" "Apache-2.0"
			(at 0 0 0)
			(layer "B.Fab")
			(hide yes)
			(effects
				(font
					(size 1 1)
					(thickness 0.15)
				)
				(justify mirror)
			)
		)
		(property "MPN" "CR0402-FX-33R0GLF"
			(at 0 0 0)
			(layer "B.Fab")
			(hide yes)
			(effects
				(font
					(size 1 1)
					(thickness 0.15)
				)
				(justify mirror)
			)
		)
		(property "Manufacturer" "Bourns"
			(at 0 0 0)
			(layer "B.Fab")
			(hide yes)
			(effects
				(font
					(size 1 1)
					(thickness 0.15)
				)
				(justify mirror)
			)
		)
		(property "Tolerance" "1%"
			(at 0 0 0)
			(layer "B.Fab")
			(hide yes)
			(effects
				(font
					(size 1 1)
					(thickness 0.15)
				)
				(justify mirror)
			)
		)
		(property "Val" "33R"
			(at 0 0 0)
			(layer "B.Fab")
			(hide yes)
			(effects
				(font
					(size 1 1)
					(thickness 0.15)
				)
				(justify mirror)
			)
		)
		(sheetname "FMC+ HSPC")
		(sheetfile "fmc-hspc.kicad_sch")
		(attr smd)
		(fp_rect
			(start -0.925 0.47)
			(end 0.925 -0.47)
			(stroke
				(width 0.05)
				(type default)
			)
			(fill no)
			(layer "B.CrtYd")
		)
		(fp_rect
			(start -0.5 0.25)
			(end 0.5 -0.25)
			(stroke
				(width 0.15)
				(type solid)
			)
			(fill no)
			(layer "B.Fab")
		)
		(pad "1" smd roundrect
			(at -0.48 0)
			(size 0.59 0.64)
			(layers "B.Cu" "B.Mask" "B.Paste")
			(roundrect_rratio 0.25)
			(net 599 "/FMC+ HSPC/GTR_REFCLK3_R_N")
			(pintype "passive")
		)
		(pad "2" smd roundrect
			(at 0.48 0)
			(size 0.59 0.64)
			(layers "B.Cu" "B.Mask" "B.Paste")
			(roundrect_rratio 0.25)
			(net 600 "/FMC+ HSPC/GTX116.REFCLK1_N")
			(pintype "passive")
		)
	)
	(footprint "antmicro-footprints:R_0402_1005Metric"
		(layer "B.Cu")
		(at 158.245001 86.195001)
		(descr "Resistor SMD 0402")
		(tags "resistor SMD 0402")
		(property "Reference" "R274"
			(at -0.795001 0.279999 180)
			(layer "B.SilkS")
			(effects
				(font
					(size 0.7 0.7)
					(thickness 0.15)
				)
				(justify left bottom mirror)
			)
		)
		(property "Value" "R_33R_0402"
			(at 0 -1.4 180)
			(layer "B.Fab")
			(effects
				(font
					(size 0.7 0.7)
					(thickness 0.15)
				)
				(justify left bottom mirror)
			)
		)
		(property "Description" "SMD Chip Resistor, 33 ohm, ± 1%, 62.5 mW, 0402 [1005 Metric], Thick Film, General Purpose"
			(at 0 0 0)
			(layer "F.Fab")
			(hide yes)
			(effects
				(font
					(size 1.27 1.27)
					(thickness 0.15)
				)
			)
		)
		(property "Author" "Antmicro"
			(at 0 0 0)
			(layer "B.Fab")
			(hide yes)
			(effects
				(font
					(size 1 1)
					(thickness 0.15)
				)
				(justify mirror)
			)
		)
		(property "License" "Apache-2.0"
			(at 0 0 0)
			(layer "B.Fab")
			(hide yes)
			(effects
				(font
					(size 1 1)
					(thickness 0.15)
				)
				(justify mirror)
			)
		)
		(property "MPN" "CR0402-FX-33R0GLF"
			(at 0 0 0)
			(layer "B.Fab")
			(hide yes)
			(effects
				(font
					(size 1 1)
					(thickness 0.15)
				)
				(justify mirror)
			)
		)
		(property "Manufacturer" "Bourns"
			(at 0 0 0)
			(layer "B.Fab")
			(hide yes)
			(effects
				(font
					(size 1 1)
					(thickness 0.15)
				)
				(justify mirror)
			)
		)
		(property "Tolerance" "1%"
			(at 0 0 0)
			(layer "B.Fab")
			(hide yes)
			(effects
				(font
					(size 1 1)
					(thickness 0.15)
				)
				(justify mirror)
			)
		)
		(property "Val" "33R"
			(at 0 0 0)
			(layer "B.Fab")
			(hide yes)
			(effects
				(font
					(size 1 1)
					(thickness 0.15)
				)
				(justify mirror)
			)
		)
		(sheetname "FMC+ HSPC")
		(sheetfile "fmc-hspc.kicad_sch")
		(attr smd)
		(fp_rect
			(start -0.925 0.47)
			(end 0.925 -0.47)
			(stroke
				(width 0.05)
				(type default)
			)
			(fill no)
			(layer "B.CrtYd")
		)
		(fp_rect
			(start -0.5 0.25)
			(end 0.5 -0.25)
			(stroke
				(width 0.15)
				(type solid)
			)
			(fill no)
			(layer "B.Fab")
		)
		(pad "1" smd roundrect
			(at -0.48 0)
			(size 0.59 0.64)
			(layers "B.Cu" "B.Mask" "B.Paste")
			(roundrect_rratio 0.25)
			(net 595 "/FMC+ HSPC/GTR_REFCLK2_R_N")
			(pintype "passive")
		)
		(pad "2" smd roundrect
			(at 0.48 0)
			(size 0.59 0.64)
			(layers "B.Cu" "B.Mask" "B.Paste")
			(roundrect_rratio 0.25)
			(net 596 "/FMC+ HSPC/GTX116.REFCLK0_N")
			(pintype "passive")
		)
	)
	(footprint "antmicro-footprints:R_0402_1005Metric"
		(layer "B.Cu")
		(at 195.691252 96.85 180)
		(descr "Resistor SMD 0402")
		(tags "resistor SMD 0402")
		(property "Reference" "R203"
			(at 0.716252 -0.425 0)
			(layer "B.SilkS")
			(effects
				(font
					(size 0.7 0.7)
					(thickness 0.15)
				)
				(justify left bottom mirror)
			)
		)
		(property "Value" "R_10k_0402"
			(at 0 -1.4 0)
			(layer "B.Fab")
			(effects
				(font
					(size 0.7 0.7)
					(thickness 0.15)
				)
				(justify left bottom mirror)
			)
		)
		(property "Description" "SMD Chip Resistor, 10 kohm, ± 1%, 62.5 mW, 0402 [1005 Metric], Thick Film, General Purpose"
			(at 0 0 180)
			(layer "F.Fab")
			(hide yes)
			(effects
				(font
					(size 1.27 1.27)
					(thickness 0.15)
				)
			)
		)
		(property "Author" "Antmicro"
			(at 391.382504 193.7 0)
			(layer "B.Fab")
			(hide yes)
			(effects
				(font
					(size 1 1)
					(thickness 0.15)
				)
				(justify mirror)
			)
		)
		(property "DNP" "DNP"
			(at 391.382504 193.7 0)
			(layer "B.Fab")
			(hide yes)
			(effects
				(font
					(size 1 1)
					(thickness 0.15)
				)
				(justify mirror)
			)
		)
		(property "License" "Apache-2.0"
			(at 391.382504 193.7 0)
			(layer "B.Fab")
			(hide yes)
			(effects
				(font
					(size 1 1)
					(thickness 0.15)
				)
				(justify mirror)
			)
		)
		(property "MPN" "CR0402-FX-1002GLF"
			(at 391.382504 193.7 0)
			(layer "B.Fab")
			(hide yes)
			(effects
				(font
					(size 1 1)
					(thickness 0.15)
				)
				(justify mirror)
			)
		)
		(property "Manufacturer" "Bourns"
			(at 391.382504 193.7 0)
			(layer "B.Fab")
			(hide yes)
			(effects
				(font
					(size 1 1)
					(thickness 0.15)
				)
				(justify mirror)
			)
		)
		(property "Tolerance" "1%"
			(at 391.382504 193.7 0)
			(layer "B.Fab")
			(hide yes)
			(effects
				(font
					(size 1 1)
					(thickness 0.15)
				)
				(justify mirror)
			)
		)
		(property "Val" "10k"
			(at 391.382504 193.7 0)
			(layer "B.Fab")
			(hide yes)
			(effects
				(font
					(size 1 1)
					(thickness 0.15)
				)
				(justify mirror)
			)
		)
		(property "dnp" ""
			(at 391.382504 193.7 0)
			(layer "B.Fab")
			(hide yes)
			(effects
				(font
					(size 1 1)
					(thickness 0.15)
				)
				(justify mirror)
			)
		)
		(property "exclude_from_bom" ""
			(at 391.382504 193.7 0)
			(layer "B.Fab")
			(hide yes)
			(effects
				(font
					(size 1 1)
					(thickness 0.15)
				)
				(justify mirror)
			)
		)
		(sheetname "HDMI + Ethernet")
		(sheetfile "hdmi-ethernet.kicad_sch")
		(attr smd exclude_from_bom)
		(fp_rect
			(start -0.925 0.47)
			(end 0.925 -0.47)
			(stroke
				(width 0.05)
				(type default)
			)
			(fill no)
			(layer "B.CrtYd")
		)
		(fp_rect
			(start -0.5 0.25)
			(end 0.5 -0.25)
			(stroke
				(width 0.15)
				(type solid)
			)
			(fill no)
			(layer "B.Fab")
		)
		(pad "1" smd roundrect
			(at -0.48 0 180)
			(size 0.59 0.64)
			(layers "B.Cu" "B.Mask" "B.Paste")
			(roundrect_rratio 0.25)
			(net 507 "/FPGA Bank 16 & 17/GBE_RGMII.GTR_CLK")
			(pintype "passive")
		)
		(pad "2" smd roundrect
			(at 0.48 0 180)
			(size 0.59 0.64)
			(layers "B.Cu" "B.Mask" "B.Paste")
			(roundrect_rratio 0.25)
			(net 24 "+3V3")
			(pintype "passive")
		)
	)
	(footprint "antmicro-footprints:C_0201"
		(layer "B.Cu")
		(at 201.5 128.85 180)
		(descr "Capacitor SMD 0201")
		(tags "capacitor SMD 0201")
		(property "Reference" "C60"
			(at -26.9 29.025 0)
			(layer "B.SilkS")
			(effects
				(font
					(size 0.7 0.7)
					(thickness 0.15)
				)
				(justify left bottom mirror)
			)
		)
		(property "Value" "C_100n_0201"
			(at 0 -1.4 0)
			(layer "B.Fab")
			(effects
				(font
					(size 0.7 0.7)
					(thickness 0.15)
				)
				(justify left bottom mirror)
			)
		)
		(property "Description" "SMD Multilayer Ceramic Capacitor, 0.1 µF, 6.3 V, 0201 [0603 Metric], ± 10%, X6S, CC Series"
			(at 0 0 180)
			(layer "F.Fab")
			(hide yes)
			(effects
				(font
					(size 1.27 1.27)
					(thickness 0.15)
				)
			)
		)
		(property "Author" "Antmicro"
			(at 403 257.7 0)
			(layer "B.Fab")
			(hide yes)
			(effects
				(font
					(size 1 1)
					(thickness 0.15)
				)
				(justify mirror)
			)
		)
		(property "Dielectric" ""
			(at 403 257.7 0)
			(layer "B.Fab")
			(hide yes)
			(effects
				(font
					(size 1 1)
					(thickness 0.15)
				)
				(justify mirror)
			)
		)
		(property "License" "Apache-2.0"
			(at 403 257.7 0)
			(layer "B.Fab")
			(hide yes)
			(effects
				(font
					(size 1 1)
					(thickness 0.15)
				)
				(justify mirror)
			)
		)
		(property "MPN" "CC0201KRX6S5BB104"
			(at 403 257.7 0)
			(layer "B.Fab")
			(hide yes)
			(effects
				(font
					(size 1 1)
					(thickness 0.15)
				)
				(justify mirror)
			)
		)
		(property "Manufacturer" "YAGEO"
			(at 403 257.7 0)
			(layer "B.Fab")
			(hide yes)
			(effects
				(font
					(size 1 1)
					(thickness 0.15)
				)
				(justify mirror)
			)
		)
		(property "Val" "100n"
			(at 403 257.7 0)
			(layer "B.Fab")
			(hide yes)
			(effects
				(font
					(size 1 1)
					(thickness 0.15)
				)
				(justify mirror)
			)
		)
		(property "Voltage" ""
			(at 403 257.7 0)
			(layer "B.Fab")
			(hide yes)
			(effects
				(font
					(size 1 1)
					(thickness 0.15)
				)
				(justify mirror)
			)
		)
		(sheetname "FPGA supply")
		(sheetfile "fpga-supply.kicad_sch")
		(attr smd)
		(fp_rect
			(start -0.7 0.35)
			(end 0.7 -0.35)
			(stroke
				(width 0.05)
				(type default)
			)
			(fill no)
			(layer "B.CrtYd")
		)
		(fp_rect
			(start 0.3 -0.15)
			(end -0.301 0.149)
			(stroke
				(width 0.15)
				(type solid)
			)
			(fill no)
			(layer "B.Fab")
		)
		(pad "" smd roundrect
			(at -0.349 0.002 180)
			(size 0.318 0.36)
			(layers "B.Paste")
			(roundrect_rratio 0.25)
		)
		(pad "" smd roundrect
			(at 0.341 0.002 180)
			(size 0.318 0.36)
			(layers "B.Paste")
			(roundrect_rratio 0.25)
		)
		(pad "1" smd roundrect
			(at -0.321 0.002 180)
			(size 0.46 0.4)
			(layers "B.Cu" "B.Mask")
			(roundrect_rratio 0.25)
			(net 1 "GND")
			(pintype "passive")
		)
		(pad "2" smd roundrect
			(at 0.32 0.002 180)
			(size 0.46 0.4)
			(layers "B.Cu" "B.Mask")
			(roundrect_rratio 0.25)
			(net 650 "+1V0")
			(pintype "passive")
		)
	)
	(footprint "antmicro-footprints:C_0402_1005Metric"
		(layer "B.Cu")
		(at 194.475 134.175 180)
		(descr "Capacitor SMD 0402")
		(tags "capacitor SMD 0402")
		(property "Reference" "C64"
			(at -24.125 28.025 0)
			(layer "B.SilkS")
			(effects
				(font
					(size 0.7 0.7)
					(thickness 0.15)
				)
				(justify left bottom mirror)
			)
		)
		(property "Value" "C_100n_0402"
			(at 0 -1.169 0)
			(layer "B.Fab")
			(effects
				(font
					(size 0.7 0.7)
					(thickness 0.15)
				)
				(justify left bottom mirror)
			)
		)
		(property "Description" "SMD Multilayer Ceramic Capacitor, 0.1 µF, 50 V, 0402 [1005 Metric], ± 10%, X5R, GRM Series"
			(at 0 0 180)
			(layer "F.Fab")
			(hide yes)
			(effects
				(font
					(size 1.27 1.27)
					(thickness 0.15)
				)
			)
		)
		(property "Author" "Antmicro"
			(at 388.95 268.35 0)
			(layer "B.Fab")
			(hide yes)
			(effects
				(font
					(size 1 1)
					(thickness 0.15)
				)
				(justify mirror)
			)
		)
		(property "Dielectric" "X5R"
			(at 388.95 268.35 0)
			(layer "B.Fab")
			(hide yes)
			(effects
				(font
					(size 1 1)
					(thickness 0.15)
				)
				(justify mirror)
			)
		)
		(property "License" "Apache-2.0"
			(at 388.95 268.35 0)
			(layer "B.Fab")
			(hide yes)
			(effects
				(font
					(size 1 1)
					(thickness 0.15)
				)
				(justify mirror)
			)
		)
		(property "MPN" "GRM155R61H104KE14D"
			(at 388.95 268.35 0)
			(layer "B.Fab")
			(hide yes)
			(effects
				(font
					(size 1 1)
					(thickness 0.15)
				)
				(justify mirror)
			)
		)
		(property "Manufacturer" "Murata"
			(at 388.95 268.35 0)
			(layer "B.Fab")
			(hide yes)
			(effects
				(font
					(size 1 1)
					(thickness 0.15)
				)
				(justify mirror)
			)
		)
		(property "Val" "100n"
			(at 388.95 268.35 0)
			(layer "B.Fab")
			(hide yes)
			(effects
				(font
					(size 1 1)
					(thickness 0.15)
				)
				(justify mirror)
			)
		)
		(property "Voltage" "50V"
			(at 388.95 268.35 0)
			(layer "B.Fab")
			(hide yes)
			(effects
				(font
					(size 1 1)
					(thickness 0.15)
				)
				(justify mirror)
			)
		)
		(sheetname "FPGA supply")
		(sheetfile "fpga-supply.kicad_sch")
		(attr smd)
		(fp_rect
			(start -0.925 0.47)
			(end 0.925 -0.47)
			(stroke
				(width 0.05)
				(type default)
			)
			(fill no)
			(layer "B.CrtYd")
		)
		(fp_line
			(start 0.504 0.25)
			(end 0.504 -0.248)
			(stroke
				(width 0.15)
				(type solid)
			)
			(layer "B.Fab")
		)
		(fp_line
			(start 0.504 -0.248)
			(end -0.494 -0.248)
			(stroke
				(width 0.15)
				(type solid)
			)
			(layer "B.Fab")
		)
		(fp_line
			(start -0.494 0.25)
			(end 0.504 0.25)
			(stroke
				(width 0.15)
				(type solid)
			)
			(layer "B.Fab")
		)
		(fp_line
			(start -0.494 -0.248)
			(end -0.494 0.25)
			(stroke
				(width 0.15)
				(type solid)
			)
			(layer "B.Fab")
		)
		(pad "1" smd roundrect
			(at -0.48 0 180)
			(size 0.59 0.64)
			(layers "B.Cu" "B.Mask" "B.Paste")
			(roundrect_rratio 0.25)
			(net 1 "GND")
			(pintype "passive")
		)
		(pad "2" smd roundrect
			(at 0.48 0 180)
			(size 0.59 0.64)
			(layers "B.Cu" "B.Mask" "B.Paste")
			(roundrect_rratio 0.25)
			(net 26 "+1V8")
			(pintype "passive")
		)
	)
	(footprint "antmicro-footprints:R_0402_1005Metric"
		(layer "B.Cu")
		(at 220.6 123.8 180)
		(descr "Resistor SMD 0402")
		(tags "resistor SMD 0402")
		(property "Reference" "R106"
			(at -1.325 2.5 0)
			(layer "B.SilkS")
			(effects
				(font
					(size 0.7 0.7)
					(thickness 0.15)
				)
				(justify left bottom mirror)
			)
		)
		(property "Value" "R_1k_0402"
			(at 0 -1.4 0)
			(layer "B.Fab")
			(effects
				(font
					(size 0.7 0.7)
					(thickness 0.15)
				)
				(justify left bottom mirror)
			)
		)
		(property "Description" "SMD Chip Resistor, 1 kohm, ± 1%, 63 mW, 0402 [1005 Metric], Thick Film, General Purpose"
			(at 0 0 180)
			(layer "F.Fab")
			(hide yes)
			(effects
				(font
					(size 1.27 1.27)
					(thickness 0.15)
				)
			)
		)
		(property "Author" "Antmicro"
			(at 441.2 247.6 0)
			(layer "B.Fab")
			(hide yes)
			(effects
				(font
					(size 1 1)
					(thickness 0.15)
				)
				(justify mirror)
			)
		)
		(property "License" "Apache-2.0"
			(at 441.2 247.6 0)
			(layer "B.Fab")
			(hide yes)
			(effects
				(font
					(size 1 1)
					(thickness 0.15)
				)
				(justify mirror)
			)
		)
		(property "MPN" "CR0402-FX-1001GLF"
			(at 441.2 247.6 0)
			(layer "B.Fab")
			(hide yes)
			(effects
				(font
					(size 1 1)
					(thickness 0.15)
				)
				(justify mirror)
			)
		)
		(property "Manufacturer" "Bourns"
			(at 441.2 247.6 0)
			(layer "B.Fab")
			(hide yes)
			(effects
				(font
					(size 1 1)
					(thickness 0.15)
				)
				(justify mirror)
			)
		)
		(property "Tolerance" "1%"
			(at 441.2 247.6 0)
			(layer "B.Fab")
			(hide yes)
			(effects
				(font
					(size 1 1)
					(thickness 0.15)
				)
				(justify mirror)
			)
		)
		(property "Val" "1k"
			(at 441.2 247.6 0)
			(layer "B.Fab")
			(hide yes)
			(effects
				(font
					(size 1 1)
					(thickness 0.15)
				)
				(justify mirror)
			)
		)
		(sheetname "User GPIO + LED + button + DIP switch")
		(sheetfile "user-gpio.kicad_sch")
		(attr smd)
		(fp_rect
			(start -0.925 0.47)
			(end 0.925 -0.47)
			(stroke
				(width 0.05)
				(type default)
			)
			(fill no)
			(layer "B.CrtYd")
		)
		(fp_rect
			(start -0.5 0.25)
			(end 0.5 -0.25)
			(stroke
				(width 0.15)
				(type solid)
			)
			(fill no)
			(layer "B.Fab")
		)
		(pad "1" smd roundrect
			(at -0.48 0 180)
			(size 0.59 0.64)
			(layers "B.Cu" "B.Mask" "B.Paste")
			(roundrect_rratio 0.25)
			(net 876 "/User GPIO + LED + button + DIP switch/FAN_PWM_CTRL_AON")
			(pintype "passive")
		)
		(pad "2" smd roundrect
			(at 0.48 0 180)
			(size 0.59 0.64)
			(layers "B.Cu" "B.Mask" "B.Paste")
			(roundrect_rratio 0.25)
			(net 24 "+3V3")
			(pintype "passive")
		)
	)
	(footprint "antmicro-footprints:C_0603_1608Metric"
		(layer "B.Cu")
		(at 195.125 147.25)
		(descr "Capacitor SMD 0603")
		(tags "capacitor 0603")
		(property "Reference" "C54"
			(at -1.045 1.47 0)
			(layer "B.SilkS")
			(effects
				(font
					(size 0.7 0.7)
					(thickness 0.15)
				)
				(justify right bottom mirror)
			)
		)
		(property "Value" "C_47u_0603"
			(at 0 -1.6 0)
			(layer "B.Fab")
			(effects
				(font
					(size 0.7 0.7)
					(thickness 0.15)
				)
				(justify right bottom mirror)
			)
		)
		(property "Description" "SMD Multilayer Ceramic Capacitor, 47 µF, 6.3 V, 0603 [1608 Metric], ± 20%, X5R, GRM Series"
			(at 0 0 0)
			(layer "F.Fab")
			(hide yes)
			(effects
				(font
					(size 1.27 1.27)
					(thickness 0.15)
				)
			)
		)
		(property "Author" "Antmicro"
			(at 0 0 0)
			(layer "B.Fab")
			(hide yes)
			(effects
				(font
					(size 1 1)
					(thickness 0.15)
				)
				(justify mirror)
			)
		)
		(property "Dielectric" ""
			(at 0 0 0)
			(layer "B.Fab")
			(hide yes)
			(effects
				(font
					(size 1 1)
					(thickness 0.15)
				)
				(justify mirror)
			)
		)
		(property "License" "Apache-2.0"
			(at 0 0 0)
			(layer "B.Fab")
			(hide yes)
			(effects
				(font
					(size 1 1)
					(thickness 0.15)
				)
				(justify mirror)
			)
		)
		(property "MPN" "GRM188R60J476ME15D"
			(at 0 0 0)
			(layer "B.Fab")
			(hide yes)
			(effects
				(font
					(size 1 1)
					(thickness 0.15)
				)
				(justify mirror)
			)
		)
		(property "Manufacturer" "Murata"
			(at 0 0 0)
			(layer "B.Fab")
			(hide yes)
			(effects
				(font
					(size 1 1)
					(thickness 0.15)
				)
				(justify mirror)
			)
		)
		(property "Val" "47u"
			(at 0 0 0)
			(layer "B.Fab")
			(hide yes)
			(effects
				(font
					(size 1 1)
					(thickness 0.15)
				)
				(justify mirror)
			)
		)
		(property "Voltage" ""
			(at 0 0 0)
			(layer "B.Fab")
			(hide yes)
			(effects
				(font
					(size 1 1)
					(thickness 0.15)
				)
				(justify mirror)
			)
		)
		(sheetname "FPGA supply")
		(sheetfile "fpga-supply.kicad_sch")
		(attr smd)
		(fp_line
			(start -0.15 -0.4)
			(end 0.15 -0.4)
			(stroke
				(width 0.15)
				(type solid)
			)
			(layer "B.SilkS")
		)
		(fp_line
			(start -0.15 0.4)
			(end 0.15 0.4)
			(stroke
				(width 0.15)
				(type solid)
			)
			(layer "B.SilkS")
		)
		(fp_rect
			(start -1.25 0.65)
			(end 1.25 -0.65)
			(stroke
				(width 0.05)
				(type solid)
			)
			(fill no)
			(layer "B.CrtYd")
		)
		(fp_rect
			(start -0.8 0.4)
			(end 0.8 -0.4)
			(stroke
				(width 0.15)
				(type solid)
			)
			(fill no)
			(layer "B.Fab")
		)
		(pad "1" smd roundrect
			(at -0.7 0)
			(size 0.8 1)
			(layers "B.Cu" "B.Mask" "B.Paste")
			(roundrect_rratio 0.2)
			(net 1 "GND")
			(pintype "passive")
		)
		(pad "2" smd roundrect
			(at 0.7 0)
			(size 0.8 1)
			(layers "B.Cu" "B.Mask" "B.Paste")
			(roundrect_rratio 0.2)
			(net 26 "+1V8")
			(pintype "passive")
		)
	)
	(footprint "antmicro-footprints:C_0402_1005Metric"
		(layer "B.Cu")
		(at 168.6 188.2 -90)
		(descr "Capacitor SMD 0402")
		(tags "capacitor SMD 0402")
		(property "Reference" "C339"
			(at -1.8 -1.275 90)
			(layer "B.SilkS")
			(effects
				(font
					(size 0.7 0.7)
					(thickness 0.15)
				)
				(justify left bottom mirror)
			)
		)
		(property "Value" "C_100n_0402"
			(at 0 -1.4 90)
			(layer "B.Fab")
			(effects
				(font
					(size 0.7 0.7)
					(thickness 0.15)
				)
				(justify left bottom mirror)
			)
		)
		(property "Description" "SMD Multilayer Ceramic Capacitor, 0.1 µF, 50 V, 0402 [1005 Metric], ± 10%, X5R, GRM Series"
			(at 0 0 270)
			(layer "F.Fab")
			(hide yes)
			(effects
				(font
					(size 1.27 1.27)
					(thickness 0.15)
				)
			)
		)
		(property "Author" "Antmicro"
			(at -19.6 356.8 0)
			(layer "B.Fab")
			(hide yes)
			(effects
				(font
					(size 1 1)
					(thickness 0.15)
				)
				(justify mirror)
			)
		)
		(property "DNP" "DNP"
			(at -19.6 356.8 0)
			(layer "B.Fab")
			(hide yes)
			(effects
				(font
					(size 1 1)
					(thickness 0.15)
				)
				(justify mirror)
			)
		)
		(property "Dielectric" "X5R"
			(at -19.6 356.8 0)
			(layer "B.Fab")
			(hide yes)
			(effects
				(font
					(size 1 1)
					(thickness 0.15)
				)
				(justify mirror)
			)
		)
		(property "License" "Apache-2.0"
			(at -19.6 356.8 0)
			(layer "B.Fab")
			(hide yes)
			(effects
				(font
					(size 1 1)
					(thickness 0.15)
				)
				(justify mirror)
			)
		)
		(property "MPN" "GRM155R61H104KE14D"
			(at -19.6 356.8 0)
			(layer "B.Fab")
			(hide yes)
			(effects
				(font
					(size 1 1)
					(thickness 0.15)
				)
				(justify mirror)
			)
		)
		(property "Manufacturer" "Murata"
			(at -19.6 356.8 0)
			(layer "B.Fab")
			(hide yes)
			(effects
				(font
					(size 1 1)
					(thickness 0.15)
				)
				(justify mirror)
			)
		)
		(property "Val" "100n"
			(at -19.6 356.8 0)
			(layer "B.Fab")
			(hide yes)
			(effects
				(font
					(size 1 1)
					(thickness 0.15)
				)
				(justify mirror)
			)
		)
		(property "Voltage" "50V"
			(at -19.6 356.8 0)
			(layer "B.Fab")
			(hide yes)
			(effects
				(font
					(size 1 1)
					(thickness 0.15)
				)
				(justify mirror)
			)
		)
		(property "dnp" ""
			(at -19.6 356.8 0)
			(layer "B.Fab")
			(hide yes)
			(effects
				(font
					(size 1 1)
					(thickness 0.15)
				)
				(justify mirror)
			)
		)
		(property "exclude_from_bom" ""
			(at -19.6 356.8 0)
			(layer "B.Fab")
			(hide yes)
			(effects
				(font
					(size 1 1)
					(thickness 0.15)
				)
				(justify mirror)
			)
		)
		(sheetname "DC-DC Converters")
		(sheetfile "dc-dc.kicad_sch")
		(attr smd exclude_from_bom)
		(fp_rect
			(start -0.925 0.47)
			(end 0.925 -0.47)
			(stroke
				(width 0.05)
				(type default)
			)
			(fill no)
			(layer "B.CrtYd")
		)
		(fp_line
			(start -0.494 0.25)
			(end 0.504 0.25)
			(stroke
				(width 0.15)
				(type solid)
			)
			(layer "B.Fab")
		)
		(fp_line
			(start 0.504 0.25)
			(end 0.504 -0.248)
			(stroke
				(width 0.15)
				(type solid)
			)
			(layer "B.Fab")
		)
		(fp_line
			(start -0.494 -0.248)
			(end -0.494 0.25)
			(stroke
				(width 0.15)
				(type solid)
			)
			(layer "B.Fab")
		)
		(fp_line
			(start 0.504 -0.248)
			(end -0.494 -0.248)
			(stroke
				(width 0.15)
				(type solid)
			)
			(layer "B.Fab")
		)
		(pad "1" smd roundrect
			(at -0.48 0 270)
			(size 0.59 0.64)
			(layers "B.Cu" "B.Mask" "B.Paste")
			(roundrect_rratio 0.25)
			(net 1 "GND")
			(pintype "passive")
		)
		(pad "2" smd roundrect
			(at 0.48 0 270)
			(size 0.59 0.64)
			(layers "B.Cu" "B.Mask" "B.Paste")
			(roundrect_rratio 0.25)
			(net 14 "/DC-DC Converters/SEQ_EN")
			(pintype "passive")
		)
	)
	(footprint "antmicro-footprints:C_0201"
		(layer "B.Cu")
		(at 191.2 120.2 -45)
		(descr "Capacitor SMD 0201")
		(tags "capacitor SMD 0201")
		(property "Reference" "C86"
			(at -4.40174 -35.72657 315)
			(unlocked yes)
			(layer "B.SilkS")
			(effects
				(font
					(size 0.7 0.7)
					(thickness 0.15)
				)
				(justify left bottom mirror)
			)
		)
		(property "Value" "C_4u7_0201"
			(at 0 -1.399999 135)
			(layer "B.Fab")
			(effects
				(font
					(size 0.7 0.7)
					(thickness 0.15)
				)
				(justify left bottom mirror)
			)
		)
		(property "Description" "SMD Multilayer Ceramic Capacitor, 4.7 µF, 6.3 V, 0201 [0603 Metric], ± 20%, X5R, GRM Series"
			(at 0 0 315)
			(layer "F.Fab")
			(hide yes)
			(effects
				(font
					(size 1.27 1.27)
					(thickness 0.15)
				)
			)
		)
		(property "Author" "Antmicro"
			(at -28.993052 170.404582 0)
			(layer "B.Fab")
			(hide yes)
			(effects
				(font
					(size 1 1)
					(thickness 0.15)
				)
				(justify mirror)
			)
		)
		(property "Dielectric" ""
			(at -28.993052 170.404582 0)
			(layer "B.Fab")
			(hide yes)
			(effects
				(font
					(size 1 1)
					(thickness 0.15)
				)
				(justify mirror)
			)
		)
		(property "License" "Apache-2.0"
			(at -28.993052 170.404582 0)
			(layer "B.Fab")
			(hide yes)
			(effects
				(font
					(size 1 1)
					(thickness 0.15)
				)
				(justify mirror)
			)
		)
		(property "MPN" "GRM035R60J475ME15D"
			(at -28.993052 170.404582 0)
			(layer "B.Fab")
			(hide yes)
			(effects
				(font
					(size 1 1)
					(thickness 0.15)
				)
				(justify mirror)
			)
		)
		(property "Manufacturer" "Murata"
			(at -28.993052 170.404582 0)
			(layer "B.Fab")
			(hide yes)
			(effects
				(font
					(size 1 1)
					(thickness 0.15)
				)
				(justify mirror)
			)
		)
		(property "Val" "4u7"
			(at -28.993052 170.404582 0)
			(layer "B.Fab")
			(hide yes)
			(effects
				(font
					(size 1 1)
					(thickness 0.15)
				)
				(justify mirror)
			)
		)
		(property "Voltage" ""
			(at -28.993052 170.404582 0)
			(layer "B.Fab")
			(hide yes)
			(effects
				(font
					(size 1 1)
					(thickness 0.15)
				)
				(justify mirror)
			)
		)
		(sheetname "FPGA supply")
		(sheetfile "fpga-supply.kicad_sch")
		(attr smd)
		(fp_poly
			(pts
				(xy -0.7 0.35) (xy 0.7 0.35) (xy 0.7 -0.35) (xy -0.7 -0.35)
			)
			(stroke
				(width 0.05)
				(type default)
			)
			(fill no)
			(layer "B.CrtYd")
		)
		(fp_poly
			(pts
				(xy 0.3 -0.15) (xy -0.301 -0.15) (xy -0.301 0.149) (xy 0.3 0.149)
			)
			(stroke
				(width 0.15)
				(type solid)
			)
			(fill no)
			(layer "B.Fab")
		)
		(pad "" smd roundrect
			(at -0.349 0.002 315)
			(size 0.318 0.36)
			(layers "B.Paste")
			(roundrect_rratio 0.25)
		)
		(pad "" smd roundrect
			(at 0.341 0.002 315)
			(size 0.318 0.36)
			(layers "B.Paste")
			(roundrect_rratio 0.25)
		)
		(pad "1" smd roundrect
			(at -0.321 0.002 315)
			(size 0.46 0.4)
			(layers "B.Cu" "B.Mask")
			(roundrect_rratio 0.25)
			(net 1 "GND")
			(pintype "passive")
		)
		(pad "2" smd roundrect
			(at 0.32 0.002 315)
			(size 0.46 0.4)
			(layers "B.Cu" "B.Mask")
			(roundrect_rratio 0.25)
			(net 6 "+1V0_MGTAVCC")
			(pintype "passive")
		)
	)
	(footprint "antmicro-footprints:C_0402_1005Metric"
		(layer "B.Cu")
		(at 194.5 117 -90)
		(descr "Capacitor SMD 0402")
		(tags "capacitor SMD 0402")
		(property "Reference" "C99"
			(at -1.1 -1.225 90)
			(layer "B.SilkS")
			(effects
				(font
					(size 0.7 0.7)
					(thickness 0.15)
				)
				(justify left bottom mirror)
			)
		)
		(property "Value" "C_100n_0402"
			(at 0 -1.169 90)
			(layer "B.Fab")
			(effects
				(font
					(size 0.7 0.7)
					(thickness 0.15)
				)
				(justify left bottom mirror)
			)
		)
		(property "Description" "SMD Multilayer Ceramic Capacitor, 0.1 µF, 50 V, 0402 [1005 Metric], ± 10%, X5R, GRM Series"
			(at 0 0 270)
			(layer "F.Fab")
			(hide yes)
			(effects
				(font
					(size 1.27 1.27)
					(thickness 0.15)
				)
			)
		)
		(property "Author" "Antmicro"
			(at 77.5 311.5 0)
			(layer "B.Fab")
			(hide yes)
			(effects
				(font
					(size 1 1)
					(thickness 0.15)
				)
				(justify mirror)
			)
		)
		(property "Dielectric" "X5R"
			(at 77.5 311.5 0)
			(layer "B.Fab")
			(hide yes)
			(effects
				(font
					(size 1 1)
					(thickness 0.15)
				)
				(justify mirror)
			)
		)
		(property "License" "Apache-2.0"
			(at 77.5 311.5 0)
			(layer "B.Fab")
			(hide yes)
			(effects
				(font
					(size 1 1)
					(thickness 0.15)
				)
				(justify mirror)
			)
		)
		(property "MPN" "GRM155R61H104KE14D"
			(at 77.5 311.5 0)
			(layer "B.Fab")
			(hide yes)
			(effects
				(font
					(size 1 1)
					(thickness 0.15)
				)
				(justify mirror)
			)
		)
		(property "Manufacturer" "Murata"
			(at 77.5 311.5 0)
			(layer "B.Fab")
			(hide yes)
			(effects
				(font
					(size 1 1)
					(thickness 0.15)
				)
				(justify mirror)
			)
		)
		(property "Val" "100n"
			(at 77.5 311.5 0)
			(layer "B.Fab")
			(hide yes)
			(effects
				(font
					(size 1 1)
					(thickness 0.15)
				)
				(justify mirror)
			)
		)
		(property "Voltage" "50V"
			(at 77.5 311.5 0)
			(layer "B.Fab")
			(hide yes)
			(effects
				(font
					(size 1 1)
					(thickness 0.15)
				)
				(justify mirror)
			)
		)
		(sheetname "FPGA Bank 18 & 32")
		(sheetfile "fpga-bank-18-32.kicad_sch")
		(attr smd)
		(fp_rect
			(start -0.925 0.47)
			(end 0.925 -0.47)
			(stroke
				(width 0.05)
				(type default)
			)
			(fill no)
			(layer "B.CrtYd")
		)
		(fp_line
			(start -0.494 0.25)
			(end 0.504 0.25)
			(stroke
				(width 0.15)
				(type solid)
			)
			(layer "B.Fab")
		)
		(fp_line
			(start 0.504 0.25)
			(end 0.504 -0.248)
			(stroke
				(width 0.15)
				(type solid)
			)
			(layer "B.Fab")
		)
		(fp_line
			(start -0.494 -0.248)
			(end -0.494 0.25)
			(stroke
				(width 0.15)
				(type solid)
			)
			(layer "B.Fab")
		)
		(fp_line
			(start 0.504 -0.248)
			(end -0.494 -0.248)
			(stroke
				(width 0.15)
				(type solid)
			)
			(layer "B.Fab")
		)
		(pad "1" smd roundrect
			(at -0.48 0 270)
			(size 0.59 0.64)
			(layers "B.Cu" "B.Mask" "B.Paste")
			(roundrect_rratio 0.25)
			(net 1 "GND")
			(pintype "passive")
		)
		(pad "2" smd roundrect
			(at 0.48 0 270)
			(size 0.59 0.64)
			(layers "B.Cu" "B.Mask" "B.Paste")
			(roundrect_rratio 0.25)
			(net 24 "+3V3")
			(pintype "passive")
		)
	)
	(footprint "antmicro-footprints:R_0402_1005Metric"
		(layer "B.Cu")
		(at 258.4 91 -90)
		(descr "Resistor SMD 0402")
		(tags "resistor SMD 0402")
		(property "Reference" "R356"
			(at -1.3 0.45 90)
			(layer "B.SilkS")
			(effects
				(font
					(size 0.7 0.7)
					(thickness 0.15)
				)
				(justify left bottom mirror)
			)
		)
		(property "Value" "R_100k_0402"
			(at 0 -1.4 90)
			(layer "B.Fab")
			(effects
				(font
					(size 0.7 0.7)
					(thickness 0.15)
				)
				(justify left bottom mirror)
			)
		)
		(property "Description" "SMD Chip Resistor, 100 kohm, ± 1%, 62.5 mW, 0402 [1005 Metric], Thick Film, General Purpose"
			(at 0 0 270)
			(layer "F.Fab")
			(hide yes)
			(effects
				(font
					(size 1.27 1.27)
					(thickness 0.15)
				)
			)
		)
		(property "Author" "Antmicro"
			(at 167.4 349.4 0)
			(layer "B.Fab")
			(hide yes)
			(effects
				(font
					(size 1 1)
					(thickness 0.15)
				)
				(justify mirror)
			)
		)
		(property "License" "Apache-2.0"
			(at 167.4 349.4 0)
			(layer "B.Fab")
			(hide yes)
			(effects
				(font
					(size 1 1)
					(thickness 0.15)
				)
				(justify mirror)
			)
		)
		(property "MPN" "CR0402-FX-1003GLF"
			(at 167.4 349.4 0)
			(layer "B.Fab")
			(hide yes)
			(effects
				(font
					(size 1 1)
					(thickness 0.15)
				)
				(justify mirror)
			)
		)
		(property "Manufacturer" "Bourns"
			(at 167.4 349.4 0)
			(layer "B.Fab")
			(hide yes)
			(effects
				(font
					(size 1 1)
					(thickness 0.15)
				)
				(justify mirror)
			)
		)
		(property "Tolerance" "1%"
			(at 167.4 349.4 0)
			(layer "B.Fab")
			(hide yes)
			(effects
				(font
					(size 1 1)
					(thickness 0.15)
				)
				(justify mirror)
			)
		)
		(property "Val" "100k"
			(at 167.4 349.4 0)
			(layer "B.Fab")
			(hide yes)
			(effects
				(font
					(size 1 1)
					(thickness 0.15)
				)
				(justify mirror)
			)
		)
		(sheetname "User GPIO + LED + button + DIP switch")
		(sheetfile "user-gpio.kicad_sch")
		(attr smd)
		(fp_rect
			(start -0.925 0.47)
			(end 0.925 -0.47)
			(stroke
				(width 0.05)
				(type default)
			)
			(fill no)
			(layer "B.CrtYd")
		)
		(fp_rect
			(start -0.5 0.25)
			(end 0.5 -0.25)
			(stroke
				(width 0.15)
				(type solid)
			)
			(fill no)
			(layer "B.Fab")
		)
		(pad "1" smd roundrect
			(at -0.48 0 270)
			(size 0.59 0.64)
			(layers "B.Cu" "B.Mask" "B.Paste")
			(roundrect_rratio 0.25)
			(net 1302 "/USER_IO.LED_GREEN3")
			(pintype "passive")
		)
		(pad "2" smd roundrect
			(at 0.48 0 270)
			(size 0.59 0.64)
			(layers "B.Cu" "B.Mask" "B.Paste")
			(roundrect_rratio 0.25)
			(net 1 "GND")
			(pintype "passive")
		)
	)
	(footprint "antmicro-footprints:R_0402_1005Metric"
		(layer "B.Cu")
		(at 229 154.2)
		(descr "Resistor SMD 0402")
		(tags "resistor SMD 0402")
		(property "Reference" "R223"
			(at 3.65 0.375 180)
			(layer "B.SilkS")
			(effects
				(font
					(size 0.7 0.7)
					(thickness 0.15)
				)
				(justify left bottom mirror)
			)
		)
		(property "Value" "R_10k_0402"
			(at 0 -1.4 180)
			(layer "B.Fab")
			(effects
				(font
					(size 0.7 0.7)
					(thickness 0.15)
				)
				(justify left bottom mirror)
			)
		)
		(property "Description" "SMD Chip Resistor, 10 kohm, ± 1%, 62.5 mW, 0402 [1005 Metric], Thick Film, General Purpose"
			(at 0 0 0)
			(layer "F.Fab")
			(hide yes)
			(effects
				(font
					(size 1.27 1.27)
					(thickness 0.15)
				)
			)
		)
		(property "Author" "Antmicro"
			(at 0 0 0)
			(layer "B.Fab")
			(hide yes)
			(effects
				(font
					(size 1 1)
					(thickness 0.15)
				)
				(justify mirror)
			)
		)
		(property "DNP" "DNP"
			(at 0 0 0)
			(layer "B.Fab")
			(hide yes)
			(effects
				(font
					(size 1 1)
					(thickness 0.15)
				)
				(justify mirror)
			)
		)
		(property "License" "Apache-2.0"
			(at 0 0 0)
			(layer "B.Fab")
			(hide yes)
			(effects
				(font
					(size 1 1)
					(thickness 0.15)
				)
				(justify mirror)
			)
		)
		(property "MPN" "CR0402-FX-1002GLF"
			(at 0 0 0)
			(layer "B.Fab")
			(hide yes)
			(effects
				(font
					(size 1 1)
					(thickness 0.15)
				)
				(justify mirror)
			)
		)
		(property "Manufacturer" "Bourns"
			(at 0 0 0)
			(layer "B.Fab")
			(hide yes)
			(effects
				(font
					(size 1 1)
					(thickness 0.15)
				)
				(justify mirror)
			)
		)
		(property "Tolerance" "1%"
			(at 0 0 0)
			(layer "B.Fab")
			(hide yes)
			(effects
				(font
					(size 1 1)
					(thickness 0.15)
				)
				(justify mirror)
			)
		)
		(property "Val" "10k"
			(at 0 0 0)
			(layer "B.Fab")
			(hide yes)
			(effects
				(font
					(size 1 1)
					(thickness 0.15)
				)
				(justify mirror)
			)
		)
		(property "dnp" ""
			(at 0 0 0)
			(layer "B.Fab")
			(hide yes)
			(effects
				(font
					(size 1 1)
					(thickness 0.15)
				)
				(justify mirror)
			)
		)
		(property "exclude_from_bom" ""
			(at 0 0 0)
			(layer "B.Fab")
			(hide yes)
			(effects
				(font
					(size 1 1)
					(thickness 0.15)
				)
				(justify mirror)
			)
		)
		(sheetname "HDMI + Ethernet")
		(sheetfile "hdmi-ethernet.kicad_sch")
		(attr smd exclude_from_bom)
		(fp_rect
			(start -0.925 0.47)
			(end 0.925 -0.47)
			(stroke
				(width 0.05)
				(type default)
			)
			(fill no)
			(layer "B.CrtYd")
		)
		(fp_rect
			(start -0.5 0.25)
			(end 0.5 -0.25)
			(stroke
				(width 0.15)
				(type solid)
			)
			(fill no)
			(layer "B.Fab")
		)
		(pad "1" smd roundrect
			(at -0.48 0)
			(size 0.59 0.64)
			(layers "B.Cu" "B.Mask" "B.Paste")
			(roundrect_rratio 0.25)
			(net 847 "/HDMI + Ethernet/ETH_LED_LINK-")
			(pintype "passive")
		)
		(pad "2" smd roundrect
			(at 0.48 0)
			(size 0.59 0.64)
			(layers "B.Cu" "B.Mask" "B.Paste")
			(roundrect_rratio 0.25)
			(net 26 "+1V8")
			(pintype "passive")
		)
	)
	(footprint "antmicro-footprints:NetTie-2_SMD_Pad0.127mm"
		(layer "B.Cu")
		(at 253.701 148.4 -90)
		(descr "Net tie, 2 pin, 0.127mm  SMD pads")
		(tags "net tie")
		(property "Reference" "NT12"
			(at -0.128 1.345 90)
			(layer "B.SilkS")
			(hide yes)
			(effects
				(font
					(size 0.7 0.7)
					(thickness 0.15)
				)
				(justify left bottom mirror)
			)
		)
		(property "Value" "Net-Tie_2"
			(at 0 -1.199 90)
			(layer "B.Fab")
			(effects
				(font
					(size 0.7 0.7)
					(thickness 0.15)
				)
				(justify left bottom mirror)
			)
		)
		(property "Description" "Net tie, 2 pins"
			(at 0 0 270)
			(layer "F.Fab")
			(hide yes)
			(effects
				(font
					(size 1.27 1.27)
					(thickness 0.15)
				)
			)
		)
		(property "Author" "Antmicro"
			(at 105.301 402.101 0)
			(layer "B.Fab")
			(hide yes)
			(effects
				(font
					(size 1 1)
					(thickness 0.15)
				)
				(justify mirror)
			)
		)
		(property "License" "Apache-2.0"
			(at 105.301 402.101 0)
			(layer "B.Fab")
			(hide yes)
			(effects
				(font
					(size 1 1)
					(thickness 0.15)
				)
				(justify mirror)
			)
		)
		(property "MPN" ""
			(at 105.301 402.101 0)
			(layer "B.Fab")
			(hide yes)
			(effects
				(font
					(size 1 1)
					(thickness 0.15)
				)
				(justify mirror)
			)
		)
		(property "Manufacturer" ""
			(at 105.301 402.101 0)
			(layer "B.Fab")
			(hide yes)
			(effects
				(font
					(size 1 1)
					(thickness 0.15)
				)
				(justify mirror)
			)
		)
		(sheetname "FPGA Bank 14 & 15")
		(sheetfile "fpga-bank-14-15.kicad_sch")
		(attr exclude_from_pos_files)
		(net_tie_pad_groups "1, 2")
		(fp_poly
			(pts
				(xy -0.0635 0.0635) (xy 0.0625 0.0635) (xy 0.0625 -0.0635) (xy -0.0635 -0.0635)
			)
			(stroke
				(width 0)
				(type solid)
			)
			(fill yes)
			(layer "B.Cu")
		)
		(pad "1" smd roundrect
			(at -0.127 0 90)
			(size 0.127 0.127)
			(layers "B.Cu")
			(roundrect_rratio 0.5)
			(chamfer_ratio 0)
			(chamfer top_left bottom_left)
			(net 1297 "/USB_SPI.~{CS}")
			(pinfunction "1")
			(pintype "passive")
		)
		(pad "2" smd roundrect
			(at 0.126 0 270)
			(size 0.127 0.127)
			(layers "B.Cu")
			(roundrect_rratio 0.5)
			(chamfer_ratio 0)
			(chamfer top_left bottom_left)
			(net 1325 "/SUP_MCU.~{SCS}")
			(pinfunction "2")
			(pintype "passive")
		)
	)
	(footprint "antmicro-footprints:R_0402_1005Metric"
		(layer "B.Cu")
		(at 182.1 168.7125 -90)
		(descr "Resistor SMD 0402")
		(tags "resistor SMD 0402")
		(property "Reference" "R303"
			(at -3.6125 -0.375 90)
			(layer "B.SilkS")
			(effects
				(font
					(size 0.7 0.7)
					(thickness 0.15)
				)
				(justify left bottom mirror)
			)
		)
		(property "Value" "R_0R_0402"
			(at 0 -1.4 90)
			(layer "B.Fab")
			(effects
				(font
					(size 0.7 0.7)
					(thickness 0.15)
				)
				(justify left bottom mirror)
			)
		)
		(property "Description" "SMD Chip Resistor, Jumper, 0 ohm, 100 mW, 0402 [1005 Metric], Thick Film, General Purpose"
			(at 0 0 270)
			(layer "F.Fab")
			(hide yes)
			(effects
				(font
					(size 1.27 1.27)
					(thickness 0.15)
				)
			)
		)
		(property "Author" "Antmicro"
			(at 13.3875 350.8125 0)
			(layer "B.Fab")
			(hide yes)
			(effects
				(font
					(size 1 1)
					(thickness 0.15)
				)
				(justify mirror)
			)
		)
		(property "Current" "1A"
			(at 13.3875 350.8125 0)
			(layer "B.Fab")
			(hide yes)
			(effects
				(font
					(size 1 1)
					(thickness 0.15)
				)
				(justify mirror)
			)
		)
		(property "DNP" "DNP"
			(at 13.3875 350.8125 0)
			(layer "B.Fab")
			(hide yes)
			(effects
				(font
					(size 1 1)
					(thickness 0.15)
				)
				(justify mirror)
			)
		)
		(property "License" "Apache-2.0"
			(at 13.3875 350.8125 0)
			(layer "B.Fab")
			(hide yes)
			(effects
				(font
					(size 1 1)
					(thickness 0.15)
				)
				(justify mirror)
			)
		)
		(property "MPN" "ERJ2GE0R00X"
			(at 13.3875 350.8125 0)
			(layer "B.Fab")
			(hide yes)
			(effects
				(font
					(size 1 1)
					(thickness 0.15)
				)
				(justify mirror)
			)
		)
		(property "Manufacturer" "Panasonic"
			(at 13.3875 350.8125 0)
			(layer "B.Fab")
			(hide yes)
			(effects
				(font
					(size 1 1)
					(thickness 0.15)
				)
				(justify mirror)
			)
		)
		(property "Tolerance" ""
			(at 13.3875 350.8125 0)
			(layer "B.Fab")
			(hide yes)
			(effects
				(font
					(size 1 1)
					(thickness 0.15)
				)
				(justify mirror)
			)
		)
		(property "Val" "0R"
			(at 13.3875 350.8125 0)
			(layer "B.Fab")
			(hide yes)
			(effects
				(font
					(size 1 1)
					(thickness 0.15)
				)
				(justify mirror)
			)
		)
		(property "dnp" ""
			(at 13.3875 350.8125 0)
			(layer "B.Fab")
			(hide yes)
			(effects
				(font
					(size 1 1)
					(thickness 0.15)
				)
				(justify mirror)
			)
		)
		(property "exclude_from_bom" ""
			(at 13.3875 350.8125 0)
			(layer "B.Fab")
			(hide yes)
			(effects
				(font
					(size 1 1)
					(thickness 0.15)
				)
				(justify mirror)
			)
		)
		(sheetname "DC-DC Converters")
		(sheetfile "dc-dc.kicad_sch")
		(attr smd exclude_from_bom)
		(fp_rect
			(start -0.925 0.47)
			(end 0.925 -0.47)
			(stroke
				(width 0.05)
				(type default)
			)
			(fill no)
			(layer "B.CrtYd")
		)
		(fp_rect
			(start -0.5 0.25)
			(end 0.5 -0.25)
			(stroke
				(width 0.15)
				(type solid)
			)
			(fill no)
			(layer "B.Fab")
		)
		(pad "1" smd roundrect
			(at -0.48 0 270)
			(size 0.59 0.64)
			(layers "B.Cu" "B.Mask" "B.Paste")
			(roundrect_rratio 0.25)
			(net 1218 "/DC-DC Converters/SENSE_3V3_2_N")
			(pintype "passive")
		)
		(pad "2" smd roundrect
			(at 0.48 0 270)
			(size 0.59 0.64)
			(layers "B.Cu" "B.Mask" "B.Paste")
			(roundrect_rratio 0.25)
			(net 957 "/DC-DC Converters/FB6")
			(pintype "passive")
		)
	)
	(footprint "antmicro-footprints:R_Array_4x0201_Panasonic_EXB18V"
		(layer "B.Cu")
		(at 164.199999 144.999999)
		(property "Reference" "R13"
			(at -4.524999 6.250001 0)
			(layer "B.SilkS")
			(effects
				(font
					(size 0.7 0.7)
					(thickness 0.15)
				)
				(justify left bottom mirror)
			)
		)
		(property "Value" "4x39R_0201_array"
			(at -1.1 -1.8 0)
			(layer "B.Fab")
			(effects
				(font
					(size 0.7 0.7)
					(thickness 0.15)
				)
				(justify right bottom mirror)
			)
		)
		(property "Description" "Fixed Network Resistor, 39 ohm, Isolated, 4 Resistors, 0502 [1406 Metric], Flat, ± 5%"
			(at 0 0 0)
			(layer "F.Fab")
			(hide yes)
			(effects
				(font
					(size 1.27 1.27)
					(thickness 0.15)
				)
			)
		)
		(property "Author" "Antmicro"
			(at 0 0 0)
			(layer "B.Fab")
			(hide yes)
			(effects
				(font
					(size 1 1)
					(thickness 0.15)
				)
				(justify mirror)
			)
		)
		(property "License" "Apache-2.0"
			(at 0 0 0)
			(layer "B.Fab")
			(hide yes)
			(effects
				(font
					(size 1 1)
					(thickness 0.15)
				)
				(justify mirror)
			)
		)
		(property "MPN" "EXB-18V390JX"
			(at 0 0 0)
			(layer "B.Fab")
			(hide yes)
			(effects
				(font
					(size 1 1)
					(thickness 0.15)
				)
				(justify mirror)
			)
		)
		(property "Manufacturer" "Panasonic"
			(at 0 0 0)
			(layer "B.Fab")
			(hide yes)
			(effects
				(font
					(size 1 1)
					(thickness 0.15)
				)
				(justify mirror)
			)
		)
		(property "Val" "4x39R_0201"
			(at 0 0 0)
			(layer "B.Fab")
			(hide yes)
			(effects
				(font
					(size 1 1)
					(thickness 0.15)
				)
				(justify mirror)
			)
		)
		(sheetname "DRAM + SRAM")
		(sheetfile "ram.kicad_sch")
		(attr smd)
		(fp_line
			(start -0.8 0.45)
			(end -0.8 -0.45)
			(stroke
				(width 0.12)
				(type solid)
			)
			(layer "B.SilkS")
		)
		(fp_line
			(start 0.8 0.45)
			(end 0.8 -0.45)
			(stroke
				(width 0.12)
				(type solid)
			)
			(layer "B.SilkS")
		)
		(fp_rect
			(start -0.898 0.66)
			(end 0.898 -0.65)
			(stroke
				(width 0.05)
				(type solid)
			)
			(fill no)
			(layer "B.CrtYd")
		)
		(pad "1" smd roundrect
			(at -0.6 -0.298)
			(size 0.2 0.4)
			(layers "B.Cu" "B.Mask" "B.Paste")
			(roundrect_rratio 0.25)
			(net 544 "/DRAM + SRAM/DDR.A13")
			(pinfunction "R1.1")
			(pintype "passive")
		)
		(pad "2" smd roundrect
			(at -0.202 -0.298)
			(size 0.2 0.4)
			(layers "B.Cu" "B.Mask" "B.Paste")
			(roundrect_rratio 0.25)
			(net 538 "/DRAM + SRAM/DDR.A7")
			(pinfunction "R2.1")
			(pintype "passive")
		)
		(pad "3" smd roundrect
			(at 0.2 -0.298)
			(size 0.2 0.4)
			(layers "B.Cu" "B.Mask" "B.Paste")
			(roundrect_rratio 0.25)
			(net 540 "/DRAM + SRAM/DDR.A9")
			(pinfunction "R3.1")
			(pintype "passive")
		)
		(pad "4" smd roundrect
			(at 0.598 -0.298)
			(size 0.2 0.4)
			(layers "B.Cu" "B.Mask" "B.Paste")
			(roundrect_rratio 0.25)
			(net 536 "/DRAM + SRAM/DDR.A5")
			(pinfunction "R4.1")
			(pintype "passive")
		)
		(pad "5" smd roundrect
			(at 0.598 0.3)
			(size 0.2 0.4)
			(layers "B.Cu" "B.Mask" "B.Paste")
			(roundrect_rratio 0.25)
			(net 7 "+0V675_VTT")
			(pinfunction "R4.2")
			(pintype "passive")
		)
		(pad "6" smd roundrect
			(at 0.2 0.3)
			(size 0.2 0.4)
			(layers "B.Cu" "B.Mask" "B.Paste")
			(roundrect_rratio 0.25)
			(net 7 "+0V675_VTT")
			(pinfunction "R3.2")
			(pintype "passive")
		)
		(pad "7" smd roundrect
			(at -0.202 0.3)
			(size 0.2 0.4)
			(layers "B.Cu" "B.Mask" "B.Paste")
			(roundrect_rratio 0.25)
			(net 7 "+0V675_VTT")
			(pinfunction "R2.2")
			(pintype "passive")
		)
		(pad "8" smd roundrect
			(at -0.6 0.3)
			(size 0.2 0.4)
			(layers "B.Cu" "B.Mask" "B.Paste")
			(roundrect_rratio 0.25)
			(net 7 "+0V675_VTT")
			(pinfunction "R1.2")
			(pintype "passive")
		)
	)
	(footprint "antmicro-footprints:C_0603_1608Metric"
		(layer "B.Cu")
		(at 200 134 90)
		(descr "Capacitor SMD 0603")
		(tags "capacitor 0603")
		(property "Reference" "C385"
			(at 27.7 25.75 90)
			(layer "B.SilkS")
			(effects
				(font
					(size 0.7 0.7)
					(thickness 0.15)
				)
				(justify right bottom mirror)
			)
		)
		(property "Value" "C_47u_0603"
			(at 0 -1.6 90)
			(layer "B.Fab")
			(effects
				(font
					(size 0.7 0.7)
					(thickness 0.15)
				)
				(justify right bottom mirror)
			)
		)
		(property "Description" "SMD Multilayer Ceramic Capacitor, 47 µF, 6.3 V, 0603 [1608 Metric], ± 20%, X5R, GRM Series"
			(at 0 0 90)
			(layer "F.Fab")
			(hide yes)
			(effects
				(font
					(size 1.27 1.27)
					(thickness 0.15)
				)
			)
		)
		(property "Author" "Antmicro"
			(at 334 -66 0)
			(layer "B.Fab")
			(hide yes)
			(effects
				(font
					(size 1 1)
					(thickness 0.15)
				)
				(justify mirror)
			)
		)
		(property "Dielectric" ""
			(at 334 -66 0)
			(layer "B.Fab")
			(hide yes)
			(effects
				(font
					(size 1 1)
					(thickness 0.15)
				)
				(justify mirror)
			)
		)
		(property "License" "Apache-2.0"
			(at 334 -66 0)
			(layer "B.Fab")
			(hide yes)
			(effects
				(font
					(size 1 1)
					(thickness 0.15)
				)
				(justify mirror)
			)
		)
		(property "MPN" "GRM188R60J476ME15D"
			(at 334 -66 0)
			(layer "B.Fab")
			(hide yes)
			(effects
				(font
					(size 1 1)
					(thickness 0.15)
				)
				(justify mirror)
			)
		)
		(property "Manufacturer" "Murata"
			(at 334 -66 0)
			(layer "B.Fab")
			(hide yes)
			(effects
				(font
					(size 1 1)
					(thickness 0.15)
				)
				(justify mirror)
			)
		)
		(property "Val" "47u"
			(at 334 -66 0)
			(layer "B.Fab")
			(hide yes)
			(effects
				(font
					(size 1 1)
					(thickness 0.15)
				)
				(justify mirror)
			)
		)
		(property "Voltage" ""
			(at 334 -66 0)
			(layer "B.Fab")
			(hide yes)
			(effects
				(font
					(size 1 1)
					(thickness 0.15)
				)
				(justify mirror)
			)
		)
		(sheetname "FPGA supply")
		(sheetfile "fpga-supply.kicad_sch")
		(attr smd)
		(fp_line
			(start -0.15 -0.4)
			(end 0.15 -0.4)
			(stroke
				(width 0.15)
				(type solid)
			)
			(layer "B.SilkS")
		)
		(fp_line
			(start -0.15 0.4)
			(end 0.15 0.4)
			(stroke
				(width 0.15)
				(type solid)
			)
			(layer "B.SilkS")
		)
		(fp_rect
			(start -1.25 0.65)
			(end 1.25 -0.65)
			(stroke
				(width 0.05)
				(type solid)
			)
			(fill no)
			(layer "B.CrtYd")
		)
		(fp_rect
			(start -0.8 0.4)
			(end 0.8 -0.4)
			(stroke
				(width 0.15)
				(type solid)
			)
			(fill no)
			(layer "B.Fab")
		)
		(pad "1" smd roundrect
			(at -0.7 0 90)
			(size 0.8 1)
			(layers "B.Cu" "B.Mask" "B.Paste")
			(roundrect_rratio 0.2)
			(net 1 "GND")
			(pintype "passive")
		)
		(pad "2" smd roundrect
			(at 0.7 0 90)
			(size 0.8 1)
			(layers "B.Cu" "B.Mask" "B.Paste")
			(roundrect_rratio 0.2)
			(net 650 "+1V0")
			(pintype "passive")
		)
	)
	(footprint "antmicro-footprints:C_0402_1005Metric"
		(layer "B.Cu")
		(at 208 135.5 180)
		(descr "Capacitor SMD 0402")
		(tags "capacitor SMD 0402")
		(property "Reference" "C40"
			(at -1.1 0.425 0)
			(layer "B.SilkS")
			(effects
				(font
					(size 0.7 0.7)
					(thickness 0.15)
				)
				(justify left bottom mirror)
			)
		)
		(property "Value" "C_100n_0402"
			(at 0 -1.169 0)
			(layer "B.Fab")
			(effects
				(font
					(size 0.7 0.7)
					(thickness 0.15)
				)
				(justify left bottom mirror)
			)
		)
		(property "Description" "SMD Multilayer Ceramic Capacitor, 0.1 µF, 50 V, 0402 [1005 Metric], ± 10%, X5R, GRM Series"
			(at 0 0 180)
			(layer "F.Fab")
			(hide yes)
			(effects
				(font
					(size 1.27 1.27)
					(thickness 0.15)
				)
			)
		)
		(property "Author" "Antmicro"
			(at 416 271 0)
			(layer "B.Fab")
			(hide yes)
			(effects
				(font
					(size 1 1)
					(thickness 0.15)
				)
				(justify mirror)
			)
		)
		(property "Dielectric" "X5R"
			(at 416 271 0)
			(layer "B.Fab")
			(hide yes)
			(effects
				(font
					(size 1 1)
					(thickness 0.15)
				)
				(justify mirror)
			)
		)
		(property "License" "Apache-2.0"
			(at 416 271 0)
			(layer "B.Fab")
			(hide yes)
			(effects
				(font
					(size 1 1)
					(thickness 0.15)
				)
				(justify mirror)
			)
		)
		(property "MPN" "GRM155R61H104KE14D"
			(at 416 271 0)
			(layer "B.Fab")
			(hide yes)
			(effects
				(font
					(size 1 1)
					(thickness 0.15)
				)
				(justify mirror)
			)
		)
		(property "Manufacturer" "Murata"
			(at 416 271 0)
			(layer "B.Fab")
			(hide yes)
			(effects
				(font
					(size 1 1)
					(thickness 0.15)
				)
				(justify mirror)
			)
		)
		(property "Val" "100n"
			(at 416 271 0)
			(layer "B.Fab")
			(hide yes)
			(effects
				(font
					(size 1 1)
					(thickness 0.15)
				)
				(justify mirror)
			)
		)
		(property "Voltage" "50V"
			(at 416 271 0)
			(layer "B.Fab")
			(hide yes)
			(effects
				(font
					(size 1 1)
					(thickness 0.15)
				)
				(justify mirror)
			)
		)
		(sheetname "FPGA Bank 12 & 13")
		(sheetfile "fpga-bank-12-13.kicad_sch")
		(attr smd)
		(fp_rect
			(start -0.925 0.47)
			(end 0.925 -0.47)
			(stroke
				(width 0.05)
				(type default)
			)
			(fill no)
			(layer "B.CrtYd")
		)
		(fp_line
			(start 0.504 0.25)
			(end 0.504 -0.248)
			(stroke
				(width 0.15)
				(type solid)
			)
			(layer "B.Fab")
		)
		(fp_line
			(start 0.504 -0.248)
			(end -0.494 -0.248)
			(stroke
				(width 0.15)
				(type solid)
			)
			(layer "B.Fab")
		)
		(fp_line
			(start -0.494 0.25)
			(end 0.504 0.25)
			(stroke
				(width 0.15)
				(type solid)
			)
			(layer "B.Fab")
		)
		(fp_line
			(start -0.494 -0.248)
			(end -0.494 0.25)
			(stroke
				(width 0.15)
				(type solid)
			)
			(layer "B.Fab")
		)
		(pad "1" smd roundrect
			(at -0.48 0 180)
			(size 0.59 0.64)
			(layers "B.Cu" "B.Mask" "B.Paste")
			(roundrect_rratio 0.25)
			(net 1 "GND")
			(pintype "passive")
		)
		(pad "2" smd roundrect
			(at 0.48 0 180)
			(size 0.59 0.64)
			(layers "B.Cu" "B.Mask" "B.Paste")
			(roundrect_rratio 0.25)
			(net 24 "+3V3")
			(pintype "passive")
		)
	)
	(footprint "antmicro-footprints:R_0402_1005Metric"
		(layer "B.Cu")
		(at 242.351 143.05 -90)
		(descr "Resistor SMD 0402")
		(tags "resistor SMD 0402")
		(property "Reference" "R165"
			(at 0.85 -0.399 90)
			(layer "B.SilkS")
			(effects
				(font
					(size 0.7 0.7)
					(thickness 0.15)
				)
				(justify left bottom mirror)
			)
		)
		(property "Value" "R_0R_0402"
			(at 0 -1.4 90)
			(layer "B.Fab")
			(effects
				(font
					(size 0.7 0.7)
					(thickness 0.15)
				)
				(justify left bottom mirror)
			)
		)
		(property "Description" "SMD Chip Resistor, Jumper, 0 ohm, 100 mW, 0402 [1005 Metric], Thick Film, General Purpose"
			(at 0 0 270)
			(layer "F.Fab")
			(hide yes)
			(effects
				(font
					(size 1.27 1.27)
					(thickness 0.15)
				)
			)
		)
		(property "Author" "Antmicro"
			(at 99.301 385.401 0)
			(layer "B.Fab")
			(hide yes)
			(effects
				(font
					(size 1 1)
					(thickness 0.15)
				)
				(justify mirror)
			)
		)
		(property "Current" "1A"
			(at 99.301 385.401 0)
			(layer "B.Fab")
			(hide yes)
			(effects
				(font
					(size 1 1)
					(thickness 0.15)
				)
				(justify mirror)
			)
		)
		(property "License" "Apache-2.0"
			(at 99.301 385.401 0)
			(layer "B.Fab")
			(hide yes)
			(effects
				(font
					(size 1 1)
					(thickness 0.15)
				)
				(justify mirror)
			)
		)
		(property "MPN" "ERJ2GE0R00X"
			(at 99.301 385.401 0)
			(layer "B.Fab")
			(hide yes)
			(effects
				(font
					(size 1 1)
					(thickness 0.15)
				)
				(justify mirror)
			)
		)
		(property "Manufacturer" "Panasonic"
			(at 99.301 385.401 0)
			(layer "B.Fab")
			(hide yes)
			(effects
				(font
					(size 1 1)
					(thickness 0.15)
				)
				(justify mirror)
			)
		)
		(property "Tolerance" ""
			(at 99.301 385.401 0)
			(layer "B.Fab")
			(hide yes)
			(effects
				(font
					(size 1 1)
					(thickness 0.15)
				)
				(justify mirror)
			)
		)
		(property "Val" "0R"
			(at 99.301 385.401 0)
			(layer "B.Fab")
			(hide yes)
			(effects
				(font
					(size 1 1)
					(thickness 0.15)
				)
				(justify mirror)
			)
		)
		(sheetname "USB PHY")
		(sheetfile "usb-phy.kicad_sch")
		(attr smd)
		(fp_rect
			(start -0.925 0.47)
			(end 0.925 -0.47)
			(stroke
				(width 0.05)
				(type default)
			)
			(fill no)
			(layer "B.CrtYd")
		)
		(fp_rect
			(start -0.5 0.25)
			(end 0.5 -0.25)
			(stroke
				(width 0.15)
				(type solid)
			)
			(fill no)
			(layer "B.Fab")
		)
		(pad "1" smd roundrect
			(at -0.48 0 270)
			(size 0.59 0.64)
			(layers "B.Cu" "B.Mask" "B.Paste")
			(roundrect_rratio 0.25)
			(net 343 "Net-(Q17-G)")
			(pintype "passive")
		)
		(pad "2" smd roundrect
			(at 0.48 0 270)
			(size 0.59 0.64)
			(layers "B.Cu" "B.Mask" "B.Paste")
			(roundrect_rratio 0.25)
			(net 925 "/USB PHY/BDBUS3")
			(pintype "passive")
		)
	)
	(footprint "antmicro-footprints:R_0402_1005Metric"
		(layer "B.Cu")
		(at 261.5 91)
		(descr "Resistor SMD 0402")
		(tags "resistor SMD 0402")
		(property "Reference" "R110"
			(at 1.375 1.275 180)
			(layer "B.SilkS")
			(effects
				(font
					(size 0.7 0.7)
					(thickness 0.15)
				)
				(justify left bottom mirror)
			)
		)
		(property "Value" "R_1k_0402"
			(at 0 -1.4 180)
			(layer "B.Fab")
			(effects
				(font
					(size 0.7 0.7)
					(thickness 0.15)
				)
				(justify left bottom mirror)
			)
		)
		(property "Description" "SMD Chip Resistor, 1 kohm, ± 1%, 63 mW, 0402 [1005 Metric], Thick Film, General Purpose"
			(at 0 0 0)
			(layer "F.Fab")
			(hide yes)
			(effects
				(font
					(size 1.27 1.27)
					(thickness 0.15)
				)
			)
		)
		(property "Author" "Antmicro"
			(at 0 0 0)
			(layer "B.Fab")
			(hide yes)
			(effects
				(font
					(size 1 1)
					(thickness 0.15)
				)
				(justify mirror)
			)
		)
		(property "License" "Apache-2.0"
			(at 0 0 0)
			(layer "B.Fab")
			(hide yes)
			(effects
				(font
					(size 1 1)
					(thickness 0.15)
				)
				(justify mirror)
			)
		)
		(property "MPN" "CR0402-FX-1001GLF"
			(at 0 0 0)
			(layer "B.Fab")
			(hide yes)
			(effects
				(font
					(size 1 1)
					(thickness 0.15)
				)
				(justify mirror)
			)
		)
		(property "Manufacturer" "Bourns"
			(at 0 0 0)
			(layer "B.Fab")
			(hide yes)
			(effects
				(font
					(size 1 1)
					(thickness 0.15)
				)
				(justify mirror)
			)
		)
		(property "Tolerance" "1%"
			(at 0 0 0)
			(layer "B.Fab")
			(hide yes)
			(effects
				(font
					(size 1 1)
					(thickness 0.15)
				)
				(justify mirror)
			)
		)
		(property "Val" "1k"
			(at 0 0 0)
			(layer "B.Fab")
			(hide yes)
			(effects
				(font
					(size 1 1)
					(thickness 0.15)
				)
				(justify mirror)
			)
		)
		(sheetname "User GPIO + LED + button + DIP switch")
		(sheetfile "user-gpio.kicad_sch")
		(attr smd)
		(fp_rect
			(start -0.925 0.47)
			(end 0.925 -0.47)
			(stroke
				(width 0.05)
				(type default)
			)
			(fill no)
			(layer "B.CrtYd")
		)
		(fp_rect
			(start -0.5 0.25)
			(end 0.5 -0.25)
			(stroke
				(width 0.15)
				(type solid)
			)
			(fill no)
			(layer "B.Fab")
		)
		(pad "1" smd roundrect
			(at -0.48 0)
			(size 0.59 0.64)
			(layers "B.Cu" "B.Mask" "B.Paste")
			(roundrect_rratio 0.25)
			(net 24 "+3V3")
			(pintype "passive")
		)
		(pad "2" smd roundrect
			(at 0.48 0)
			(size 0.59 0.64)
			(layers "B.Cu" "B.Mask" "B.Paste")
			(roundrect_rratio 0.25)
			(net 781 "Net-(D21-A)")
			(pintype "passive")
		)
	)
	(footprint "antmicro-footprints:R_0402_1005Metric"
		(layer "B.Cu")
		(at 218.099999 77.899999 90)
		(descr "Resistor SMD 0402")
		(tags "resistor SMD 0402")
		(property "Reference" "R114"
			(at 3.599999 0.400001 270)
			(layer "B.SilkS")
			(effects
				(font
					(size 0.7 0.7)
					(thickness 0.15)
				)
				(justify left bottom mirror)
			)
		)
		(property "Value" "R_100R_0402"
			(at 0 -1.4 270)
			(layer "B.Fab")
			(effects
				(font
					(size 0.7 0.7)
					(thickness 0.15)
				)
				(justify left bottom mirror)
			)
		)
		(property "Description" "SMD Chip Resistor, 100 ohm, ± 1%, 62.5 mW, 0402 [1005 Metric], Thick Film, General Purpose"
			(at 0 0 90)
			(layer "F.Fab")
			(hide yes)
			(effects
				(font
					(size 1.27 1.27)
					(thickness 0.15)
				)
			)
		)
		(property "Author" "Antmicro"
			(at 295.999998 -140.2 0)
			(layer "B.Fab")
			(hide yes)
			(effects
				(font
					(size 1 1)
					(thickness 0.15)
				)
				(justify mirror)
			)
		)
		(property "License" "Apache-2.0"
			(at 295.999998 -140.2 0)
			(layer "B.Fab")
			(hide yes)
			(effects
				(font
					(size 1 1)
					(thickness 0.15)
				)
				(justify mirror)
			)
		)
		(property "MPN" "CR0402-FX-1000GLF"
			(at 295.999998 -140.2 0)
			(layer "B.Fab")
			(hide yes)
			(effects
				(font
					(size 1 1)
					(thickness 0.15)
				)
				(justify mirror)
			)
		)
		(property "Manufacturer" "Bourns"
			(at 295.999998 -140.2 0)
			(layer "B.Fab")
			(hide yes)
			(effects
				(font
					(size 1 1)
					(thickness 0.15)
				)
				(justify mirror)
			)
		)
		(property "Tolerance" "1%"
			(at 295.999998 -140.2 0)
			(layer "B.Fab")
			(hide yes)
			(effects
				(font
					(size 1 1)
					(thickness 0.15)
				)
				(justify mirror)
			)
		)
		(property "Val" "100R"
			(at 295.999998 -140.2 0)
			(layer "B.Fab")
			(hide yes)
			(effects
				(font
					(size 1 1)
					(thickness 0.15)
				)
				(justify mirror)
			)
		)
		(sheetname "User GPIO + LED + button + DIP switch")
		(sheetfile "user-gpio.kicad_sch")
		(attr smd)
		(fp_rect
			(start -0.925 0.47)
			(end 0.925 -0.47)
			(stroke
				(width 0.05)
				(type default)
			)
			(fill no)
			(layer "B.CrtYd")
		)
		(fp_rect
			(start -0.5 0.25)
			(end 0.5 -0.25)
			(stroke
				(width 0.15)
				(type solid)
			)
			(fill no)
			(layer "B.Fab")
		)
		(pad "1" smd roundrect
			(at -0.48 0 90)
			(size 0.59 0.64)
			(layers "B.Cu" "B.Mask" "B.Paste")
			(roundrect_rratio 0.25)
			(net 804 "/User GPIO + LED + button + DIP switch/PMOD_A_9")
			(pintype "passive")
		)
		(pad "2" smd roundrect
			(at 0.48 0 90)
			(size 0.59 0.64)
			(layers "B.Cu" "B.Mask" "B.Paste")
			(roundrect_rratio 0.25)
			(net 438 "/FPGA Bank 12 & 13/PMOD_A.IO9")
			(pintype "passive")
		)
	)
	(footprint "antmicro-footprints:C_0402_1005Metric"
		(layer "B.Cu")
		(at 251.351 135.5 -90)
		(descr "Capacitor SMD 0402")
		(tags "capacitor SMD 0402")
		(property "Reference" "C211"
			(at 0.35 0.326 180)
			(layer "B.SilkS")
			(effects
				(font
					(size 0.7 0.7)
					(thickness 0.15)
				)
				(justify left bottom mirror)
			)
		)
		(property "Value" "C_1u_0402"
			(at 0 -1.4 90)
			(layer "B.Fab")
			(effects
				(font
					(size 0.7 0.7)
					(thickness 0.15)
				)
				(justify left bottom mirror)
			)
		)
		(property "Description" "SMD Multilayer Ceramic Capacitor, 1 µF, 10 V, 0402 [1005 Metric], ± 10%, X6S, C"
			(at 0 0 270)
			(layer "F.Fab")
			(hide yes)
			(effects
				(font
					(size 1.27 1.27)
					(thickness 0.15)
				)
			)
		)
		(property "Author" "Antmicro"
			(at 115.851 386.851 0)
			(layer "B.Fab")
			(hide yes)
			(effects
				(font
					(size 1 1)
					(thickness 0.15)
				)
				(justify mirror)
			)
		)
		(property "Dielectric" ""
			(at 115.851 386.851 0)
			(layer "B.Fab")
			(hide yes)
			(effects
				(font
					(size 1 1)
					(thickness 0.15)
				)
				(justify mirror)
			)
		)
		(property "License" "Apache-2.0"
			(at 115.851 386.851 0)
			(layer "B.Fab")
			(hide yes)
			(effects
				(font
					(size 1 1)
					(thickness 0.15)
				)
				(justify mirror)
			)
		)
		(property "MPN" "C1005X6S1A105K050BC"
			(at 115.851 386.851 0)
			(layer "B.Fab")
			(hide yes)
			(effects
				(font
					(size 1 1)
					(thickness 0.15)
				)
				(justify mirror)
			)
		)
		(property "Manufacturer" "TDK"
			(at 115.851 386.851 0)
			(layer "B.Fab")
			(hide yes)
			(effects
				(font
					(size 1 1)
					(thickness 0.15)
				)
				(justify mirror)
			)
		)
		(property "Val" "1u"
			(at 115.851 386.851 0)
			(layer "B.Fab")
			(hide yes)
			(effects
				(font
					(size 1 1)
					(thickness 0.15)
				)
				(justify mirror)
			)
		)
		(property "Voltage" ""
			(at 115.851 386.851 0)
			(layer "B.Fab")
			(hide yes)
			(effects
				(font
					(size 1 1)
					(thickness 0.15)
				)
				(justify mirror)
			)
		)
		(sheetname "SPI Flash + SD Card")
		(sheetfile "spi-flash.kicad_sch")
		(attr smd)
		(fp_rect
			(start -0.925 0.47)
			(end 0.925 -0.47)
			(stroke
				(width 0.05)
				(type default)
			)
			(fill no)
			(layer "B.CrtYd")
		)
		(fp_line
			(start -0.494 0.25)
			(end 0.504 0.25)
			(stroke
				(width 0.15)
				(type solid)
			)
			(layer "B.Fab")
		)
		(fp_line
			(start 0.504 0.25)
			(end 0.504 -0.248)
			(stroke
				(width 0.15)
				(type solid)
			)
			(layer "B.Fab")
		)
		(fp_line
			(start -0.494 -0.248)
			(end -0.494 0.25)
			(stroke
				(width 0.15)
				(type solid)
			)
			(layer "B.Fab")
		)
		(fp_line
			(start 0.504 -0.248)
			(end -0.494 -0.248)
			(stroke
				(width 0.15)
				(type solid)
			)
			(layer "B.Fab")
		)
		(pad "1" smd roundrect
			(at -0.48 0 270)
			(size 0.59 0.64)
			(layers "B.Cu" "B.Mask" "B.Paste")
			(roundrect_rratio 0.25)
			(net 1 "GND")
			(pintype "passive")
		)
		(pad "2" smd roundrect
			(at 0.48 0 270)
			(size 0.59 0.64)
			(layers "B.Cu" "B.Mask" "B.Paste")
			(roundrect_rratio 0.25)
			(net 24 "+3V3")
			(pintype "passive")
		)
	)
	(footprint "antmicro-footprints:R_0402_1005Metric"
		(layer "B.Cu")
		(at 163.1625 175.3 -90)
		(descr "Resistor SMD 0402")
		(tags "resistor SMD 0402")
		(property "Reference" "R317"
			(at 0.7 -0.4125 90)
			(layer "B.SilkS")
			(effects
				(font
					(size 0.7 0.7)
					(thickness 0.15)
				)
				(justify left bottom mirror)
			)
		)
		(property "Value" "R_0R_0402"
			(at 0 -1.4 90)
			(layer "B.Fab")
			(effects
				(font
					(size 0.7 0.7)
					(thickness 0.15)
				)
				(justify left bottom mirror)
			)
		)
		(property "Description" "SMD Chip Resistor, Jumper, 0 ohm, 100 mW, 0402 [1005 Metric], Thick Film, General Purpose"
			(at 0 0 270)
			(layer "F.Fab")
			(hide yes)
			(effects
				(font
					(size 1.27 1.27)
					(thickness 0.15)
				)
			)
		)
		(property "Author" "Antmicro"
			(at -12.1375 338.4625 0)
			(layer "B.Fab")
			(hide yes)
			(effects
				(font
					(size 1 1)
					(thickness 0.15)
				)
				(justify mirror)
			)
		)
		(property "Current" "1A"
			(at -12.1375 338.4625 0)
			(layer "B.Fab")
			(hide yes)
			(effects
				(font
					(size 1 1)
					(thickness 0.15)
				)
				(justify mirror)
			)
		)
		(property "DNP" "DNP"
			(at -12.1375 338.4625 0)
			(layer "B.Fab")
			(hide yes)
			(effects
				(font
					(size 1 1)
					(thickness 0.15)
				)
				(justify mirror)
			)
		)
		(property "License" "Apache-2.0"
			(at -12.1375 338.4625 0)
			(layer "B.Fab")
			(hide yes)
			(effects
				(font
					(size 1 1)
					(thickness 0.15)
				)
				(justify mirror)
			)
		)
		(property "MPN" "ERJ2GE0R00X"
			(at -12.1375 338.4625 0)
			(layer "B.Fab")
			(hide yes)
			(effects
				(font
					(size 1 1)
					(thickness 0.15)
				)
				(justify mirror)
			)
		)
		(property "Manufacturer" "Panasonic"
			(at -12.1375 338.4625 0)
			(layer "B.Fab")
			(hide yes)
			(effects
				(font
					(size 1 1)
					(thickness 0.15)
				)
				(justify mirror)
			)
		)
		(property "Tolerance" ""
			(at -12.1375 338.4625 0)
			(layer "B.Fab")
			(hide yes)
			(effects
				(font
					(size 1 1)
					(thickness 0.15)
				)
				(justify mirror)
			)
		)
		(property "Val" "0R"
			(at -12.1375 338.4625 0)
			(layer "B.Fab")
			(hide yes)
			(effects
				(font
					(size 1 1)
					(thickness 0.15)
				)
				(justify mirror)
			)
		)
		(property "dnp" ""
			(at -12.1375 338.4625 0)
			(layer "B.Fab")
			(hide yes)
			(effects
				(font
					(size 1 1)
					(thickness 0.15)
				)
				(justify mirror)
			)
		)
		(property "exclude_from_bom" ""
			(at -12.1375 338.4625 0)
			(layer "B.Fab")
			(hide yes)
			(effects
				(font
					(size 1 1)
					(thickness 0.15)
				)
				(justify mirror)
			)
		)
		(sheetname "DC-DC Converters")
		(sheetfile "dc-dc.kicad_sch")
		(attr smd exclude_from_bom)
		(fp_rect
			(start -0.925 0.47)
			(end 0.925 -0.47)
			(stroke
				(width 0.05)
				(type default)
			)
			(fill no)
			(layer "B.CrtYd")
		)
		(fp_rect
			(start -0.5 0.25)
			(end 0.5 -0.25)
			(stroke
				(width 0.15)
				(type solid)
			)
			(fill no)
			(layer "B.Fab")
		)
		(pad "1" smd roundrect
			(at -0.48 0 270)
			(size 0.59 0.64)
			(layers "B.Cu" "B.Mask" "B.Paste")
			(roundrect_rratio 0.25)
			(net 962 "/DC-DC Converters/FB3")
			(pintype "passive")
		)
		(pad "2" smd roundrect
			(at 0.48 0 270)
			(size 0.59 0.64)
			(layers "B.Cu" "B.Mask" "B.Paste")
			(roundrect_rratio 0.25)
			(net 1226 "/DC-DC Converters/SENSE_1V2_P")
			(pintype "passive")
		)
	)
	(footprint "antmicro-footprints:SC70-3"
		(layer "B.Cu")
		(at 256.901 172.44762 -90)
		(property "Reference" "Q18"
			(at 1.72738 -2.649 180)
			(layer "B.SilkS")
			(effects
				(font
					(size 0.7 0.7)
					(thickness 0.15)
				)
				(justify left bottom mirror)
			)
		)
		(property "Value" "BSS138PW"
			(at 0 -2.3 90)
			(layer "B.Fab")
			(effects
				(font
					(size 0.7 0.7)
					(thickness 0.15)
				)
				(justify left bottom mirror)
			)
		)
		(property "Description" "Power MOSFET, N Channel, 60 V, 320 mA, 0.9 ohm, SOT-323, Surface Mount"
			(at 0 0 270)
			(layer "F.Fab")
			(hide yes)
			(effects
				(font
					(size 1.27 1.27)
					(thickness 0.15)
				)
			)
		)
		(property "Author" "Antmicro"
			(at 84.45338 429.34862 0)
			(layer "B.Fab")
			(hide yes)
			(effects
				(font
					(size 1 1)
					(thickness 0.15)
				)
				(justify mirror)
			)
		)
		(property "License" "Apache-2.0"
			(at 84.45338 429.34862 0)
			(layer "B.Fab")
			(hide yes)
			(effects
				(font
					(size 1 1)
					(thickness 0.15)
				)
				(justify mirror)
			)
		)
		(property "MPN" "BSS138PW"
			(at 84.45338 429.34862 0)
			(layer "B.Fab")
			(hide yes)
			(effects
				(font
					(size 1 1)
					(thickness 0.15)
				)
				(justify mirror)
			)
		)
		(property "Manufacturer" "Nexperia"
			(at 84.45338 429.34862 0)
			(layer "B.Fab")
			(hide yes)
			(effects
				(font
					(size 1 1)
					(thickness 0.15)
				)
				(justify mirror)
			)
		)
		(sheetname "Power supply")
		(sheetfile "power-supply.kicad_sch")
		(attr smd)
		(fp_line
			(start -0.3 1)
			(end 0.627 0.999)
			(stroke
				(width 0.15)
				(type solid)
			)
			(layer "B.SilkS")
		)
		(fp_line
			(start 0.627 0.6)
			(end 0.627 0.999)
			(stroke
				(width 0.15)
				(type solid)
			)
			(layer "B.SilkS")
		)
		(fp_line
			(start 0.627 -0.6)
			(end 0.627 -1.001)
			(stroke
				(width 0.15)
				(type solid)
			)
			(layer "B.SilkS")
		)
		(fp_line
			(start -0.3 -1)
			(end 0.627 -1.001)
			(stroke
				(width 0.15)
				(type solid)
			)
			(layer "B.SilkS")
		)
		(fp_line
			(start -0.9 1.3)
			(end 0.9 1.3)
			(stroke
				(width 0.05)
				(type solid)
			)
			(layer "B.CrtYd")
		)
		(fp_line
			(start -0.9 1.3)
			(end -0.9 1)
			(stroke
				(width 0.05)
				(type solid)
			)
			(layer "B.CrtYd")
		)
		(fp_line
			(start 0.9 1.3)
			(end 0.9 0.4)
			(stroke
				(width 0.05)
				(type solid)
			)
			(layer "B.CrtYd")
		)
		(fp_line
			(start -0.9 1)
			(end -1.4 1)
			(stroke
				(width 0.05)
				(type solid)
			)
			(layer "B.CrtYd")
		)
		(fp_line
			(start 0.9 0.4)
			(end 1.4 0.4)
			(stroke
				(width 0.05)
				(type solid)
			)
			(layer "B.CrtYd")
		)
		(fp_line
			(start 1.4 0.4)
			(end 1.4 -0.4)
			(stroke
				(width 0.05)
				(type solid)
			)
			(layer "B.CrtYd")
		)
		(fp_line
			(start 0.9 -0.4)
			(end 0.9 -1.3)
			(stroke
				(width 0.05)
				(type solid)
			)
			(layer "B.CrtYd")
		)
		(fp_line
			(start 1.4 -0.4)
			(end 0.9 -0.4)
			(stroke
				(width 0.05)
				(type solid)
			)
			(layer "B.CrtYd")
		)
		(fp_line
			(start -1.4 -1)
			(end -1.4 1)
			(stroke
				(width 0.05)
				(type solid)
			)
			(layer "B.CrtYd")
		)
		(fp_line
			(start -0.9 -1)
			(end -1.4 -1)
			(stroke
				(width 0.05)
				(type solid)
			)
			(layer "B.CrtYd")
		)
		(fp_line
			(start -0.9 -1.3)
			(end -0.9 -1)
			(stroke
				(width 0.05)
				(type solid)
			)
			(layer "B.CrtYd")
		)
		(fp_line
			(start 0.9 -1.3)
			(end -0.9 -1.3)
			(stroke
				(width 0.05)
				(type solid)
			)
			(layer "B.CrtYd")
		)
		(fp_rect
			(start -0.623 0.999)
			(end 0.627 -1.001)
			(stroke
				(width 0.15)
				(type solid)
			)
			(fill no)
			(layer "B.Fab")
		)
		(pad "1" smd rect
			(at -1.051 0.65 180)
			(size 0.6 0.6)
			(layers "B.Cu" "B.Mask" "B.Paste")
			(net 889 "/Power supply/PG")
			(pinfunction "G")
			(pintype "passive")
		)
		(pad "2" smd rect
			(at -1.051 -0.65 180)
			(size 0.6 0.6)
			(layers "B.Cu" "B.Mask" "B.Paste")
			(net 699 "GNDD")
			(pinfunction "S")
			(pintype "passive")
		)
		(pad "3" smd rect
			(at 1.05 0 180)
			(size 0.6 0.6)
			(layers "B.Cu" "B.Mask" "B.Paste")
			(net 344 "Net-(Q18-D)")
			(pinfunction "D")
			(pintype "passive")
		)
	)
	(footprint "antmicro-footprints:C_0402_1005Metric"
		(layer "B.Cu")
		(at 157.65 146.5 -90)
		(descr "Capacitor SMD 0402")
		(tags "capacitor SMD 0402")
		(property "Reference" "C170"
			(at -1.025 3.475 90)
			(layer "B.SilkS")
			(effects
				(font
					(size 0.7 0.7)
					(thickness 0.15)
				)
				(justify left bottom mirror)
			)
		)
		(property "Value" "C_100n_0402"
			(at 0 -1.169 90)
			(layer "B.Fab")
			(effects
				(font
					(size 0.7 0.7)
					(thickness 0.15)
				)
				(justify left bottom mirror)
			)
		)
		(property "Description" "SMD Multilayer Ceramic Capacitor, 0.1 µF, 50 V, 0402 [1005 Metric], ± 10%, X5R, GRM Series"
			(at 0 0 270)
			(layer "F.Fab")
			(hide yes)
			(effects
				(font
					(size 1.27 1.27)
					(thickness 0.15)
				)
			)
		)
		(property "Author" "Antmicro"
			(at 11.15 304.15 0)
			(layer "B.Fab")
			(hide yes)
			(effects
				(font
					(size 1 1)
					(thickness 0.15)
				)
				(justify mirror)
			)
		)
		(property "Dielectric" "X5R"
			(at 11.15 304.15 0)
			(layer "B.Fab")
			(hide yes)
			(effects
				(font
					(size 1 1)
					(thickness 0.15)
				)
				(justify mirror)
			)
		)
		(property "License" "Apache-2.0"
			(at 11.15 304.15 0)
			(layer "B.Fab")
			(hide yes)
			(effects
				(font
					(size 1 1)
					(thickness 0.15)
				)
				(justify mirror)
			)
		)
		(property "MPN" "GRM155R61H104KE14D"
			(at 11.15 304.15 0)
			(layer "B.Fab")
			(hide yes)
			(effects
				(font
					(size 1 1)
					(thickness 0.15)
				)
				(justify mirror)
			)
		)
		(property "Manufacturer" "Murata"
			(at 11.15 304.15 0)
			(layer "B.Fab")
			(hide yes)
			(effects
				(font
					(size 1 1)
					(thickness 0.15)
				)
				(justify mirror)
			)
		)
		(property "Val" "100n"
			(at 11.15 304.15 0)
			(layer "B.Fab")
			(hide yes)
			(effects
				(font
					(size 1 1)
					(thickness 0.15)
				)
				(justify mirror)
			)
		)
		(property "Voltage" "50V"
			(at 11.15 304.15 0)
			(layer "B.Fab")
			(hide yes)
			(effects
				(font
					(size 1 1)
					(thickness 0.15)
				)
				(justify mirror)
			)
		)
		(sheetname "DRAM + SRAM")
		(sheetfile "ram.kicad_sch")
		(attr smd)
		(fp_rect
			(start -0.925 0.47)
			(end 0.925 -0.47)
			(stroke
				(width 0.05)
				(type default)
			)
			(fill no)
			(layer "B.CrtYd")
		)
		(fp_line
			(start -0.494 0.25)
			(end 0.504 0.25)
			(stroke
				(width 0.15)
				(type solid)
			)
			(layer "B.Fab")
		)
		(fp_line
			(start 0.504 0.25)
			(end 0.504 -0.248)
			(stroke
				(width 0.15)
				(type solid)
			)
			(layer "B.Fab")
		)
		(fp_line
			(start -0.494 -0.248)
			(end -0.494 0.25)
			(stroke
				(width 0.15)
				(type solid)
			)
			(layer "B.Fab")
		)
		(fp_line
			(start 0.504 -0.248)
			(end -0.494 -0.248)
			(stroke
				(width 0.15)
				(type solid)
			)
			(layer "B.Fab")
		)
		(pad "1" smd roundrect
			(at -0.48 0 270)
			(size 0.59 0.64)
			(layers "B.Cu" "B.Mask" "B.Paste")
			(roundrect_rratio 0.25)
			(net 7 "+0V675_VTT")
			(pintype "passive")
		)
		(pad "2" smd roundrect
			(at 0.48 0 270)
			(size 0.59 0.64)
			(layers "B.Cu" "B.Mask" "B.Paste")
			(roundrect_rratio 0.25)
			(net 25 "+1V35")
			(pintype "passive")
		)
	)
	(footprint "antmicro-footprints:C_0201"
		(layer "B.Cu")
		(at 188.000001 116.500001 180)
		(descr "Capacitor SMD 0201")
		(tags "capacitor SMD 0201")
		(property "Reference" "C142"
			(at 2.350001 0.425001 0)
			(layer "B.SilkS")
			(effects
				(font
					(size 0.7 0.7)
					(thickness 0.15)
				)
				(justify left bottom mirror)
			)
		)
		(property "Value" "C_100n_0201"
			(at 0 -1.4 0)
			(layer "B.Fab")
			(effects
				(font
					(size 0.7 0.7)
					(thickness 0.15)
				)
				(justify left bottom mirror)
			)
		)
		(property "Description" "SMD Multilayer Ceramic Capacitor, 0.1 µF, 6.3 V, 0201 [0603 Metric], ± 10%, X6S, CC Series"
			(at 0 0 180)
			(layer "F.Fab")
			(hide yes)
			(effects
				(font
					(size 1.27 1.27)
					(thickness 0.15)
				)
			)
		)
		(property "Author" "Antmicro"
			(at 376.000002 233.000002 0)
			(layer "B.Fab")
			(hide yes)
			(effects
				(font
					(size 1 1)
					(thickness 0.15)
				)
				(justify mirror)
			)
		)
		(property "Dielectric" ""
			(at 376.000002 233.000002 0)
			(layer "B.Fab")
			(hide yes)
			(effects
				(font
					(size 1 1)
					(thickness 0.15)
				)
				(justify mirror)
			)
		)
		(property "License" "Apache-2.0"
			(at 376.000002 233.000002 0)
			(layer "B.Fab")
			(hide yes)
			(effects
				(font
					(size 1 1)
					(thickness 0.15)
				)
				(justify mirror)
			)
		)
		(property "MPN" "CC0201KRX6S5BB104"
			(at 376.000002 233.000002 0)
			(layer "B.Fab")
			(hide yes)
			(effects
				(font
					(size 1 1)
					(thickness 0.15)
				)
				(justify mirror)
			)
		)
		(property "Manufacturer" "YAGEO"
			(at 376.000002 233.000002 0)
			(layer "B.Fab")
			(hide yes)
			(effects
				(font
					(size 1 1)
					(thickness 0.15)
				)
				(justify mirror)
			)
		)
		(property "Val" "100n"
			(at 376.000002 233.000002 0)
			(layer "B.Fab")
			(hide yes)
			(effects
				(font
					(size 1 1)
					(thickness 0.15)
				)
				(justify mirror)
			)
		)
		(property "Voltage" ""
			(at 376.000002 233.000002 0)
			(layer "B.Fab")
			(hide yes)
			(effects
				(font
					(size 1 1)
					(thickness 0.15)
				)
				(justify mirror)
			)
		)
		(sheetname "FPGA supply")
		(sheetfile "fpga-supply.kicad_sch")
		(attr smd)
		(fp_rect
			(start -0.7 0.35)
			(end 0.7 -0.35)
			(stroke
				(width 0.05)
				(type default)
			)
			(fill no)
			(layer "B.CrtYd")
		)
		(fp_rect
			(start 0.3 -0.15)
			(end -0.301 0.149)
			(stroke
				(width 0.15)
				(type solid)
			)
			(fill no)
			(layer "B.Fab")
		)
		(pad "" smd roundrect
			(at -0.349 0.002 180)
			(size 0.318 0.36)
			(layers "B.Paste")
			(roundrect_rratio 0.25)
		)
		(pad "" smd roundrect
			(at 0.341 0.002 180)
			(size 0.318 0.36)
			(layers "B.Paste")
			(roundrect_rratio 0.25)
		)
		(pad "1" smd roundrect
			(at -0.321 0.002 180)
			(size 0.46 0.4)
			(layers "B.Cu" "B.Mask")
			(roundrect_rratio 0.25)
			(net 1 "GND")
			(pintype "passive")
		)
		(pad "2" smd roundrect
			(at 0.32 0.002 180)
			(size 0.46 0.4)
			(layers "B.Cu" "B.Mask")
			(roundrect_rratio 0.25)
			(net 8 "+1V2_MGTAVTT")
			(pintype "passive")
		)
	)
	(footprint "antmicro-footprints:C_0402_1005Metric"
		(layer "B.Cu")
		(at 191.75 130.3)
		(descr "Capacitor SMD 0402")
		(tags "capacitor SMD 0402")
		(property "Reference" "C118"
			(at 22.925 -28.05 180)
			(layer "B.SilkS")
			(effects
				(font
					(size 0.7 0.7)
					(thickness 0.15)
				)
				(justify left bottom mirror)
			)
		)
		(property "Value" "C_100n_0402"
			(at 0 -1.169 180)
			(layer "B.Fab")
			(effects
				(font
					(size 0.7 0.7)
					(thickness 0.15)
				)
				(justify left bottom mirror)
			)
		)
		(property "Description" "SMD Multilayer Ceramic Capacitor, 0.1 µF, 50 V, 0402 [1005 Metric], ± 10%, X5R, GRM Series"
			(at 0 0 0)
			(layer "F.Fab")
			(hide yes)
			(effects
				(font
					(size 1.27 1.27)
					(thickness 0.15)
				)
			)
		)
		(property "Author" "Antmicro"
			(at 0 0 0)
			(layer "B.Fab")
			(hide yes)
			(effects
				(font
					(size 1 1)
					(thickness 0.15)
				)
				(justify mirror)
			)
		)
		(property "Dielectric" "X5R"
			(at 0 0 0)
			(layer "B.Fab")
			(hide yes)
			(effects
				(font
					(size 1 1)
					(thickness 0.15)
				)
				(justify mirror)
			)
		)
		(property "License" "Apache-2.0"
			(at 0 0 0)
			(layer "B.Fab")
			(hide yes)
			(effects
				(font
					(size 1 1)
					(thickness 0.15)
				)
				(justify mirror)
			)
		)
		(property "MPN" "GRM155R61H104KE14D"
			(at 0 0 0)
			(layer "B.Fab")
			(hide yes)
			(effects
				(font
					(size 1 1)
					(thickness 0.15)
				)
				(justify mirror)
			)
		)
		(property "Manufacturer" "Murata"
			(at 0 0 0)
			(layer "B.Fab")
			(hide yes)
			(effects
				(font
					(size 1 1)
					(thickness 0.15)
				)
				(justify mirror)
			)
		)
		(property "Val" "100n"
			(at 0 0 0)
			(layer "B.Fab")
			(hide yes)
			(effects
				(font
					(size 1 1)
					(thickness 0.15)
				)
				(justify mirror)
			)
		)
		(property "Voltage" "50V"
			(at 0 0 0)
			(layer "B.Fab")
			(hide yes)
			(effects
				(font
					(size 1 1)
					(thickness 0.15)
				)
				(justify mirror)
			)
		)
		(sheetname "FPGA supply")
		(sheetfile "fpga-supply.kicad_sch")
		(attr smd)
		(fp_rect
			(start -0.925 0.47)
			(end 0.925 -0.47)
			(stroke
				(width 0.05)
				(type default)
			)
			(fill no)
			(layer "B.CrtYd")
		)
		(fp_line
			(start -0.494 -0.248)
			(end -0.494 0.25)
			(stroke
				(width 0.15)
				(type solid)
			)
			(layer "B.Fab")
		)
		(fp_line
			(start -0.494 0.25)
			(end 0.504 0.25)
			(stroke
				(width 0.15)
				(type solid)
			)
			(layer "B.Fab")
		)
		(fp_line
			(start 0.504 -0.248)
			(end -0.494 -0.248)
			(stroke
				(width 0.15)
				(type solid)
			)
			(layer "B.Fab")
		)
		(fp_line
			(start 0.504 0.25)
			(end 0.504 -0.248)
			(stroke
				(width 0.15)
				(type solid)
			)
			(layer "B.Fab")
		)
		(pad "1" smd roundrect
			(at -0.48 0)
			(size 0.59 0.64)
			(layers "B.Cu" "B.Mask" "B.Paste")
			(roundrect_rratio 0.25)
			(net 26 "+1V8")
			(pintype "passive")
		)
		(pad "2" smd roundrect
			(at 0.48 0)
			(size 0.59 0.64)
			(layers "B.Cu" "B.Mask" "B.Paste")
			(roundrect_rratio 0.25)
			(net 1 "GND")
			(pintype "passive")
		)
	)
	(footprint "antmicro-footprints:R_0402_1005Metric"
		(layer "B.Cu")
		(at 189.36 79.8 90)
		(descr "Resistor SMD 0402")
		(tags "resistor SMD 0402")
		(property "Reference" "R144"
			(at -0.725 0.4 270)
			(layer "B.SilkS")
			(effects
				(font
					(size 0.7 0.7)
					(thickness 0.15)
				)
				(justify left bottom mirror)
			)
		)
		(property "Value" "R_100R_0402"
			(at 0 -1.4 270)
			(layer "B.Fab")
			(effects
				(font
					(size 0.7 0.7)
					(thickness 0.15)
				)
				(justify left bottom mirror)
			)
		)
		(property "Description" "SMD Chip Resistor, 100 ohm, ± 1%, 62.5 mW, 0402 [1005 Metric], Thick Film, General Purpose"
			(at 0 0 90)
			(layer "F.Fab")
			(hide yes)
			(effects
				(font
					(size 1.27 1.27)
					(thickness 0.15)
				)
			)
		)
		(property "Author" "Antmicro"
			(at 269.16 -109.56 0)
			(layer "B.Fab")
			(hide yes)
			(effects
				(font
					(size 1 1)
					(thickness 0.15)
				)
				(justify mirror)
			)
		)
		(property "License" "Apache-2.0"
			(at 269.16 -109.56 0)
			(layer "B.Fab")
			(hide yes)
			(effects
				(font
					(size 1 1)
					(thickness 0.15)
				)
				(justify mirror)
			)
		)
		(property "MPN" "CR0402-FX-1000GLF"
			(at 269.16 -109.56 0)
			(layer "B.Fab")
			(hide yes)
			(effects
				(font
					(size 1 1)
					(thickness 0.15)
				)
				(justify mirror)
			)
		)
		(property "Manufacturer" "Bourns"
			(at 269.16 -109.56 0)
			(layer "B.Fab")
			(hide yes)
			(effects
				(font
					(size 1 1)
					(thickness 0.15)
				)
				(justify mirror)
			)
		)
		(property "Tolerance" "1%"
			(at 269.16 -109.56 0)
			(layer "B.Fab")
			(hide yes)
			(effects
				(font
					(size 1 1)
					(thickness 0.15)
				)
				(justify mirror)
			)
		)
		(property "Val" "100R"
			(at 269.16 -109.56 0)
			(layer "B.Fab")
			(hide yes)
			(effects
				(font
					(size 1 1)
					(thickness 0.15)
				)
				(justify mirror)
			)
		)
		(sheetname "User GPIO + LED + button + DIP switch")
		(sheetfile "user-gpio.kicad_sch")
		(attr smd)
		(fp_rect
			(start -0.925 0.47)
			(end 0.925 -0.47)
			(stroke
				(width 0.05)
				(type default)
			)
			(fill no)
			(layer "B.CrtYd")
		)
		(fp_rect
			(start -0.5 0.25)
			(end 0.5 -0.25)
			(stroke
				(width 0.15)
				(type solid)
			)
			(fill no)
			(layer "B.Fab")
		)
		(pad "1" smd roundrect
			(at -0.48 0 90)
			(size 0.59 0.64)
			(layers "B.Cu" "B.Mask" "B.Paste")
			(roundrect_rratio 0.25)
			(net 489 "/FPGA Bank 12 & 13/CW_HEADER.IO1")
			(pintype "passive")
		)
		(pad "2" smd roundrect
			(at 0.48 0 90)
			(size 0.59 0.64)
			(layers "B.Cu" "B.Mask" "B.Paste")
			(roundrect_rratio 0.25)
			(net 827 "/User GPIO + LED + button + DIP switch/CW_20PIN_IO1")
			(pintype "passive")
		)
	)
	(footprint "antmicro-footprints:C_0201"
		(layer "B.Cu")
		(at 201.5 128.05)
		(descr "Capacitor SMD 0201")
		(tags "capacitor SMD 0201")
		(property "Reference" "C132"
			(at 24.375 -29.15 0)
			(layer "B.SilkS")
			(effects
				(font
					(size 0.7 0.7)
					(thickness 0.15)
				)
				(justify right bottom mirror)
			)
		)
		(property "Value" "C_100n_0201"
			(at 0 -1.4 0)
			(layer "B.Fab")
			(effects
				(font
					(size 0.7 0.7)
					(thickness 0.15)
				)
				(justify right bottom mirror)
			)
		)
		(property "Description" "SMD Multilayer Ceramic Capacitor, 0.1 µF, 6.3 V, 0201 [0603 Metric], ± 10%, X6S, CC Series"
			(at 0 0 0)
			(layer "F.Fab")
			(hide yes)
			(effects
				(font
					(size 1.27 1.27)
					(thickness 0.15)
				)
			)
		)
		(property "Author" "Antmicro"
			(at 0 0 0)
			(layer "B.Fab")
			(hide yes)
			(effects
				(font
					(size 1 1)
					(thickness 0.15)
				)
				(justify mirror)
			)
		)
		(property "Dielectric" ""
			(at 0 0 0)
			(layer "B.Fab")
			(hide yes)
			(effects
				(font
					(size 1 1)
					(thickness 0.15)
				)
				(justify mirror)
			)
		)
		(property "License" "Apache-2.0"
			(at 0 0 0)
			(layer "B.Fab")
			(hide yes)
			(effects
				(font
					(size 1 1)
					(thickness 0.15)
				)
				(justify mirror)
			)
		)
		(property "MPN" "CC0201KRX6S5BB104"
			(at 0 0 0)
			(layer "B.Fab")
			(hide yes)
			(effects
				(font
					(size 1 1)
					(thickness 0.15)
				)
				(justify mirror)
			)
		)
		(property "Manufacturer" "YAGEO"
			(at 0 0 0)
			(layer "B.Fab")
			(hide yes)
			(effects
				(font
					(size 1 1)
					(thickness 0.15)
				)
				(justify mirror)
			)
		)
		(property "Val" "100n"
			(at 0 0 0)
			(layer "B.Fab")
			(hide yes)
			(effects
				(font
					(size 1 1)
					(thickness 0.15)
				)
				(justify mirror)
			)
		)
		(property "Voltage" ""
			(at 0 0 0)
			(layer "B.Fab")
			(hide yes)
			(effects
				(font
					(size 1 1)
					(thickness 0.15)
				)
				(justify mirror)
			)
		)
		(sheetname "FPGA supply")
		(sheetfile "fpga-supply.kicad_sch")
		(attr smd)
		(fp_rect
			(start -0.7 0.35)
			(end 0.7 -0.35)
			(stroke
				(width 0.05)
				(type default)
			)
			(fill no)
			(layer "B.CrtYd")
		)
		(fp_rect
			(start 0.3 -0.15)
			(end -0.301 0.149)
			(stroke
				(width 0.15)
				(type solid)
			)
			(fill no)
			(layer "B.Fab")
		)
		(pad "" smd roundrect
			(at -0.349 0.002)
			(size 0.318 0.36)
			(layers "B.Paste")
			(roundrect_rratio 0.25)
		)
		(pad "" smd roundrect
			(at 0.341 0.002)
			(size 0.318 0.36)
			(layers "B.Paste")
			(roundrect_rratio 0.25)
		)
		(pad "1" smd roundrect
			(at -0.321 0.002)
			(size 0.46 0.4)
			(layers "B.Cu" "B.Mask")
			(roundrect_rratio 0.25)
			(net 1 "GND")
			(pintype "passive")
		)
		(pad "2" smd roundrect
			(at 0.32 0.002)
			(size 0.46 0.4)
			(layers "B.Cu" "B.Mask")
			(roundrect_rratio 0.25)
			(net 650 "+1V0")
			(pintype "passive")
		)
	)
	(footprint "antmicro-footprints:R_0402_1005Metric"
		(layer "B.Cu")
		(at 153.065 140.95 180)
		(descr "Resistor SMD 0402")
		(tags "resistor SMD 0402")
		(property "Reference" "R325"
			(at -1.31 0.525 0)
			(layer "B.SilkS")
			(effects
				(font
					(size 0.7 0.7)
					(thickness 0.15)
				)
				(justify left bottom mirror)
			)
		)
		(property "Value" "R_4k7_0402"
			(at 0 -1.4 0)
			(layer "B.Fab")
			(effects
				(font
					(size 0.7 0.7)
					(thickness 0.15)
				)
				(justify left bottom mirror)
			)
		)
		(property "Description" "SMD Chip Resistor, 4.7 kohm, ± 1%, 62.5 mW, 0402 [1005 Metric], Thick Film, General Purpose"
			(at 0 0 180)
			(layer "F.Fab")
			(hide yes)
			(effects
				(font
					(size 1.27 1.27)
					(thickness 0.15)
				)
			)
		)
		(property "Author" "Antmicro"
			(at 306.13 281.9 0)
			(layer "B.Fab")
			(hide yes)
			(effects
				(font
					(size 1 1)
					(thickness 0.15)
				)
				(justify mirror)
			)
		)
		(property "License" "Apache-2.0"
			(at 306.13 281.9 0)
			(layer "B.Fab")
			(hide yes)
			(effects
				(font
					(size 1 1)
					(thickness 0.15)
				)
				(justify mirror)
			)
		)
		(property "MPN" "CR0402-FX-4701GLF"
			(at 306.13 281.9 0)
			(layer "B.Fab")
			(hide yes)
			(effects
				(font
					(size 1 1)
					(thickness 0.15)
				)
				(justify mirror)
			)
		)
		(property "Manufacturer" "Bourns"
			(at 306.13 281.9 0)
			(layer "B.Fab")
			(hide yes)
			(effects
				(font
					(size 1 1)
					(thickness 0.15)
				)
				(justify mirror)
			)
		)
		(property "Tolerance" "1%"
			(at 306.13 281.9 0)
			(layer "B.Fab")
			(hide yes)
			(effects
				(font
					(size 1 1)
					(thickness 0.15)
				)
				(justify mirror)
			)
		)
		(property "Val" "4k7"
			(at 306.13 281.9 0)
			(layer "B.Fab")
			(hide yes)
			(effects
				(font
					(size 1 1)
					(thickness 0.15)
				)
				(justify mirror)
			)
		)
		(sheetname "DC-DC Converters")
		(sheetfile "dc-dc.kicad_sch")
		(attr smd)
		(fp_rect
			(start -0.925 0.47)
			(end 0.925 -0.47)
			(stroke
				(width 0.05)
				(type default)
			)
			(fill no)
			(layer "B.CrtYd")
		)
		(fp_rect
			(start -0.5 0.25)
			(end 0.5 -0.25)
			(stroke
				(width 0.15)
				(type solid)
			)
			(fill no)
			(layer "B.Fab")
		)
		(pad "1" smd roundrect
			(at -0.48 0 180)
			(size 0.59 0.64)
			(layers "B.Cu" "B.Mask" "B.Paste")
			(roundrect_rratio 0.25)
			(net 1 "GND")
			(pintype "passive")
		)
		(pad "2" smd roundrect
			(at 0.48 0 180)
			(size 0.59 0.64)
			(layers "B.Cu" "B.Mask" "B.Paste")
			(roundrect_rratio 0.25)
			(net 969 "/DC-DC Converters/MGTAVTT_ILIM")
			(pintype "passive")
		)
	)
	(footprint "antmicro-footprints:NetTie-2_SMD_Pad0.127mm"
		(layer "B.Cu")
		(at 208.860001 147.257 -90)
		(descr "Net tie, 2 pin, 0.127mm  SMD pads")
		(tags "net tie")
		(property "Reference" "NT30"
			(at -0.128 1.345 90)
			(layer "B.SilkS")
			(hide yes)
			(effects
				(font
					(size 0.7 0.7)
					(thickness 0.15)
				)
				(justify left bottom mirror)
			)
		)
		(property "Value" "Net-Tie_2"
			(at 0 -1.199 90)
			(layer "B.Fab")
			(effects
				(font
					(size 0.7 0.7)
					(thickness 0.15)
				)
				(justify left bottom mirror)
			)
		)
		(property "Description" "Net tie, 2 pins"
			(at 0 0 270)
			(layer "F.Fab")
			(hide yes)
			(effects
				(font
					(size 1.27 1.27)
					(thickness 0.15)
				)
			)
		)
		(property "Author" "Antmicro"
			(at 61.603001 356.117001 0)
			(layer "B.Fab")
			(hide yes)
			(effects
				(font
					(size 1 1)
					(thickness 0.15)
				)
				(justify mirror)
			)
		)
		(property "License" "Apache-2.0"
			(at 61.603001 356.117001 0)
			(layer "B.Fab")
			(hide yes)
			(effects
				(font
					(size 1 1)
					(thickness 0.15)
				)
				(justify mirror)
			)
		)
		(property "MPN" ""
			(at 61.603001 356.117001 0)
			(layer "B.Fab")
			(hide yes)
			(effects
				(font
					(size 1 1)
					(thickness 0.15)
				)
				(justify mirror)
			)
		)
		(property "Manufacturer" ""
			(at 61.603001 356.117001 0)
			(layer "B.Fab")
			(hide yes)
			(effects
				(font
					(size 1 1)
					(thickness 0.15)
				)
				(justify mirror)
			)
		)
		(sheetname "DC-DC Converters")
		(sheetfile "dc-dc.kicad_sch")
		(attr exclude_from_pos_files)
		(net_tie_pad_groups "1, 2")
		(fp_poly
			(pts
				(xy -0.0635 0.0635) (xy 0.0625 0.0635) (xy 0.0625 -0.0635) (xy -0.0635 -0.0635)
			)
			(stroke
				(width 0)
				(type solid)
			)
			(fill yes)
			(layer "B.Cu")
		)
		(pad "1" smd roundrect
			(at -0.127 0 90)
			(size 0.127 0.127)
			(layers "B.Cu")
			(roundrect_rratio 0.5)
			(chamfer_ratio 0)
			(chamfer top_left bottom_left)
			(net 1 "GND")
			(pinfunction "1")
			(pintype "passive")
		)
		(pad "2" smd roundrect
			(at 0.126 0 270)
			(size 0.127 0.127)
			(layers "B.Cu")
			(roundrect_rratio 0.5)
			(chamfer_ratio 0)
			(chamfer top_left bottom_left)
			(net 1218 "/DC-DC Converters/SENSE_3V3_2_N")
			(pinfunction "2")
			(pintype "passive")
		)
	)
	(footprint "antmicro-footprints:R_0402_1005Metric"
		(layer "B.Cu")
		(at 202.2 90.8 90)
		(descr "Resistor SMD 0402")
		(tags "resistor SMD 0402")
		(property "Reference" "R205"
			(at 1.95 2.4 270)
			(layer "B.SilkS")
			(effects
				(font
					(size 0.7 0.7)
					(thickness 0.15)
				)
				(justify left bottom mirror)
			)
		)
		(property "Value" "R_10k_0402"
			(at 0 -1.4 270)
			(layer "B.Fab")
			(effects
				(font
					(size 0.7 0.7)
					(thickness 0.15)
				)
				(justify left bottom mirror)
			)
		)
		(property "Description" "SMD Chip Resistor, 10 kohm, ± 1%, 62.5 mW, 0402 [1005 Metric], Thick Film, General Purpose"
			(at 0 0 90)
			(layer "F.Fab")
			(hide yes)
			(effects
				(font
					(size 1.27 1.27)
					(thickness 0.15)
				)
			)
		)
		(property "Author" "Antmicro"
			(at 293 -111.4 0)
			(layer "B.Fab")
			(hide yes)
			(effects
				(font
					(size 1 1)
					(thickness 0.15)
				)
				(justify mirror)
			)
		)
		(property "License" "Apache-2.0"
			(at 293 -111.4 0)
			(layer "B.Fab")
			(hide yes)
			(effects
				(font
					(size 1 1)
					(thickness 0.15)
				)
				(justify mirror)
			)
		)
		(property "MPN" "CR0402-FX-1002GLF"
			(at 293 -111.4 0)
			(layer "B.Fab")
			(hide yes)
			(effects
				(font
					(size 1 1)
					(thickness 0.15)
				)
				(justify mirror)
			)
		)
		(property "Manufacturer" "Bourns"
			(at 293 -111.4 0)
			(layer "B.Fab")
			(hide yes)
			(effects
				(font
					(size 1 1)
					(thickness 0.15)
				)
				(justify mirror)
			)
		)
		(property "Tolerance" "1%"
			(at 293 -111.4 0)
			(layer "B.Fab")
			(hide yes)
			(effects
				(font
					(size 1 1)
					(thickness 0.15)
				)
				(justify mirror)
			)
		)
		(property "Val" "10k"
			(at 293 -111.4 0)
			(layer "B.Fab")
			(hide yes)
			(effects
				(font
					(size 1 1)
					(thickness 0.15)
				)
				(justify mirror)
			)
		)
		(sheetname "HDMI + Ethernet")
		(sheetfile "hdmi-ethernet.kicad_sch")
		(attr smd)
		(fp_rect
			(start -0.925 0.47)
			(end 0.925 -0.47)
			(stroke
				(width 0.05)
				(type default)
			)
			(fill no)
			(layer "B.CrtYd")
		)
		(fp_rect
			(start -0.5 0.25)
			(end 0.5 -0.25)
			(stroke
				(width 0.15)
				(type solid)
			)
			(fill no)
			(layer "B.Fab")
		)
		(pad "1" smd roundrect
			(at -0.48 0 90)
			(size 0.59 0.64)
			(layers "B.Cu" "B.Mask" "B.Paste")
			(roundrect_rratio 0.25)
			(net 851 "/HDMI + Ethernet/GBE_LED_LINK-")
			(pintype "passive")
		)
		(pad "2" smd roundrect
			(at 0.48 0 90)
			(size 0.59 0.64)
			(layers "B.Cu" "B.Mask" "B.Paste")
			(roundrect_rratio 0.25)
			(net 24 "+3V3")
			(pintype "passive")
		)
	)
	(footprint "antmicro-footprints:SOD-523"
		(layer "B.Cu")
		(at 249.401 114.2 180)
		(property "Reference" "D31"
			(at 1.076 -0.375 0)
			(layer "B.SilkS")
			(effects
				(font
					(size 0.7 0.7)
					(thickness 0.15)
				)
				(justify left bottom mirror)
			)
		)
		(property "Value" "BAT54-02V-G3-08"
			(at 0 -1.499 0)
			(layer "B.Fab")
			(effects
				(font
					(size 0.7 0.7)
					(thickness 0.15)
				)
				(justify left bottom mirror)
			)
		)
		(property "Description" "Small Signal Schottky Diode, Single, 30 V, 200 mA, 800 mV, 600 mA, 125 °C"
			(at 0 0 180)
			(layer "F.Fab")
			(hide yes)
			(effects
				(font
					(size 1.27 1.27)
					(thickness 0.15)
				)
			)
		)
		(property "Author" "Antmicro"
			(at 498.802 228.4 0)
			(layer "B.Fab")
			(hide yes)
			(effects
				(font
					(size 1 1)
					(thickness 0.15)
				)
				(justify mirror)
			)
		)
		(property "License" "Apache-2.0"
			(at 498.802 228.4 0)
			(layer "B.Fab")
			(hide yes)
			(effects
				(font
					(size 1 1)
					(thickness 0.15)
				)
				(justify mirror)
			)
		)
		(property "MPN" "BAT54-02V-G3-08"
			(at 498.802 228.4 0)
			(layer "B.Fab")
			(hide yes)
			(effects
				(font
					(size 1 1)
					(thickness 0.15)
				)
				(justify mirror)
			)
		)
		(property "Manufacturer" "Vishay"
			(at 498.802 228.4 0)
			(layer "B.Fab")
			(hide yes)
			(effects
				(font
					(size 1 1)
					(thickness 0.15)
				)
				(justify mirror)
			)
		)
		(property "Public" "False"
			(at 498.802 228.4 0)
			(layer "B.Fab")
			(hide yes)
			(effects
				(font
					(size 1 1)
					(thickness 0.15)
				)
				(justify mirror)
			)
		)
		(sheetname "HDMI + Ethernet")
		(sheetfile "hdmi-ethernet.kicad_sch")
		(attr smd)
		(fp_line
			(start -0.35 0.5)
			(end -0.35 -0.5)
			(stroke
				(width 0.15)
				(type solid)
			)
			(layer "B.SilkS")
		)
		(fp_rect
			(start -1 0.6)
			(end 1 -0.6)
			(stroke
				(width 0.05)
				(type solid)
			)
			(fill no)
			(layer "B.CrtYd")
		)
		(fp_line
			(start 0.65 0.425)
			(end 0.65 -0.423)
			(stroke
				(width 0.15)
				(type solid)
			)
			(layer "B.Fab")
		)
		(fp_line
			(start -0.35 0.4)
			(end -0.35 -0.4)
			(stroke
				(width 0.15)
				(type solid)
			)
			(layer "B.Fab")
		)
		(fp_line
			(start -0.652 0.425)
			(end 0.65 0.425)
			(stroke
				(width 0.15)
				(type solid)
			)
			(layer "B.Fab")
		)
		(fp_line
			(start -0.652 -0.423)
			(end 0.65 -0.423)
			(stroke
				(width 0.15)
				(type solid)
			)
			(layer "B.Fab")
		)
		(fp_line
			(start -0.652 -0.423)
			(end -0.652 0.425)
			(stroke
				(width 0.15)
				(type solid)
			)
			(layer "B.Fab")
		)
		(pad "1" smd roundrect
			(at -0.701 0 180)
			(size 0.5 0.6)
			(layers "B.Cu" "B.Mask" "B.Paste")
			(roundrect_rratio 0.25)
			(net 794 "/HDMI + Ethernet/HDMI_CONN_5V")
			(pinfunction "C")
			(pintype "passive")
		)
		(pad "2" smd roundrect
			(at 0.699 0 180)
			(size 0.5 0.6)
			(layers "B.Cu" "B.Mask" "B.Paste")
			(roundrect_rratio 0.25)
			(net 795 "/HDMI + Ethernet/HDMI_5V")
			(pinfunction "A")
			(pintype "passive")
		)
	)
	(footprint "antmicro-footprints:C_0402_1005Metric"
		(layer "B.Cu")
		(at 158.6 146.5 -90)
		(descr "Capacitor SMD 0402")
		(tags "capacitor SMD 0402")
		(property "Reference" "C172"
			(at -1.025 3.475 90)
			(layer "B.SilkS")
			(effects
				(font
					(size 0.7 0.7)
					(thickness 0.15)
				)
				(justify left bottom mirror)
			)
		)
		(property "Value" "C_100n_0402"
			(at 0 -1.169 90)
			(layer "B.Fab")
			(effects
				(font
					(size 0.7 0.7)
					(thickness 0.15)
				)
				(justify left bottom mirror)
			)
		)
		(property "Description" "SMD Multilayer Ceramic Capacitor, 0.1 µF, 50 V, 0402 [1005 Metric], ± 10%, X5R, GRM Series"
			(at 0 0 270)
			(layer "F.Fab")
			(hide yes)
			(effects
				(font
					(size 1.27 1.27)
					(thickness 0.15)
				)
			)
		)
		(property "Author" "Antmicro"
			(at 12.1 305.1 0)
			(layer "B.Fab")
			(hide yes)
			(effects
				(font
					(size 1 1)
					(thickness 0.15)
				)
				(justify mirror)
			)
		)
		(property "Dielectric" "X5R"
			(at 12.1 305.1 0)
			(layer "B.Fab")
			(hide yes)
			(effects
				(font
					(size 1 1)
					(thickness 0.15)
				)
				(justify mirror)
			)
		)
		(property "License" "Apache-2.0"
			(at 12.1 305.1 0)
			(layer "B.Fab")
			(hide yes)
			(effects
				(font
					(size 1 1)
					(thickness 0.15)
				)
				(justify mirror)
			)
		)
		(property "MPN" "GRM155R61H104KE14D"
			(at 12.1 305.1 0)
			(layer "B.Fab")
			(hide yes)
			(effects
				(font
					(size 1 1)
					(thickness 0.15)
				)
				(justify mirror)
			)
		)
		(property "Manufacturer" "Murata"
			(at 12.1 305.1 0)
			(layer "B.Fab")
			(hide yes)
			(effects
				(font
					(size 1 1)
					(thickness 0.15)
				)
				(justify mirror)
			)
		)
		(property "Val" "100n"
			(at 12.1 305.1 0)
			(layer "B.Fab")
			(hide yes)
			(effects
				(font
					(size 1 1)
					(thickness 0.15)
				)
				(justify mirror)
			)
		)
		(property "Voltage" "50V"
			(at 12.1 305.1 0)
			(layer "B.Fab")
			(hide yes)
			(effects
				(font
					(size 1 1)
					(thickness 0.15)
				)
				(justify mirror)
			)
		)
		(sheetname "DRAM + SRAM")
		(sheetfile "ram.kicad_sch")
		(attr smd)
		(fp_rect
			(start -0.925 0.47)
			(end 0.925 -0.47)
			(stroke
				(width 0.05)
				(type default)
			)
			(fill no)
			(layer "B.CrtYd")
		)
		(fp_line
			(start -0.494 0.25)
			(end 0.504 0.25)
			(stroke
				(width 0.15)
				(type solid)
			)
			(layer "B.Fab")
		)
		(fp_line
			(start 0.504 0.25)
			(end 0.504 -0.248)
			(stroke
				(width 0.15)
				(type solid)
			)
			(layer "B.Fab")
		)
		(fp_line
			(start -0.494 -0.248)
			(end -0.494 0.25)
			(stroke
				(width 0.15)
				(type solid)
			)
			(layer "B.Fab")
		)
		(fp_line
			(start 0.504 -0.248)
			(end -0.494 -0.248)
			(stroke
				(width 0.15)
				(type solid)
			)
			(layer "B.Fab")
		)
		(pad "1" smd roundrect
			(at -0.48 0 270)
			(size 0.59 0.64)
			(layers "B.Cu" "B.Mask" "B.Paste")
			(roundrect_rratio 0.25)
			(net 7 "+0V675_VTT")
			(pintype "passive")
		)
		(pad "2" smd roundrect
			(at 0.48 0 270)
			(size 0.59 0.64)
			(layers "B.Cu" "B.Mask" "B.Paste")
			(roundrect_rratio 0.25)
			(net 25 "+1V35")
			(pintype "passive")
		)
	)
	(footprint "antmicro-footprints:R_0402_1005Metric"
		(layer "B.Cu")
		(at 201.891252 99.25 90)
		(descr "Resistor SMD 0402")
		(tags "resistor SMD 0402")
		(property "Reference" "R239"
			(at -3.8 0.358748 270)
			(layer "B.SilkS")
			(effects
				(font
					(size 0.7 0.7)
					(thickness 0.15)
				)
				(justify left bottom mirror)
			)
		)
		(property "Value" "R_10k_0402"
			(at 0 -1.4 270)
			(layer "B.Fab")
			(effects
				(font
					(size 0.7 0.7)
					(thickness 0.15)
				)
				(justify left bottom mirror)
			)
		)
		(property "Description" "SMD Chip Resistor, 10 kohm, ± 1%, 62.5 mW, 0402 [1005 Metric], Thick Film, General Purpose"
			(at 0 0 90)
			(layer "F.Fab")
			(hide yes)
			(effects
				(font
					(size 1.27 1.27)
					(thickness 0.15)
				)
			)
		)
		(property "Author" "Antmicro"
			(at 301.141252 -102.641252 0)
			(layer "B.Fab")
			(hide yes)
			(effects
				(font
					(size 1 1)
					(thickness 0.15)
				)
				(justify mirror)
			)
		)
		(property "License" "Apache-2.0"
			(at 301.141252 -102.641252 0)
			(layer "B.Fab")
			(hide yes)
			(effects
				(font
					(size 1 1)
					(thickness 0.15)
				)
				(justify mirror)
			)
		)
		(property "MPN" "CR0402-FX-1002GLF"
			(at 301.141252 -102.641252 0)
			(layer "B.Fab")
			(hide yes)
			(effects
				(font
					(size 1 1)
					(thickness 0.15)
				)
				(justify mirror)
			)
		)
		(property "Manufacturer" "Bourns"
			(at 301.141252 -102.641252 0)
			(layer "B.Fab")
			(hide yes)
			(effects
				(font
					(size 1 1)
					(thickness 0.15)
				)
				(justify mirror)
			)
		)
		(property "Tolerance" "1%"
			(at 301.141252 -102.641252 0)
			(layer "B.Fab")
			(hide yes)
			(effects
				(font
					(size 1 1)
					(thickness 0.15)
				)
				(justify mirror)
			)
		)
		(property "Val" "10k"
			(at 301.141252 -102.641252 0)
			(layer "B.Fab")
			(hide yes)
			(effects
				(font
					(size 1 1)
					(thickness 0.15)
				)
				(justify mirror)
			)
		)
		(sheetname "HDMI + Ethernet")
		(sheetfile "hdmi-ethernet.kicad_sch")
		(attr smd)
		(fp_rect
			(start -0.925 0.47)
			(end 0.925 -0.47)
			(stroke
				(width 0.05)
				(type default)
			)
			(fill no)
			(layer "B.CrtYd")
		)
		(fp_rect
			(start -0.5 0.25)
			(end 0.5 -0.25)
			(stroke
				(width 0.15)
				(type solid)
			)
			(fill no)
			(layer "B.Fab")
		)
		(pad "1" smd roundrect
			(at -0.48 0 90)
			(size 0.59 0.64)
			(layers "B.Cu" "B.Mask" "B.Paste")
			(roundrect_rratio 0.25)
			(net 24 "+3V3")
			(pintype "passive")
		)
		(pad "2" smd roundrect
			(at 0.48 0 90)
			(size 0.59 0.64)
			(layers "B.Cu" "B.Mask" "B.Paste")
			(roundrect_rratio 0.25)
			(net 522 "/FPGA Bank 16 & 17/GBE_RGMII.~{RESET}")
			(pintype "passive")
		)
	)
	(footprint "antmicro-footprints:R_0402_1005Metric"
		(layer "B.Cu")
		(at 242.351 141.05 90)
		(descr "Resistor SMD 0402")
		(tags "resistor SMD 0402")
		(property "Reference" "R166"
			(at 1.425 1.324 270)
			(layer "B.SilkS")
			(effects
				(font
					(size 0.7 0.7)
					(thickness 0.15)
				)
				(justify left bottom mirror)
			)
		)
		(property "Value" "R_47k_0402"
			(at 0 -1.4 270)
			(layer "B.Fab")
			(effects
				(font
					(size 0.7 0.7)
					(thickness 0.15)
				)
				(justify left bottom mirror)
			)
		)
		(property "Description" "SMD Chip Resistor, 47 kohm, ± 1%, 62.5 mW, 0402 [1005 Metric], Thick Film, General Purpose"
			(at 0 0 90)
			(layer "F.Fab")
			(hide yes)
			(effects
				(font
					(size 1.27 1.27)
					(thickness 0.15)
				)
			)
		)
		(property "Author" "Antmicro"
			(at 383.401 -101.301 0)
			(layer "B.Fab")
			(hide yes)
			(effects
				(font
					(size 1 1)
					(thickness 0.15)
				)
				(justify mirror)
			)
		)
		(property "License" "Apache-2.0"
			(at 383.401 -101.301 0)
			(layer "B.Fab")
			(hide yes)
			(effects
				(font
					(size 1 1)
					(thickness 0.15)
				)
				(justify mirror)
			)
		)
		(property "MPN" "CR0402-FX-4702GLF"
			(at 383.401 -101.301 0)
			(layer "B.Fab")
			(hide yes)
			(effects
				(font
					(size 1 1)
					(thickness 0.15)
				)
				(justify mirror)
			)
		)
		(property "Manufacturer" "Bourns"
			(at 383.401 -101.301 0)
			(layer "B.Fab")
			(hide yes)
			(effects
				(font
					(size 1 1)
					(thickness 0.15)
				)
				(justify mirror)
			)
		)
		(property "Tolerance" "1%"
			(at 383.401 -101.301 0)
			(layer "B.Fab")
			(hide yes)
			(effects
				(font
					(size 1 1)
					(thickness 0.15)
				)
				(justify mirror)
			)
		)
		(property "Val" "47k"
			(at 383.401 -101.301 0)
			(layer "B.Fab")
			(hide yes)
			(effects
				(font
					(size 1 1)
					(thickness 0.15)
				)
				(justify mirror)
			)
		)
		(sheetname "USB PHY")
		(sheetfile "usb-phy.kicad_sch")
		(attr smd)
		(fp_rect
			(start -0.925 0.47)
			(end 0.925 -0.47)
			(stroke
				(width 0.05)
				(type default)
			)
			(fill no)
			(layer "B.CrtYd")
		)
		(fp_rect
			(start -0.5 0.25)
			(end 0.5 -0.25)
			(stroke
				(width 0.15)
				(type solid)
			)
			(fill no)
			(layer "B.Fab")
		)
		(pad "1" smd roundrect
			(at -0.48 0 90)
			(size 0.59 0.64)
			(layers "B.Cu" "B.Mask" "B.Paste")
			(roundrect_rratio 0.25)
			(net 878 "/USB PHY/~{BDBUS3}")
			(pintype "passive")
		)
		(pad "2" smd roundrect
			(at 0.48 0 90)
			(size 0.59 0.64)
			(layers "B.Cu" "B.Mask" "B.Paste")
			(roundrect_rratio 0.25)
			(net 707 "/USB PHY/FTDI_3V3")
			(pintype "passive")
		)
	)
	(footprint "antmicro-footprints:C_0402_1005Metric"
		(layer "B.Cu")
		(at 205.49 133 90)
		(descr "Capacitor SMD 0402")
		(tags "capacitor SMD 0402")
		(property "Reference" "C37"
			(at 29.525 28.7 270)
			(layer "B.SilkS")
			(effects
				(font
					(size 0.7 0.7)
					(thickness 0.15)
				)
				(justify left bottom mirror)
			)
		)
		(property "Value" "C_100n_0402"
			(at 0 -1.169 270)
			(layer "B.Fab")
			(effects
				(font
					(size 0.7 0.7)
					(thickness 0.15)
				)
				(justify left bottom mirror)
			)
		)
		(property "Description" "SMD Multilayer Ceramic Capacitor, 0.1 µF, 50 V, 0402 [1005 Metric], ± 10%, X5R, GRM Series"
			(at 0 0 90)
			(layer "F.Fab")
			(hide yes)
			(effects
				(font
					(size 1.27 1.27)
					(thickness 0.15)
				)
			)
		)
		(property "Author" "Antmicro"
			(at 338.49 -72.49 0)
			(layer "B.Fab")
			(hide yes)
			(effects
				(font
					(size 1 1)
					(thickness 0.15)
				)
				(justify mirror)
			)
		)
		(property "Dielectric" "X5R"
			(at 338.49 -72.49 0)
			(layer "B.Fab")
			(hide yes)
			(effects
				(font
					(size 1 1)
					(thickness 0.15)
				)
				(justify mirror)
			)
		)
		(property "License" "Apache-2.0"
			(at 338.49 -72.49 0)
			(layer "B.Fab")
			(hide yes)
			(effects
				(font
					(size 1 1)
					(thickness 0.15)
				)
				(justify mirror)
			)
		)
		(property "MPN" "GRM155R61H104KE14D"
			(at 338.49 -72.49 0)
			(layer "B.Fab")
			(hide yes)
			(effects
				(font
					(size 1 1)
					(thickness 0.15)
				)
				(justify mirror)
			)
		)
		(property "Manufacturer" "Murata"
			(at 338.49 -72.49 0)
			(layer "B.Fab")
			(hide yes)
			(effects
				(font
					(size 1 1)
					(thickness 0.15)
				)
				(justify mirror)
			)
		)
		(property "Val" "100n"
			(at 338.49 -72.49 0)
			(layer "B.Fab")
			(hide yes)
			(effects
				(font
					(size 1 1)
					(thickness 0.15)
				)
				(justify mirror)
			)
		)
		(property "Voltage" "50V"
			(at 338.49 -72.49 0)
			(layer "B.Fab")
			(hide yes)
			(effects
				(font
					(size 1 1)
					(thickness 0.15)
				)
				(justify mirror)
			)
		)
		(sheetname "FPGA Bank 14 & 15")
		(sheetfile "fpga-bank-14-15.kicad_sch")
		(attr smd)
		(fp_rect
			(start -0.925 0.47)
			(end 0.925 -0.47)
			(stroke
				(width 0.05)
				(type default)
			)
			(fill no)
			(layer "B.CrtYd")
		)
		(fp_line
			(start 0.504 -0.248)
			(end -0.494 -0.248)
			(stroke
				(width 0.15)
				(type solid)
			)
			(layer "B.Fab")
		)
		(fp_line
			(start -0.494 -0.248)
			(end -0.494 0.25)
			(stroke
				(width 0.15)
				(type solid)
			)
			(layer "B.Fab")
		)
		(fp_line
			(start 0.504 0.25)
			(end 0.504 -0.248)
			(stroke
				(width 0.15)
				(type solid)
			)
			(layer "B.Fab")
		)
		(fp_line
			(start -0.494 0.25)
			(end 0.504 0.25)
			(stroke
				(width 0.15)
				(type solid)
			)
			(layer "B.Fab")
		)
		(pad "1" smd roundrect
			(at -0.48 0 90)
			(size 0.59 0.64)
			(layers "B.Cu" "B.Mask" "B.Paste")
			(roundrect_rratio 0.25)
			(net 1 "GND")
			(pintype "passive")
		)
		(pad "2" smd roundrect
			(at 0.48 0 90)
			(size 0.59 0.64)
			(layers "B.Cu" "B.Mask" "B.Paste")
			(roundrect_rratio 0.25)
			(net 24 "+3V3")
			(pintype "passive")
		)
	)
	(footprint "antmicro-footprints:NetTie-2_SMD_Pad0.127mm"
		(layer "B.Cu")
		(at 254.101 127.2 -90)
		(descr "Net tie, 2 pin, 0.127mm  SMD pads")
		(tags "net tie")
		(property "Reference" "NT22"
			(at -0.128 1.345 90)
			(layer "B.SilkS")
			(hide yes)
			(effects
				(font
					(size 0.7 0.7)
					(thickness 0.15)
				)
				(justify left bottom mirror)
			)
		)
		(property "Value" "Net-Tie_2"
			(at 0 -1.199 90)
			(layer "B.Fab")
			(effects
				(font
					(size 0.7 0.7)
					(thickness 0.15)
				)
				(justify left bottom mirror)
			)
		)
		(property "Description" "Net tie, 2 pins"
			(at 0 0 270)
			(layer "F.Fab")
			(hide yes)
			(effects
				(font
					(size 1.27 1.27)
					(thickness 0.15)
				)
			)
		)
		(property "Author" "Antmicro"
			(at 126.901 381.301 0)
			(layer "B.Fab")
			(hide yes)
			(effects
				(font
					(size 1 1)
					(thickness 0.15)
				)
				(justify mirror)
			)
		)
		(property "License" "Apache-2.0"
			(at 126.901 381.301 0)
			(layer "B.Fab")
			(hide yes)
			(effects
				(font
					(size 1 1)
					(thickness 0.15)
				)
				(justify mirror)
			)
		)
		(property "MPN" ""
			(at 126.901 381.301 0)
			(layer "B.Fab")
			(hide yes)
			(effects
				(font
					(size 1 1)
					(thickness 0.15)
				)
				(justify mirror)
			)
		)
		(property "Manufacturer" ""
			(at 126.901 381.301 0)
			(layer "B.Fab")
			(hide yes)
			(effects
				(font
					(size 1 1)
					(thickness 0.15)
				)
				(justify mirror)
			)
		)
		(sheetname "Supervisior MCU")
		(sheetfile "supervisor-mcu.kicad_sch")
		(attr exclude_from_pos_files)
		(net_tie_pad_groups "1, 2")
		(fp_poly
			(pts
				(xy -0.0635 0.0635) (xy 0.0625 0.0635) (xy 0.0625 -0.0635) (xy -0.0635 -0.0635)
			)
			(stroke
				(width 0)
				(type solid)
			)
			(fill yes)
			(layer "B.Cu")
		)
		(pad "1" smd roundrect
			(at -0.127 0 90)
			(size 0.127 0.127)
			(layers "B.Cu")
			(roundrect_rratio 0.5)
			(chamfer_ratio 0)
			(chamfer top_left bottom_left)
			(net 1336 "/I2C.SDA")
			(pinfunction "1")
			(pintype "passive")
		)
		(pad "2" smd roundrect
			(at 0.126 0 270)
			(size 0.127 0.127)
			(layers "B.Cu")
			(roundrect_rratio 0.5)
			(chamfer_ratio 0)
			(chamfer top_left bottom_left)
			(net 1337 "/SUP_MCU.SDA")
			(pinfunction "2")
			(pintype "passive")
		)
	)
	(footprint "antmicro-footprints:C_0201"
		(layer "B.Cu")
		(at 201.5 126.45)
		(descr "Capacitor SMD 0201")
		(tags "capacitor SMD 0201")
		(property "Reference" "C122"
			(at 24.475 -29.525 0)
			(layer "B.SilkS")
			(effects
				(font
					(size 0.7 0.7)
					(thickness 0.15)
				)
				(justify right bottom mirror)
			)
		)
		(property "Value" "C_100n_0201"
			(at 0 -1.4 0)
			(layer "B.Fab")
			(effects
				(font
					(size 0.7 0.7)
					(thickness 0.15)
				)
				(justify right bottom mirror)
			)
		)
		(property "Description" "SMD Multilayer Ceramic Capacitor, 0.1 µF, 6.3 V, 0201 [0603 Metric], ± 10%, X6S, CC Series"
			(at 0 0 0)
			(layer "F.Fab")
			(hide yes)
			(effects
				(font
					(size 1.27 1.27)
					(thickness 0.15)
				)
			)
		)
		(property "Author" "Antmicro"
			(at 0 0 0)
			(layer "B.Fab")
			(hide yes)
			(effects
				(font
					(size 1 1)
					(thickness 0.15)
				)
				(justify mirror)
			)
		)
		(property "Dielectric" ""
			(at 0 0 0)
			(layer "B.Fab")
			(hide yes)
			(effects
				(font
					(size 1 1)
					(thickness 0.15)
				)
				(justify mirror)
			)
		)
		(property "License" "Apache-2.0"
			(at 0 0 0)
			(layer "B.Fab")
			(hide yes)
			(effects
				(font
					(size 1 1)
					(thickness 0.15)
				)
				(justify mirror)
			)
		)
		(property "MPN" "CC0201KRX6S5BB104"
			(at 0 0 0)
			(layer "B.Fab")
			(hide yes)
			(effects
				(font
					(size 1 1)
					(thickness 0.15)
				)
				(justify mirror)
			)
		)
		(property "Manufacturer" "YAGEO"
			(at 0 0 0)
			(layer "B.Fab")
			(hide yes)
			(effects
				(font
					(size 1 1)
					(thickness 0.15)
				)
				(justify mirror)
			)
		)
		(property "Val" "100n"
			(at 0 0 0)
			(layer "B.Fab")
			(hide yes)
			(effects
				(font
					(size 1 1)
					(thickness 0.15)
				)
				(justify mirror)
			)
		)
		(property "Voltage" ""
			(at 0 0 0)
			(layer "B.Fab")
			(hide yes)
			(effects
				(font
					(size 1 1)
					(thickness 0.15)
				)
				(justify mirror)
			)
		)
		(sheetname "FPGA supply")
		(sheetfile "fpga-supply.kicad_sch")
		(attr smd)
		(fp_rect
			(start -0.7 0.35)
			(end 0.7 -0.35)
			(stroke
				(width 0.05)
				(type default)
			)
			(fill no)
			(layer "B.CrtYd")
		)
		(fp_rect
			(start 0.3 -0.15)
			(end -0.301 0.149)
			(stroke
				(width 0.15)
				(type solid)
			)
			(fill no)
			(layer "B.Fab")
		)
		(pad "" smd roundrect
			(at -0.349 0.002)
			(size 0.318 0.36)
			(layers "B.Paste")
			(roundrect_rratio 0.25)
		)
		(pad "" smd roundrect
			(at 0.341 0.002)
			(size 0.318 0.36)
			(layers "B.Paste")
			(roundrect_rratio 0.25)
		)
		(pad "1" smd roundrect
			(at -0.321 0.002)
			(size 0.46 0.4)
			(layers "B.Cu" "B.Mask")
			(roundrect_rratio 0.25)
			(net 1 "GND")
			(pintype "passive")
		)
		(pad "2" smd roundrect
			(at 0.32 0.002)
			(size 0.46 0.4)
			(layers "B.Cu" "B.Mask")
			(roundrect_rratio 0.25)
			(net 650 "+1V0")
			(pintype "passive")
		)
	)
	(footprint "antmicro-footprints:C_0402_1005Metric"
		(layer "B.Cu")
		(at 164.85 188.3 -90)
		(descr "Capacitor SMD 0402")
		(tags "capacitor SMD 0402")
		(property "Reference" "C337"
			(at -1.6 0.45 90)
			(layer "B.SilkS")
			(effects
				(font
					(size 0.7 0.7)
					(thickness 0.15)
				)
				(justify left bottom mirror)
			)
		)
		(property "Value" "C_100n_0402"
			(at 0 -1.4 90)
			(layer "B.Fab")
			(effects
				(font
					(size 0.7 0.7)
					(thickness 0.15)
				)
				(justify left bottom mirror)
			)
		)
		(property "Description" "SMD Multilayer Ceramic Capacitor, 0.1 µF, 50 V, 0402 [1005 Metric], ± 10%, X5R, GRM Series"
			(at 0 0 270)
			(layer "F.Fab")
			(hide yes)
			(effects
				(font
					(size 1.27 1.27)
					(thickness 0.15)
				)
			)
		)
		(property "Author" "Antmicro"
			(at -23.45 353.15 0)
			(layer "B.Fab")
			(hide yes)
			(effects
				(font
					(size 1 1)
					(thickness 0.15)
				)
				(justify mirror)
			)
		)
		(property "Dielectric" "X5R"
			(at -23.45 353.15 0)
			(layer "B.Fab")
			(hide yes)
			(effects
				(font
					(size 1 1)
					(thickness 0.15)
				)
				(justify mirror)
			)
		)
		(property "License" "Apache-2.0"
			(at -23.45 353.15 0)
			(layer "B.Fab")
			(hide yes)
			(effects
				(font
					(size 1 1)
					(thickness 0.15)
				)
				(justify mirror)
			)
		)
		(property "MPN" "GRM155R61H104KE14D"
			(at -23.45 353.15 0)
			(layer "B.Fab")
			(hide yes)
			(effects
				(font
					(size 1 1)
					(thickness 0.15)
				)
				(justify mirror)
			)
		)
		(property "Manufacturer" "Murata"
			(at -23.45 353.15 0)
			(layer "B.Fab")
			(hide yes)
			(effects
				(font
					(size 1 1)
					(thickness 0.15)
				)
				(justify mirror)
			)
		)
		(property "Val" "100n"
			(at -23.45 353.15 0)
			(layer "B.Fab")
			(hide yes)
			(effects
				(font
					(size 1 1)
					(thickness 0.15)
				)
				(justify mirror)
			)
		)
		(property "Voltage" "50V"
			(at -23.45 353.15 0)
			(layer "B.Fab")
			(hide yes)
			(effects
				(font
					(size 1 1)
					(thickness 0.15)
				)
				(justify mirror)
			)
		)
		(sheetname "DC-DC Converters")
		(sheetfile "dc-dc.kicad_sch")
		(attr smd)
		(fp_rect
			(start -0.925 0.47)
			(end 0.925 -0.47)
			(stroke
				(width 0.05)
				(type default)
			)
			(fill no)
			(layer "B.CrtYd")
		)
		(fp_line
			(start -0.494 0.25)
			(end 0.504 0.25)
			(stroke
				(width 0.15)
				(type solid)
			)
			(layer "B.Fab")
		)
		(fp_line
			(start 0.504 0.25)
			(end 0.504 -0.248)
			(stroke
				(width 0.15)
				(type solid)
			)
			(layer "B.Fab")
		)
		(fp_line
			(start -0.494 -0.248)
			(end -0.494 0.25)
			(stroke
				(width 0.15)
				(type solid)
			)
			(layer "B.Fab")
		)
		(fp_line
			(start 0.504 -0.248)
			(end -0.494 -0.248)
			(stroke
				(width 0.15)
				(type solid)
			)
			(layer "B.Fab")
		)
		(pad "1" smd roundrect
			(at -0.48 0 270)
			(size 0.59 0.64)
			(layers "B.Cu" "B.Mask" "B.Paste")
			(roundrect_rratio 0.25)
			(net 1 "GND")
			(pintype "passive")
		)
		(pad "2" smd roundrect
			(at 0.48 0 270)
			(size 0.59 0.64)
			(layers "B.Cu" "B.Mask" "B.Paste")
			(roundrect_rratio 0.25)
			(net 37 "+3V3_AON")
			(pintype "passive")
		)
	)
	(footprint "antmicro-footprints:C_0201"
		(layer "B.Cu")
		(at 192.3 124.2 -45)
		(descr "Capacitor SMD 0201")
		(tags "capacitor SMD 0201")
		(property "Reference" "C104"
			(at -4.454773 -36.097801 315)
			(unlocked yes)
			(layer "B.SilkS")
			(effects
				(font
					(size 0.7 0.7)
					(thickness 0.15)
				)
				(justify left bottom mirror)
			)
		)
		(property "Value" "C_100n_0201"
			(at 0 -1.399999 135)
			(layer "B.Fab")
			(effects
				(font
					(size 0.7 0.7)
					(thickness 0.15)
				)
				(justify left bottom mirror)
			)
		)
		(property "Description" "SMD Multilayer Ceramic Capacitor, 0.1 µF, 6.3 V, 0201 [0603 Metric], ± 10%, X6S, CC Series"
			(at 0 0 315)
			(layer "F.Fab")
			(hide yes)
			(effects
				(font
					(size 1.27 1.27)
					(thickness 0.15)
				)
			)
		)
		(property "Author" "Antmicro"
			(at -31.499296 172.353971 0)
			(layer "B.Fab")
			(hide yes)
			(effects
				(font
					(size 1 1)
					(thickness 0.15)
				)
				(justify mirror)
			)
		)
		(property "Dielectric" ""
			(at -31.499296 172.353971 0)
			(layer "B.Fab")
			(hide yes)
			(effects
				(font
					(size 1 1)
					(thickness 0.15)
				)
				(justify mirror)
			)
		)
		(property "License" "Apache-2.0"
			(at -31.499296 172.353971 0)
			(layer "B.Fab")
			(hide yes)
			(effects
				(font
					(size 1 1)
					(thickness 0.15)
				)
				(justify mirror)
			)
		)
		(property "MPN" "CC0201KRX6S5BB104"
			(at -31.499296 172.353971 0)
			(layer "B.Fab")
			(hide yes)
			(effects
				(font
					(size 1 1)
					(thickness 0.15)
				)
				(justify mirror)
			)
		)
		(property "Manufacturer" "YAGEO"
			(at -31.499296 172.353971 0)
			(layer "B.Fab")
			(hide yes)
			(effects
				(font
					(size 1 1)
					(thickness 0.15)
				)
				(justify mirror)
			)
		)
		(property "Val" "100n"
			(at -31.499296 172.353971 0)
			(layer "B.Fab")
			(hide yes)
			(effects
				(font
					(size 1 1)
					(thickness 0.15)
				)
				(justify mirror)
			)
		)
		(property "Voltage" ""
			(at -31.499296 172.353971 0)
			(layer "B.Fab")
			(hide yes)
			(effects
				(font
					(size 1 1)
					(thickness 0.15)
				)
				(justify mirror)
			)
		)
		(sheetname "FPGA supply")
		(sheetfile "fpga-supply.kicad_sch")
		(attr smd)
		(fp_poly
			(pts
				(xy -0.7 0.35) (xy 0.7 0.35) (xy 0.7 -0.35) (xy -0.7 -0.35)
			)
			(stroke
				(width 0.05)
				(type default)
			)
			(fill no)
			(layer "B.CrtYd")
		)
		(fp_poly
			(pts
				(xy 0.3 -0.15) (xy -0.301 -0.15) (xy -0.301 0.149) (xy 0.3 0.149)
			)
			(stroke
				(width 0.15)
				(type solid)
			)
			(fill no)
			(layer "B.Fab")
		)
		(pad "" smd roundrect
			(at -0.349 0.002 315)
			(size 0.318 0.36)
			(layers "B.Paste")
			(roundrect_rratio 0.25)
		)
		(pad "" smd roundrect
			(at 0.341 0.002 315)
			(size 0.318 0.36)
			(layers "B.Paste")
			(roundrect_rratio 0.25)
		)
		(pad "1" smd roundrect
			(at -0.321 0.002 315)
			(size 0.46 0.4)
			(layers "B.Cu" "B.Mask")
			(roundrect_rratio 0.25)
			(net 6 "+1V0_MGTAVCC")
			(pintype "passive")
		)
		(pad "2" smd roundrect
			(at 0.32 0.002 315)
			(size 0.46 0.4)
			(layers "B.Cu" "B.Mask")
			(roundrect_rratio 0.25)
			(net 1 "GND")
			(pintype "passive")
		)
	)
	(footprint "antmicro-footprints:R_0402_1005Metric"
		(layer "B.Cu")
		(at 253.601 170.9 90)
		(descr "Resistor SMD 0402")
		(tags "resistor SMD 0402")
		(property "Reference" "R167"
			(at 1.3 -0.501 90)
			(layer "B.SilkS")
			(effects
				(font
					(size 0.7 0.7)
					(thickness 0.15)
				)
				(justify left bottom mirror)
			)
		)
		(property "Value" "R_10k_0402"
			(at 0 -1.4 270)
			(layer "B.Fab")
			(effects
				(font
					(size 0.7 0.7)
					(thickness 0.15)
				)
				(justify left bottom mirror)
			)
		)
		(property "Description" "SMD Chip Resistor, 10 kohm, ± 1%, 62.5 mW, 0402 [1005 Metric], Thick Film, General Purpose"
			(at 0 0 90)
			(layer "F.Fab")
			(hide yes)
			(effects
				(font
					(size 1.27 1.27)
					(thickness 0.15)
				)
			)
		)
		(property "Author" "Antmicro"
			(at 424.501 -82.701 0)
			(layer "B.Fab")
			(hide yes)
			(effects
				(font
					(size 1 1)
					(thickness 0.15)
				)
				(justify mirror)
			)
		)
		(property "License" "Apache-2.0"
			(at 424.501 -82.701 0)
			(layer "B.Fab")
			(hide yes)
			(effects
				(font
					(size 1 1)
					(thickness 0.15)
				)
				(justify mirror)
			)
		)
		(property "MPN" "CR0402-FX-1002GLF"
			(at 424.501 -82.701 0)
			(layer "B.Fab")
			(hide yes)
			(effects
				(font
					(size 1 1)
					(thickness 0.15)
				)
				(justify mirror)
			)
		)
		(property "Manufacturer" "Bourns"
			(at 424.501 -82.701 0)
			(layer "B.Fab")
			(hide yes)
			(effects
				(font
					(size 1 1)
					(thickness 0.15)
				)
				(justify mirror)
			)
		)
		(property "Tolerance" "1%"
			(at 424.501 -82.701 0)
			(layer "B.Fab")
			(hide yes)
			(effects
				(font
					(size 1 1)
					(thickness 0.15)
				)
				(justify mirror)
			)
		)
		(property "Val" "10k"
			(at 424.501 -82.701 0)
			(layer "B.Fab")
			(hide yes)
			(effects
				(font
					(size 1 1)
					(thickness 0.15)
				)
				(justify mirror)
			)
		)
		(sheetname "Power supply")
		(sheetfile "power-supply.kicad_sch")
		(attr smd)
		(fp_rect
			(start -0.925 0.47)
			(end 0.925 -0.47)
			(stroke
				(width 0.05)
				(type default)
			)
			(fill no)
			(layer "B.CrtYd")
		)
		(fp_rect
			(start -0.5 0.25)
			(end 0.5 -0.25)
			(stroke
				(width 0.15)
				(type solid)
			)
			(fill no)
			(layer "B.Fab")
		)
		(pad "1" smd roundrect
			(at -0.48 0 90)
			(size 0.59 0.64)
			(layers "B.Cu" "B.Mask" "B.Paste")
			(roundrect_rratio 0.25)
			(net 699 "GNDD")
			(pintype "passive")
		)
		(pad "2" smd roundrect
			(at 0.48 0 90)
			(size 0.59 0.64)
			(layers "B.Cu" "B.Mask" "B.Paste")
			(roundrect_rratio 0.25)
			(net 889 "/Power supply/PG")
			(pintype "passive")
		)
	)
	(footprint "antmicro-footprints:C_0201"
		(layer "B.Cu")
		(at 190 129.5 180)
		(descr "Capacitor SMD 0201")
		(tags "capacitor SMD 0201")
		(property "Reference" "C159"
			(at 0.575 -0.35 0)
			(layer "B.SilkS")
			(effects
				(font
					(size 0.7 0.7)
					(thickness 0.15)
				)
				(justify left bottom mirror)
			)
		)
		(property "Value" "C_100n_0201"
			(at 0 -1.4 0)
			(layer "B.Fab")
			(effects
				(font
					(size 0.7 0.7)
					(thickness 0.15)
				)
				(justify left bottom mirror)
			)
		)
		(property "Description" "SMD Multilayer Ceramic Capacitor, 0.1 µF, 6.3 V, 0201 [0603 Metric], ± 10%, X6S, CC Series"
			(at 0 0 180)
			(layer "F.Fab")
			(hide yes)
			(effects
				(font
					(size 1.27 1.27)
					(thickness 0.15)
				)
			)
		)
		(property "Author" "Antmicro"
			(at 380 259 0)
			(layer "B.Fab")
			(hide yes)
			(effects
				(font
					(size 1 1)
					(thickness 0.15)
				)
				(justify mirror)
			)
		)
		(property "Dielectric" ""
			(at 380 259 0)
			(layer "B.Fab")
			(hide yes)
			(effects
				(font
					(size 1 1)
					(thickness 0.15)
				)
				(justify mirror)
			)
		)
		(property "License" "Apache-2.0"
			(at 380 259 0)
			(layer "B.Fab")
			(hide yes)
			(effects
				(font
					(size 1 1)
					(thickness 0.15)
				)
				(justify mirror)
			)
		)
		(property "MPN" "CC0201KRX6S5BB104"
			(at 380 259 0)
			(layer "B.Fab")
			(hide yes)
			(effects
				(font
					(size 1 1)
					(thickness 0.15)
				)
				(justify mirror)
			)
		)
		(property "Manufacturer" "YAGEO"
			(at 380 259 0)
			(layer "B.Fab")
			(hide yes)
			(effects
				(font
					(size 1 1)
					(thickness 0.15)
				)
				(justify mirror)
			)
		)
		(property "Val" "100n"
			(at 380 259 0)
			(layer "B.Fab")
			(hide yes)
			(effects
				(font
					(size 1 1)
					(thickness 0.15)
				)
				(justify mirror)
			)
		)
		(property "Voltage" ""
			(at 380 259 0)
			(layer "B.Fab")
			(hide yes)
			(effects
				(font
					(size 1 1)
					(thickness 0.15)
				)
				(justify mirror)
			)
		)
		(sheetname "FPGA supply")
		(sheetfile "fpga-supply.kicad_sch")
		(attr smd)
		(fp_rect
			(start -0.7 0.35)
			(end 0.7 -0.35)
			(stroke
				(width 0.05)
				(type default)
			)
			(fill no)
			(layer "B.CrtYd")
		)
		(fp_rect
			(start 0.3 -0.15)
			(end -0.301 0.149)
			(stroke
				(width 0.15)
				(type solid)
			)
			(fill no)
			(layer "B.Fab")
		)
		(pad "" smd roundrect
			(at -0.349 0.002 180)
			(size 0.318 0.36)
			(layers "B.Paste")
			(roundrect_rratio 0.25)
		)
		(pad "" smd roundrect
			(at 0.341 0.002 180)
			(size 0.318 0.36)
			(layers "B.Paste")
			(roundrect_rratio 0.25)
		)
		(pad "1" smd roundrect
			(at -0.321 0.002 180)
			(size 0.46 0.4)
			(layers "B.Cu" "B.Mask")
			(roundrect_rratio 0.25)
			(net 1 "GND")
			(pintype "passive")
		)
		(pad "2" smd roundrect
			(at 0.32 0.002 180)
			(size 0.46 0.4)
			(layers "B.Cu" "B.Mask")
			(roundrect_rratio 0.25)
			(net 8 "+1V2_MGTAVTT")
			(pintype "passive")
		)
	)
	(footprint "antmicro-footprints:R_Array_4x0201_Panasonic_EXB18V"
		(layer "B.Cu")
		(at 218.1 132.8 -90)
		(property "Reference" "R36"
			(at 1.1 -1.5 90)
			(layer "B.SilkS")
			(effects
				(font
					(size 0.7 0.7)
					(thickness 0.15)
				)
				(justify right bottom mirror)
			)
		)
		(property "Value" "4x10k_0201_array"
			(at -1.1 -1.8 90)
			(layer "B.Fab")
			(effects
				(font
					(size 0.7 0.7)
					(thickness 0.15)
				)
				(justify left bottom mirror)
			)
		)
		(property "Description" "Fixed Network Resistor, 10 kohm, Isolated, 4 Resistors, 0502 [1406 Metric], Flat, ± 5%"
			(at 0 0 270)
			(layer "F.Fab")
			(hide yes)
			(effects
				(font
					(size 1.27 1.27)
					(thickness 0.15)
				)
			)
		)
		(property "Author" "Antmicro"
			(at 85.3 350.9 0)
			(layer "B.Fab")
			(hide yes)
			(effects
				(font
					(size 1 1)
					(thickness 0.15)
				)
				(justify mirror)
			)
		)
		(property "License" "Apache-2.0"
			(at 85.3 350.9 0)
			(layer "B.Fab")
			(hide yes)
			(effects
				(font
					(size 1 1)
					(thickness 0.15)
				)
				(justify mirror)
			)
		)
		(property "MPN" "EXB-18V103JX"
			(at 85.3 350.9 0)
			(layer "B.Fab")
			(hide yes)
			(effects
				(font
					(size 1 1)
					(thickness 0.15)
				)
				(justify mirror)
			)
		)
		(property "Manufacturer" "Panasonic"
			(at 85.3 350.9 0)
			(layer "B.Fab")
			(hide yes)
			(effects
				(font
					(size 1 1)
					(thickness 0.15)
				)
				(justify mirror)
			)
		)
		(property "Val" "4x10k_0201"
			(at 85.3 350.9 0)
			(layer "B.Fab")
			(hide yes)
			(effects
				(font
					(size 1 1)
					(thickness 0.15)
				)
				(justify mirror)
			)
		)
		(sheetname "DRAM + SRAM")
		(sheetfile "ram.kicad_sch")
		(attr smd)
		(fp_line
			(start -0.8 0.45)
			(end -0.8 -0.45)
			(stroke
				(width 0.12)
				(type solid)
			)
			(layer "B.SilkS")
		)
		(fp_line
			(start 0.8 0.45)
			(end 0.8 -0.45)
			(stroke
				(width 0.12)
				(type solid)
			)
			(layer "B.SilkS")
		)
		(fp_rect
			(start -0.898 0.66)
			(end 0.898 -0.65)
			(stroke
				(width 0.05)
				(type solid)
			)
			(fill no)
			(layer "B.CrtYd")
		)
		(pad "1" smd roundrect
			(at -0.6 -0.298 270)
			(size 0.2 0.4)
			(layers "B.Cu" "B.Mask" "B.Paste")
			(roundrect_rratio 0.25)
			(net 563 "/DRAM + SRAM/SRAM.~{WE}")
			(pinfunction "R1.1")
			(pintype "passive")
		)
		(pad "2" smd roundrect
			(at -0.202 -0.298 270)
			(size 0.2 0.4)
			(layers "B.Cu" "B.Mask" "B.Paste")
			(roundrect_rratio 0.25)
			(net 564 "/DRAM + SRAM/SRAM.~{OE}")
			(pinfunction "R2.1")
			(pintype "passive")
		)
		(pad "3" smd roundrect
			(at 0.2 -0.298 270)
			(size 0.2 0.4)
			(layers "B.Cu" "B.Mask" "B.Paste")
			(roundrect_rratio 0.25)
			(net 556 "/DRAM + SRAM/SRAM.~{CE}")
			(pinfunction "R3.1")
			(pintype "passive")
		)
		(pad "4" smd roundrect
			(at 0.598 -0.298 270)
			(size 0.2 0.4)
			(layers "B.Cu" "B.Mask" "B.Paste")
			(roundrect_rratio 0.25)
			(net 562 "/DRAM + SRAM/SRAM.CE2")
			(pinfunction "R4.1")
			(pintype "passive")
		)
		(pad "5" smd roundrect
			(at 0.598 0.3 270)
			(size 0.2 0.4)
			(layers "B.Cu" "B.Mask" "B.Paste")
			(roundrect_rratio 0.25)
			(net 24 "+3V3")
			(pinfunction "R4.2")
			(pintype "passive")
		)
		(pad "6" smd roundrect
			(at 0.2 0.3 270)
			(size 0.2 0.4)
			(layers "B.Cu" "B.Mask" "B.Paste")
			(roundrect_rratio 0.25)
			(net 24 "+3V3")
			(pinfunction "R3.2")
			(pintype "passive")
		)
		(pad "7" smd roundrect
			(at -0.202 0.3 270)
			(size 0.2 0.4)
			(layers "B.Cu" "B.Mask" "B.Paste")
			(roundrect_rratio 0.25)
			(net 24 "+3V3")
			(pinfunction "R2.2")
			(pintype "passive")
		)
		(pad "8" smd roundrect
			(at -0.6 0.3 270)
			(size 0.2 0.4)
			(layers "B.Cu" "B.Mask" "B.Paste")
			(roundrect_rratio 0.25)
			(net 24 "+3V3")
			(pinfunction "R1.2")
			(pintype "passive")
		)
	)
	(footprint "antmicro-footprints:R_0402_1005Metric"
		(layer "B.Cu")
		(at 258.4 79 -90)
		(descr "Resistor SMD 0402")
		(tags "resistor SMD 0402")
		(property "Reference" "R359"
			(at -1.4 -1.3 90)
			(layer "B.SilkS")
			(effects
				(font
					(size 0.7 0.7)
					(thickness 0.15)
				)
				(justify left bottom mirror)
			)
		)
		(property "Value" "R_100k_0402"
			(at 0 -1.4 90)
			(layer "B.Fab")
			(effects
				(font
					(size 0.7 0.7)
					(thickness 0.15)
				)
				(justify left bottom mirror)
			)
		)
		(property "Description" "SMD Chip Resistor, 100 kohm, ± 1%, 62.5 mW, 0402 [1005 Metric], Thick Film, General Purpose"
			(at 0 0 270)
			(layer "F.Fab")
			(hide yes)
			(effects
				(font
					(size 1.27 1.27)
					(thickness 0.15)
				)
			)
		)
		(property "Author" "Antmicro"
			(at 179.4 337.4 0)
			(layer "B.Fab")
			(hide yes)
			(effects
				(font
					(size 1 1)
					(thickness 0.15)
				)
				(justify mirror)
			)
		)
		(property "License" "Apache-2.0"
			(at 179.4 337.4 0)
			(layer "B.Fab")
			(hide yes)
			(effects
				(font
					(size 1 1)
					(thickness 0.15)
				)
				(justify mirror)
			)
		)
		(property "MPN" "CR0402-FX-1003GLF"
			(at 179.4 337.4 0)
			(layer "B.Fab")
			(hide yes)
			(effects
				(font
					(size 1 1)
					(thickness 0.15)
				)
				(justify mirror)
			)
		)
		(property "Manufacturer" "Bourns"
			(at 179.4 337.4 0)
			(layer "B.Fab")
			(hide yes)
			(effects
				(font
					(size 1 1)
					(thickness 0.15)
				)
				(justify mirror)
			)
		)
		(property "Tolerance" "1%"
			(at 179.4 337.4 0)
			(layer "B.Fab")
			(hide yes)
			(effects
				(font
					(size 1 1)
					(thickness 0.15)
				)
				(justify mirror)
			)
		)
		(property "Val" "100k"
			(at 179.4 337.4 0)
			(layer "B.Fab")
			(hide yes)
			(effects
				(font
					(size 1 1)
					(thickness 0.15)
				)
				(justify mirror)
			)
		)
		(sheetname "User GPIO + LED + button + DIP switch")
		(sheetfile "user-gpio.kicad_sch")
		(attr smd)
		(fp_rect
			(start -0.925 0.47)
			(end 0.925 -0.47)
			(stroke
				(width 0.05)
				(type default)
			)
			(fill no)
			(layer "B.CrtYd")
		)
		(fp_rect
			(start -0.5 0.25)
			(end 0.5 -0.25)
			(stroke
				(width 0.15)
				(type solid)
			)
			(fill no)
			(layer "B.Fab")
		)
		(pad "1" smd roundrect
			(at -0.48 0 270)
			(size 0.59 0.64)
			(layers "B.Cu" "B.Mask" "B.Paste")
			(roundrect_rratio 0.25)
			(net 1305 "/USER_IO.LED_RED")
			(pintype "passive")
		)
		(pad "2" smd roundrect
			(at 0.48 0 270)
			(size 0.59 0.64)
			(layers "B.Cu" "B.Mask" "B.Paste")
			(roundrect_rratio 0.25)
			(net 1 "GND")
			(pintype "passive")
		)
	)
	(footprint "antmicro-footprints:R_0402_1005Metric"
		(layer "B.Cu")
		(at 266.8 79.4 -90)
		(descr "Resistor SMD 0402")
		(tags "resistor SMD 0402")
		(property "Reference" "R140"
			(at -1.4 -1.25 90)
			(layer "B.SilkS")
			(effects
				(font
					(size 0.7 0.7)
					(thickness 0.15)
				)
				(justify left bottom mirror)
			)
		)
		(property "Value" "R_10k_0402"
			(at 0 -1.4 90)
			(layer "B.Fab")
			(effects
				(font
					(size 0.7 0.7)
					(thickness 0.15)
				)
				(justify left bottom mirror)
			)
		)
		(property "Description" "SMD Chip Resistor, 10 kohm, ± 1%, 62.5 mW, 0402 [1005 Metric], Thick Film, General Purpose"
			(at 0 0 270)
			(layer "F.Fab")
			(hide yes)
			(effects
				(font
					(size 1.27 1.27)
					(thickness 0.15)
				)
			)
		)
		(property "Author" "Antmicro"
			(at 187.4 346.2 0)
			(layer "B.Fab")
			(hide yes)
			(effects
				(font
					(size 1 1)
					(thickness 0.15)
				)
				(justify mirror)
			)
		)
		(property "License" "Apache-2.0"
			(at 187.4 346.2 0)
			(layer "B.Fab")
			(hide yes)
			(effects
				(font
					(size 1 1)
					(thickness 0.15)
				)
				(justify mirror)
			)
		)
		(property "MPN" "CR0402-FX-1002GLF"
			(at 187.4 346.2 0)
			(layer "B.Fab")
			(hide yes)
			(effects
				(font
					(size 1 1)
					(thickness 0.15)
				)
				(justify mirror)
			)
		)
		(property "Manufacturer" "Bourns"
			(at 187.4 346.2 0)
			(layer "B.Fab")
			(hide yes)
			(effects
				(font
					(size 1 1)
					(thickness 0.15)
				)
				(justify mirror)
			)
		)
		(property "Tolerance" "1%"
			(at 187.4 346.2 0)
			(layer "B.Fab")
			(hide yes)
			(effects
				(font
					(size 1 1)
					(thickness 0.15)
				)
				(justify mirror)
			)
		)
		(property "Val" "10k"
			(at 187.4 346.2 0)
			(layer "B.Fab")
			(hide yes)
			(effects
				(font
					(size 1 1)
					(thickness 0.15)
				)
				(justify mirror)
			)
		)
		(sheetname "User GPIO + LED + button + DIP switch")
		(sheetfile "user-gpio.kicad_sch")
		(attr smd)
		(fp_rect
			(start -0.925 0.47)
			(end 0.925 -0.47)
			(stroke
				(width 0.05)
				(type default)
			)
			(fill no)
			(layer "B.CrtYd")
		)
		(fp_rect
			(start -0.5 0.25)
			(end 0.5 -0.25)
			(stroke
				(width 0.15)
				(type solid)
			)
			(fill no)
			(layer "B.Fab")
		)
		(pad "1" smd roundrect
			(at -0.48 0 270)
			(size 0.59 0.64)
			(layers "B.Cu" "B.Mask" "B.Paste")
			(roundrect_rratio 0.25)
			(net 26 "+1V8")
			(pintype "passive")
		)
		(pad "2" smd roundrect
			(at 0.48 0 270)
			(size 0.59 0.64)
			(layers "B.Cu" "B.Mask" "B.Paste")
			(roundrect_rratio 0.25)
			(net 1228 "/USER_IO.BUTTON0")
			(pintype "passive")
		)
	)
	(footprint "antmicro-footprints:C_0402_1005Metric"
		(layer "B.Cu")
		(at 229.2 165.4 90)
		(descr "Capacitor SMD 0402")
		(tags "capacitor SMD 0402")
		(property "Reference" "C193"
			(at 3.675 0.375 270)
			(layer "B.SilkS")
			(effects
				(font
					(size 0.7 0.7)
					(thickness 0.15)
				)
				(justify left bottom mirror)
			)
		)
		(property "Value" "C_1u_0402"
			(at 0 -1.4 270)
			(layer "B.Fab")
			(effects
				(font
					(size 0.7 0.7)
					(thickness 0.15)
				)
				(justify left bottom mirror)
			)
		)
		(property "Description" "SMD Multilayer Ceramic Capacitor, 1 µF, 10 V, 0402 [1005 Metric], ± 10%, X6S, C"
			(at 0 0 90)
			(layer "F.Fab")
			(hide yes)
			(effects
				(font
					(size 1.27 1.27)
					(thickness 0.15)
				)
			)
		)
		(property "Author" "Antmicro"
			(at 394.6 -63.8 0)
			(layer "B.Fab")
			(hide yes)
			(effects
				(font
					(size 1 1)
					(thickness 0.15)
				)
				(justify mirror)
			)
		)
		(property "Dielectric" ""
			(at 394.6 -63.8 0)
			(layer "B.Fab")
			(hide yes)
			(effects
				(font
					(size 1 1)
					(thickness 0.15)
				)
				(justify mirror)
			)
		)
		(property "License" "Apache-2.0"
			(at 394.6 -63.8 0)
			(layer "B.Fab")
			(hide yes)
			(effects
				(font
					(size 1 1)
					(thickness 0.15)
				)
				(justify mirror)
			)
		)
		(property "MPN" "C1005X6S1A105K050BC"
			(at 394.6 -63.8 0)
			(layer "B.Fab")
			(hide yes)
			(effects
				(font
					(size 1 1)
					(thickness 0.15)
				)
				(justify mirror)
			)
		)
		(property "Manufacturer" "TDK"
			(at 394.6 -63.8 0)
			(layer "B.Fab")
			(hide yes)
			(effects
				(font
					(size 1 1)
					(thickness 0.15)
				)
				(justify mirror)
			)
		)
		(property "Val" "1u"
			(at 394.6 -63.8 0)
			(layer "B.Fab")
			(hide yes)
			(effects
				(font
					(size 1 1)
					(thickness 0.15)
				)
				(justify mirror)
			)
		)
		(property "Voltage" ""
			(at 394.6 -63.8 0)
			(layer "B.Fab")
			(hide yes)
			(effects
				(font
					(size 1 1)
					(thickness 0.15)
				)
				(justify mirror)
			)
		)
		(sheetname "Power supply")
		(sheetfile "power-supply.kicad_sch")
		(attr smd)
		(fp_rect
			(start -0.925 0.47)
			(end 0.925 -0.47)
			(stroke
				(width 0.05)
				(type default)
			)
			(fill no)
			(layer "B.CrtYd")
		)
		(fp_line
			(start 0.504 -0.248)
			(end -0.494 -0.248)
			(stroke
				(width 0.15)
				(type solid)
			)
			(layer "B.Fab")
		)
		(fp_line
			(start -0.494 -0.248)
			(end -0.494 0.25)
			(stroke
				(width 0.15)
				(type solid)
			)
			(layer "B.Fab")
		)
		(fp_line
			(start 0.504 0.25)
			(end 0.504 -0.248)
			(stroke
				(width 0.15)
				(type solid)
			)
			(layer "B.Fab")
		)
		(fp_line
			(start -0.494 0.25)
			(end 0.504 0.25)
			(stroke
				(width 0.15)
				(type solid)
			)
			(layer "B.Fab")
		)
		(pad "1" smd roundrect
			(at -0.48 0 90)
			(size 0.59 0.64)
			(layers "B.Cu" "B.Mask" "B.Paste")
			(roundrect_rratio 0.25)
			(net 267 "/Power supply/VREG_2V7")
			(pintype "passive")
		)
		(pad "2" smd roundrect
			(at 0.48 0 90)
			(size 0.59 0.64)
			(layers "B.Cu" "B.Mask" "B.Paste")
			(roundrect_rratio 0.25)
			(net 1 "GND")
			(pintype "passive")
		)
	)
	(footprint "antmicro-footprints:R_0402_1005Metric"
		(layer "B.Cu")
		(at 224.2 146.2 -90)
		(descr "Resistor SMD 0402")
		(tags "resistor SMD 0402")
		(property "Reference" "R237"
			(at -3.625 -0.375 90)
			(layer "B.SilkS")
			(effects
				(font
					(size 0.7 0.7)
					(thickness 0.15)
				)
				(justify left bottom mirror)
			)
		)
		(property "Value" "R_10R_0402"
			(at 0 -1.4 90)
			(layer "B.Fab")
			(effects
				(font
					(size 0.7 0.7)
					(thickness 0.15)
				)
				(justify left bottom mirror)
			)
		)
		(property "Description" "SMD Chip Resistor, 10 ohm, ± 1%, 62.5 mW, 0402 [1005 Metric], Thick Film, General Purpose"
			(at 0 0 270)
			(layer "F.Fab")
			(hide yes)
			(effects
				(font
					(size 1.27 1.27)
					(thickness 0.15)
				)
			)
		)
		(property "Author" "Antmicro"
			(at 78 370.4 0)
			(layer "B.Fab")
			(hide yes)
			(effects
				(font
					(size 1 1)
					(thickness 0.15)
				)
				(justify mirror)
			)
		)
		(property "License" "Apache-2.0"
			(at 78 370.4 0)
			(layer "B.Fab")
			(hide yes)
			(effects
				(font
					(size 1 1)
					(thickness 0.15)
				)
				(justify mirror)
			)
		)
		(property "MPN" "CR0402-FX-10R0GLF"
			(at 78 370.4 0)
			(layer "B.Fab")
			(hide yes)
			(effects
				(font
					(size 1 1)
					(thickness 0.15)
				)
				(justify mirror)
			)
		)
		(property "Manufacturer" "Bourns"
			(at 78 370.4 0)
			(layer "B.Fab")
			(hide yes)
			(effects
				(font
					(size 1 1)
					(thickness 0.15)
				)
				(justify mirror)
			)
		)
		(property "Tolerance" "1%"
			(at 78 370.4 0)
			(layer "B.Fab")
			(hide yes)
			(effects
				(font
					(size 1 1)
					(thickness 0.15)
				)
				(justify mirror)
			)
		)
		(property "Val" "10R"
			(at 78 370.4 0)
			(layer "B.Fab")
			(hide yes)
			(effects
				(font
					(size 1 1)
					(thickness 0.15)
				)
				(justify mirror)
			)
		)
		(sheetname "HDMI + Ethernet")
		(sheetfile "hdmi-ethernet.kicad_sch")
		(attr smd)
		(fp_rect
			(start -0.925 0.47)
			(end 0.925 -0.47)
			(stroke
				(width 0.05)
				(type default)
			)
			(fill no)
			(layer "B.CrtYd")
		)
		(fp_rect
			(start -0.5 0.25)
			(end 0.5 -0.25)
			(stroke
				(width 0.15)
				(type solid)
			)
			(fill no)
			(layer "B.Fab")
		)
		(pad "1" smd roundrect
			(at -0.48 0 270)
			(size 0.59 0.64)
			(layers "B.Cu" "B.Mask" "B.Paste")
			(roundrect_rratio 0.25)
			(net 520 "/FPGA Bank 18 & 32/ETH_RMII.RXD1")
			(pintype "passive")
		)
		(pad "2" smd roundrect
			(at 0.48 0 270)
			(size 0.59 0.64)
			(layers "B.Cu" "B.Mask" "B.Paste")
			(roundrect_rratio 0.25)
			(net 945 "/HDMI + Ethernet/ETH_PHY_RXD1")
			(pintype "passive")
		)
	)
	(footprint "antmicro-footprints:C_0402_1005Metric"
		(layer "B.Cu")
		(at 196.325 125.825)
		(descr "Capacitor SMD 0402")
		(tags "capacitor SMD 0402")
		(property "Reference" "C116"
			(at 25.375 -29.325 180)
			(layer "B.SilkS")
			(effects
				(font
					(size 0.7 0.7)
					(thickness 0.15)
				)
				(justify left bottom mirror)
			)
		)
		(property "Value" "C_100n_0402"
			(at 0 -1.169 180)
			(layer "B.Fab")
			(effects
				(font
					(size 0.7 0.7)
					(thickness 0.15)
				)
				(justify left bottom mirror)
			)
		)
		(property "Description" "SMD Multilayer Ceramic Capacitor, 0.1 µF, 50 V, 0402 [1005 Metric], ± 10%, X5R, GRM Series"
			(at 0 0 0)
			(layer "F.Fab")
			(hide yes)
			(effects
				(font
					(size 1.27 1.27)
					(thickness 0.15)
				)
			)
		)
		(property "Author" "Antmicro"
			(at 0 0 0)
			(layer "B.Fab")
			(hide yes)
			(effects
				(font
					(size 1 1)
					(thickness 0.15)
				)
				(justify mirror)
			)
		)
		(property "Dielectric" "X5R"
			(at 0 0 0)
			(layer "B.Fab")
			(hide yes)
			(effects
				(font
					(size 1 1)
					(thickness 0.15)
				)
				(justify mirror)
			)
		)
		(property "License" "Apache-2.0"
			(at 0 0 0)
			(layer "B.Fab")
			(hide yes)
			(effects
				(font
					(size 1 1)
					(thickness 0.15)
				)
				(justify mirror)
			)
		)
		(property "MPN" "GRM155R61H104KE14D"
			(at 0 0 0)
			(layer "B.Fab")
			(hide yes)
			(effects
				(font
					(size 1 1)
					(thickness 0.15)
				)
				(justify mirror)
			)
		)
		(property "Manufacturer" "Murata"
			(at 0 0 0)
			(layer "B.Fab")
			(hide yes)
			(effects
				(font
					(size 1 1)
					(thickness 0.15)
				)
				(justify mirror)
			)
		)
		(property "Val" "100n"
			(at 0 0 0)
			(layer "B.Fab")
			(hide yes)
			(effects
				(font
					(size 1 1)
					(thickness 0.15)
				)
				(justify mirror)
			)
		)
		(property "Voltage" "50V"
			(at 0 0 0)
			(layer "B.Fab")
			(hide yes)
			(effects
				(font
					(size 1 1)
					(thickness 0.15)
				)
				(justify mirror)
			)
		)
		(sheetname "FPGA supply")
		(sheetfile "fpga-supply.kicad_sch")
		(attr smd)
		(fp_rect
			(start -0.925 0.47)
			(end 0.925 -0.47)
			(stroke
				(width 0.05)
				(type default)
			)
			(fill no)
			(layer "B.CrtYd")
		)
		(fp_line
			(start -0.494 -0.248)
			(end -0.494 0.25)
			(stroke
				(width 0.15)
				(type solid)
			)
			(layer "B.Fab")
		)
		(fp_line
			(start -0.494 0.25)
			(end 0.504 0.25)
			(stroke
				(width 0.15)
				(type solid)
			)
			(layer "B.Fab")
		)
		(fp_line
			(start 0.504 -0.248)
			(end -0.494 -0.248)
			(stroke
				(width 0.15)
				(type solid)
			)
			(layer "B.Fab")
		)
		(fp_line
			(start 0.504 0.25)
			(end 0.504 -0.248)
			(stroke
				(width 0.15)
				(type solid)
			)
			(layer "B.Fab")
		)
		(pad "1" smd roundrect
			(at -0.48 0)
			(size 0.59 0.64)
			(layers "B.Cu" "B.Mask" "B.Paste")
			(roundrect_rratio 0.25)
			(net 1 "GND")
			(pintype "passive")
		)
		(pad "2" smd roundrect
			(at 0.48 0)
			(size 0.59 0.64)
			(layers "B.Cu" "B.Mask" "B.Paste")
			(roundrect_rratio 0.25)
			(net 650 "+1V0")
			(pintype "passive")
		)
	)
	(footprint "antmicro-footprints:LED_0603_1608Metric_R"
		(layer "B.Cu")
		(at 268.301 145.35 180)
		(descr "LED SMD 0603 Red")
		(tags "LED SMD 0603 Red")
		(property "Reference" "D13"
			(at 4.101 -0.4 0)
			(layer "B.SilkS")
			(effects
				(font
					(size 0.7 0.7)
					(thickness 0.15)
				)
				(justify left bottom mirror)
			)
		)
		(property "Value" "LED_R_0603_KP-1608EC"
			(at 0 -1.6 0)
			(layer "B.Fab")
			(effects
				(font
					(size 0.7 0.7)
					(thickness 0.15)
				)
				(justify left bottom mirror)
			)
		)
		(property "Description" "LED, Red, SMD, 0603, 30 mA, 2 V, 617 nm"
			(at 0 0 180)
			(layer "F.Fab")
			(hide yes)
			(effects
				(font
					(size 1.27 1.27)
					(thickness 0.15)
				)
			)
		)
		(property "Author" "Antmicro"
			(at 536.602 290.7 0)
			(layer "B.Fab")
			(hide yes)
			(effects
				(font
					(size 1 1)
					(thickness 0.15)
				)
				(justify mirror)
			)
		)
		(property "Color" "Red"
			(at 536.602 290.7 0)
			(layer "B.Fab")
			(hide yes)
			(effects
				(font
					(size 1 1)
					(thickness 0.15)
				)
				(justify mirror)
			)
		)
		(property "License" "Apache-2.0"
			(at 536.602 290.7 0)
			(layer "B.Fab")
			(hide yes)
			(effects
				(font
					(size 1 1)
					(thickness 0.15)
				)
				(justify mirror)
			)
		)
		(property "MPN" "KP-1608EC"
			(at 536.602 290.7 0)
			(layer "B.Fab")
			(hide yes)
			(effects
				(font
					(size 1 1)
					(thickness 0.15)
				)
				(justify mirror)
			)
		)
		(property "Manufacturer" "Kingbright"
			(at 536.602 290.7 0)
			(layer "B.Fab")
			(hide yes)
			(effects
				(font
					(size 1 1)
					(thickness 0.15)
				)
				(justify mirror)
			)
		)
		(property "Public" "False"
			(at 536.602 290.7 0)
			(layer "B.Fab")
			(hide yes)
			(effects
				(font
					(size 1 1)
					(thickness 0.15)
				)
				(justify mirror)
			)
		)
		(sheetname "Power supply")
		(sheetfile "power-supply.kicad_sch")
		(attr smd)
		(fp_line
			(start 0.22 0.35)
			(end -0.22 0.35)
			(stroke
				(width 0.15)
				(type solid)
			)
			(layer "B.SilkS")
		)
		(fp_line
			(start 0.22 -0.35)
			(end -0.22 -0.35)
			(stroke
				(width 0.15)
				(type solid)
			)
			(layer "B.SilkS")
		)
		(fp_line
			(start 0.105328 -0.001008)
			(end 0.24 -0.001)
			(stroke
				(width 0.1)
				(type solid)
			)
			(layer "B.SilkS")
		)
		(fp_line
			(start 0.105328 -0.201008)
			(end 0.105328 0.198992)
			(stroke
				(width 0.1)
				(type solid)
			)
			(layer "B.SilkS")
		)
		(fp_line
			(start 0.105328 -0.201008)
			(end -0.094672 -0.001008)
			(stroke
				(width 0.1)
				(type solid)
			)
			(layer "B.SilkS")
		)
		(fp_line
			(start -0.094672 -0.001008)
			(end 0.105328 0.198992)
			(stroke
				(width 0.1)
				(type solid)
			)
			(layer "B.SilkS")
		)
		(fp_line
			(start -0.094672 -0.001008)
			(end -0.24 -0.001008)
			(stroke
				(width 0.1)
				(type solid)
			)
			(layer "B.SilkS")
		)
		(fp_line
			(start -0.094672 -0.201008)
			(end -0.094672 0.198992)
			(stroke
				(width 0.1)
				(type solid)
			)
			(layer "B.SilkS")
		)
		(fp_line
			(start -1.18 0.319)
			(end -1.18 -0.321)
			(stroke
				(width 0.15)
				(type solid)
			)
			(layer "B.SilkS")
		)
		(fp_rect
			(start 1.25 -0.65)
			(end -1.25 0.65)
			(stroke
				(width 0.05)
				(type solid)
			)
			(fill no)
			(layer "B.CrtYd")
		)
		(fp_line
			(start 0.599 0)
			(end 0.201 0)
			(stroke
				(width 0.15)
				(type solid)
			)
			(layer "B.Fab")
		)
		(fp_line
			(start 0.201 0.202)
			(end -0.101 0)
			(stroke
				(width 0.15)
				(type solid)
			)
			(layer "B.Fab")
		)
		(fp_line
			(start 0.201 0)
			(end 0.201 0.202)
			(stroke
				(width 0.15)
				(type solid)
			)
			(layer "B.Fab")
		)
		(fp_line
			(start 0.201 -0.2)
			(end 0.201 0)
			(stroke
				(width 0.15)
				(type solid)
			)
			(layer "B.Fab")
		)
		(fp_line
			(start -0.101 0)
			(end 0.201 -0.2)
			(stroke
				(width 0.15)
				(type solid)
			)
			(layer "B.Fab")
		)
		(fp_line
			(start -0.199 0.202)
			(end -0.199 -0.1)
			(stroke
				(width 0.15)
				(type solid)
			)
			(layer "B.Fab")
		)
		(fp_line
			(start -0.199 0)
			(end -0.597 0)
			(stroke
				(width 0.15)
				(type solid)
			)
			(layer "B.Fab")
		)
		(fp_line
			(start -0.199 -0.2)
			(end -0.199 -0.1)
			(stroke
				(width 0.15)
				(type solid)
			)
			(layer "B.Fab")
		)
		(fp_rect
			(start 0.848 -0.4)
			(end -0.85 0.402)
			(stroke
				(width 0.15)
				(type solid)
			)
			(fill no)
			(layer "B.Fab")
		)
		(pad "1" smd roundrect
			(at -0.7 0)
			(size 0.8 1)
			(layers "B.Cu" "B.Mask" "B.Paste")
			(roundrect_rratio 0.2)
			(net 1 "GND")
			(pinfunction "C")
			(pintype "passive")
		)
		(pad "2" smd roundrect
			(at 0.7 0)
			(size 0.8 1)
			(layers "B.Cu" "B.Mask" "B.Paste")
			(roundrect_rratio 0.2)
			(net 20 "Net-(D13-A)")
			(pinfunction "A")
			(pintype "passive")
		)
	)
	(footprint "antmicro-footprints:C_0402_1005Metric"
		(layer "B.Cu")
		(at 212 126.52 180)
		(descr "Capacitor SMD 0402")
		(tags "capacitor SMD 0402")
		(property "Reference" "C26"
			(at -1.075 0.45 0)
			(layer "B.SilkS")
			(effects
				(font
					(size 0.7 0.7)
					(thickness 0.15)
				)
				(justify left bottom mirror)
			)
		)
		(property "Value" "C_100n_0402"
			(at 0 -1.169 0)
			(layer "B.Fab")
			(effects
				(font
					(size 0.7 0.7)
					(thickness 0.15)
				)
				(justify left bottom mirror)
			)
		)
		(property "Description" "SMD Multilayer Ceramic Capacitor, 0.1 µF, 50 V, 0402 [1005 Metric], ± 10%, X5R, GRM Series"
			(at 0 0 180)
			(layer "F.Fab")
			(hide yes)
			(effects
				(font
					(size 1.27 1.27)
					(thickness 0.15)
				)
			)
		)
		(property "Author" "Antmicro"
			(at 424 253.04 0)
			(layer "B.Fab")
			(hide yes)
			(effects
				(font
					(size 1 1)
					(thickness 0.15)
				)
				(justify mirror)
			)
		)
		(property "Dielectric" "X5R"
			(at 424 253.04 0)
			(layer "B.Fab")
			(hide yes)
			(effects
				(font
					(size 1 1)
					(thickness 0.15)
				)
				(justify mirror)
			)
		)
		(property "License" "Apache-2.0"
			(at 424 253.04 0)
			(layer "B.Fab")
			(hide yes)
			(effects
				(font
					(size 1 1)
					(thickness 0.15)
				)
				(justify mirror)
			)
		)
		(property "MPN" "GRM155R61H104KE14D"
			(at 424 253.04 0)
			(layer "B.Fab")
			(hide yes)
			(effects
				(font
					(size 1 1)
					(thickness 0.15)
				)
				(justify mirror)
			)
		)
		(property "Manufacturer" "Murata"
			(at 424 253.04 0)
			(layer "B.Fab")
			(hide yes)
			(effects
				(font
					(size 1 1)
					(thickness 0.15)
				)
				(justify mirror)
			)
		)
		(property "Val" "100n"
			(at 424 253.04 0)
			(layer "B.Fab")
			(hide yes)
			(effects
				(font
					(size 1 1)
					(thickness 0.15)
				)
				(justify mirror)
			)
		)
		(property "Voltage" "50V"
			(at 424 253.04 0)
			(layer "B.Fab")
			(hide yes)
			(effects
				(font
					(size 1 1)
					(thickness 0.15)
				)
				(justify mirror)
			)
		)
		(sheetname "FPGA Bank 14 & 15")
		(sheetfile "fpga-bank-14-15.kicad_sch")
		(attr smd)
		(fp_rect
			(start -0.925 0.47)
			(end 0.925 -0.47)
			(stroke
				(width 0.05)
				(type default)
			)
			(fill no)
			(layer "B.CrtYd")
		)
		(fp_line
			(start 0.504 0.25)
			(end 0.504 -0.248)
			(stroke
				(width 0.15)
				(type solid)
			)
			(layer "B.Fab")
		)
		(fp_line
			(start 0.504 -0.248)
			(end -0.494 -0.248)
			(stroke
				(width 0.15)
				(type solid)
			)
			(layer "B.Fab")
		)
		(fp_line
			(start -0.494 0.25)
			(end 0.504 0.25)
			(stroke
				(width 0.15)
				(type solid)
			)
			(layer "B.Fab")
		)
		(fp_line
			(start -0.494 -0.248)
			(end -0.494 0.25)
			(stroke
				(width 0.15)
				(type solid)
			)
			(layer "B.Fab")
		)
		(pad "1" smd roundrect
			(at -0.48 0 180)
			(size 0.59 0.64)
			(layers "B.Cu" "B.Mask" "B.Paste")
			(roundrect_rratio 0.25)
			(net 1 "GND")
			(pintype "passive")
		)
		(pad "2" smd roundrect
			(at 0.48 0 180)
			(size 0.59 0.64)
			(layers "B.Cu" "B.Mask" "B.Paste")
			(roundrect_rratio 0.25)
			(net 2 "VCC_USR_A")
			(pintype "passive")
		)
	)
	(footprint "antmicro-footprints:R_0402_1005Metric"
		(layer "B.Cu")
		(at 266.001 127.7 180)
		(descr "Resistor SMD 0402")
		(tags "resistor SMD 0402")
		(property "Reference" "R170"
			(at 0.901 -0.7 0)
			(layer "B.SilkS")
			(effects
				(font
					(size 0.7 0.7)
					(thickness 0.15)
				)
				(justify left bottom mirror)
			)
		)
		(property "Value" "R_15k_0402"
			(at 0 -1.4 0)
			(layer "B.Fab")
			(effects
				(font
					(size 0.7 0.7)
					(thickness 0.15)
				)
				(justify left bottom mirror)
			)
		)
		(property "Description" "SMD Chip Resistor, 15 kohm, ± 1%, 62.5 mW, 0402 [1005 Metric], Thick Film, General Purpose"
			(at 0 0 180)
			(layer "F.Fab")
			(hide yes)
			(effects
				(font
					(size 1.27 1.27)
					(thickness 0.15)
				)
			)
		)
		(property "Author" "Antmicro"
			(at 532.002 255.4 0)
			(layer "B.Fab")
			(hide yes)
			(effects
				(font
					(size 1 1)
					(thickness 0.15)
				)
				(justify mirror)
			)
		)
		(property "DNP" "DNP"
			(at 532.002 255.4 0)
			(layer "B.Fab")
			(hide yes)
			(effects
				(font
					(size 1 1)
					(thickness 0.15)
				)
				(justify mirror)
			)
		)
		(property "License" "Apache-2.0"
			(at 532.002 255.4 0)
			(layer "B.Fab")
			(hide yes)
			(effects
				(font
					(size 1 1)
					(thickness 0.15)
				)
				(justify mirror)
			)
		)
		(property "MPN" "CR0402-FX-1502GLF"
			(at 532.002 255.4 0)
			(layer "B.Fab")
			(hide yes)
			(effects
				(font
					(size 1 1)
					(thickness 0.15)
				)
				(justify mirror)
			)
		)
		(property "Manufacturer" "Bourns"
			(at 532.002 255.4 0)
			(layer "B.Fab")
			(hide yes)
			(effects
				(font
					(size 1 1)
					(thickness 0.15)
				)
				(justify mirror)
			)
		)
		(property "Tolerance" "1%"
			(at 532.002 255.4 0)
			(layer "B.Fab")
			(hide yes)
			(effects
				(font
					(size 1 1)
					(thickness 0.15)
				)
				(justify mirror)
			)
		)
		(property "Val" "15k"
			(at 532.002 255.4 0)
			(layer "B.Fab")
			(hide yes)
			(effects
				(font
					(size 1 1)
					(thickness 0.15)
				)
				(justify mirror)
			)
		)
		(property "dnp" ""
			(at 532.002 255.4 0)
			(layer "B.Fab")
			(hide yes)
			(effects
				(font
					(size 1 1)
					(thickness 0.15)
				)
				(justify mirror)
			)
		)
		(property "exclude_from_bom" ""
			(at 532.002 255.4 0)
			(layer "B.Fab")
			(hide yes)
			(effects
				(font
					(size 1 1)
					(thickness 0.15)
				)
				(justify mirror)
			)
		)
		(sheetname "USB PHY")
		(sheetfile "usb-phy.kicad_sch")
		(attr smd exclude_from_bom)
		(fp_rect
			(start -0.925 0.47)
			(end 0.925 -0.47)
			(stroke
				(width 0.05)
				(type default)
			)
			(fill no)
			(layer "B.CrtYd")
		)
		(fp_rect
			(start -0.5 0.25)
			(end 0.5 -0.25)
			(stroke
				(width 0.15)
				(type solid)
			)
			(fill no)
			(layer "B.Fab")
		)
		(pad "1" smd roundrect
			(at -0.48 0 180)
			(size 0.59 0.64)
			(layers "B.Cu" "B.Mask" "B.Paste")
			(roundrect_rratio 0.25)
			(net 1 "GND")
			(pintype "passive")
		)
		(pad "2" smd roundrect
			(at 0.48 0 180)
			(size 0.59 0.64)
			(layers "B.Cu" "B.Mask" "B.Paste")
			(roundrect_rratio 0.25)
			(net 843 "/USB PHY/USB_USR_CONN_D-")
			(pintype "passive")
		)
	)
	(footprint "antmicro-footprints:C_0402_1005Metric"
		(layer "B.Cu")
		(at 193.25 130.75 90)
		(descr "Capacitor SMD 0402")
		(tags "capacitor SMD 0402")
		(property "Reference" "C16"
			(at 29.55 23 270)
			(layer "B.SilkS")
			(effects
				(font
					(size 0.7 0.7)
					(thickness 0.15)
				)
				(justify left bottom mirror)
			)
		)
		(property "Value" "C_100n_0402"
			(at 0 -1.169 270)
			(layer "B.Fab")
			(effects
				(font
					(size 0.7 0.7)
					(thickness 0.15)
				)
				(justify left bottom mirror)
			)
		)
		(property "Description" "SMD Multilayer Ceramic Capacitor, 0.1 µF, 50 V, 0402 [1005 Metric], ± 10%, X5R, GRM Series"
			(at 0 0 90)
			(layer "F.Fab")
			(hide yes)
			(effects
				(font
					(size 1.27 1.27)
					(thickness 0.15)
				)
			)
		)
		(property "Author" "Antmicro"
			(at 324 -62.5 0)
			(layer "B.Fab")
			(hide yes)
			(effects
				(font
					(size 1 1)
					(thickness 0.15)
				)
				(justify mirror)
			)
		)
		(property "Dielectric" "X5R"
			(at 324 -62.5 0)
			(layer "B.Fab")
			(hide yes)
			(effects
				(font
					(size 1 1)
					(thickness 0.15)
				)
				(justify mirror)
			)
		)
		(property "License" "Apache-2.0"
			(at 324 -62.5 0)
			(layer "B.Fab")
			(hide yes)
			(effects
				(font
					(size 1 1)
					(thickness 0.15)
				)
				(justify mirror)
			)
		)
		(property "MPN" "GRM155R61H104KE14D"
			(at 324 -62.5 0)
			(layer "B.Fab")
			(hide yes)
			(effects
				(font
					(size 1 1)
					(thickness 0.15)
				)
				(justify mirror)
			)
		)
		(property "Manufacturer" "Murata"
			(at 324 -62.5 0)
			(layer "B.Fab")
			(hide yes)
			(effects
				(font
					(size 1 1)
					(thickness 0.15)
				)
				(justify mirror)
			)
		)
		(property "Val" "100n"
			(at 324 -62.5 0)
			(layer "B.Fab")
			(hide yes)
			(effects
				(font
					(size 1 1)
					(thickness 0.15)
				)
				(justify mirror)
			)
		)
		(property "Voltage" "50V"
			(at 324 -62.5 0)
			(layer "B.Fab")
			(hide yes)
			(effects
				(font
					(size 1 1)
					(thickness 0.15)
				)
				(justify mirror)
			)
		)
		(sheetname "FPGA Config")
		(sheetfile "fpga-config.kicad_sch")
		(attr smd)
		(fp_rect
			(start -0.925 0.47)
			(end 0.925 -0.47)
			(stroke
				(width 0.05)
				(type default)
			)
			(fill no)
			(layer "B.CrtYd")
		)
		(fp_line
			(start 0.504 -0.248)
			(end -0.494 -0.248)
			(stroke
				(width 0.15)
				(type solid)
			)
			(layer "B.Fab")
		)
		(fp_line
			(start -0.494 -0.248)
			(end -0.494 0.25)
			(stroke
				(width 0.15)
				(type solid)
			)
			(layer "B.Fab")
		)
		(fp_line
			(start 0.504 0.25)
			(end 0.504 -0.248)
			(stroke
				(width 0.15)
				(type solid)
			)
			(layer "B.Fab")
		)
		(fp_line
			(start -0.494 0.25)
			(end 0.504 0.25)
			(stroke
				(width 0.15)
				(type solid)
			)
			(layer "B.Fab")
		)
		(pad "1" smd roundrect
			(at -0.48 0 90)
			(size 0.59 0.64)
			(layers "B.Cu" "B.Mask" "B.Paste")
			(roundrect_rratio 0.25)
			(net 1 "GND")
			(pintype "passive")
		)
		(pad "2" smd roundrect
			(at 0.48 0 90)
			(size 0.59 0.64)
			(layers "B.Cu" "B.Mask" "B.Paste")
			(roundrect_rratio 0.25)
			(net 24 "+3V3")
			(pintype "passive")
		)
	)
	(footprint "antmicro-footprints:C_0402_1005Metric"
		(layer "B.Cu")
		(at 268.001 127.7)
		(descr "Capacitor SMD 0402")
		(tags "capacitor SMD 0402")
		(property "Reference" "C393"
			(at -1.201 1.275 0)
			(layer "B.SilkS")
			(effects
				(font
					(size 0.7 0.7)
					(thickness 0.15)
				)
				(justify right bottom mirror)
			)
		)
		(property "Value" "C_100n_0402"
			(at 0 -1.4 0)
			(layer "B.Fab")
			(effects
				(font
					(size 0.7 0.7)
					(thickness 0.15)
				)
				(justify right bottom mirror)
			)
		)
		(property "Description" "SMD Multilayer Ceramic Capacitor, 0.1 µF, 50 V, 0402 [1005 Metric], ± 10%, X5R, GRM Series"
			(at 0 0 0)
			(layer "F.Fab")
			(hide yes)
			(effects
				(font
					(size 1.27 1.27)
					(thickness 0.15)
				)
			)
		)
		(property "Author" "Antmicro"
			(at 0 0 0)
			(layer "B.Fab")
			(hide yes)
			(effects
				(font
					(size 1 1)
					(thickness 0.15)
				)
				(justify mirror)
			)
		)
		(property "Dielectric" "X5R"
			(at 0 0 0)
			(layer "B.Fab")
			(hide yes)
			(effects
				(font
					(size 1 1)
					(thickness 0.15)
				)
				(justify mirror)
			)
		)
		(property "License" "Apache-2.0"
			(at 0 0 0)
			(layer "B.Fab")
			(hide yes)
			(effects
				(font
					(size 1 1)
					(thickness 0.15)
				)
				(justify mirror)
			)
		)
		(property "MPN" "GRM155R61H104KE14D"
			(at 0 0 0)
			(layer "B.Fab")
			(hide yes)
			(effects
				(font
					(size 1 1)
					(thickness 0.15)
				)
				(justify mirror)
			)
		)
		(property "Manufacturer" "Murata"
			(at 0 0 0)
			(layer "B.Fab")
			(hide yes)
			(effects
				(font
					(size 1 1)
					(thickness 0.15)
				)
				(justify mirror)
			)
		)
		(property "Val" "100n"
			(at 0 0 0)
			(layer "B.Fab")
			(hide yes)
			(effects
				(font
					(size 1 1)
					(thickness 0.15)
				)
				(justify mirror)
			)
		)
		(property "Voltage" "50V"
			(at 0 0 0)
			(layer "B.Fab")
			(hide yes)
			(effects
				(font
					(size 1 1)
					(thickness 0.15)
				)
				(justify mirror)
			)
		)
		(sheetname "SPI Flash + SD Card")
		(sheetfile "spi-flash.kicad_sch")
		(attr smd)
		(fp_rect
			(start -0.925 0.47)
			(end 0.925 -0.47)
			(stroke
				(width 0.05)
				(type default)
			)
			(fill no)
			(layer "B.CrtYd")
		)
		(fp_line
			(start -0.494 -0.248)
			(end -0.494 0.25)
			(stroke
				(width 0.15)
				(type solid)
			)
			(layer "B.Fab")
		)
		(fp_line
			(start -0.494 0.25)
			(end 0.504 0.25)
			(stroke
				(width 0.15)
				(type solid)
			)
			(layer "B.Fab")
		)
		(fp_line
			(start 0.504 -0.248)
			(end -0.494 -0.248)
			(stroke
				(width 0.15)
				(type solid)
			)
			(layer "B.Fab")
		)
		(fp_line
			(start 0.504 0.25)
			(end 0.504 -0.248)
			(stroke
				(width 0.15)
				(type solid)
			)
			(layer "B.Fab")
		)
		(pad "1" smd roundrect
			(at -0.48 0)
			(size 0.59 0.64)
			(layers "B.Cu" "B.Mask" "B.Paste")
			(roundrect_rratio 0.25)
			(net 1 "GND")
			(pintype "passive")
		)
		(pad "2" smd roundrect
			(at 0.48 0)
			(size 0.59 0.64)
			(layers "B.Cu" "B.Mask" "B.Paste")
			(roundrect_rratio 0.25)
			(net 16 "Net-(J23-SHIELD)")
			(pintype "passive")
		)
	)
	(footprint "antmicro-footprints:R_0402_1005Metric"
		(layer "B.Cu")
		(at 242.501 134.9)
		(descr "Resistor SMD 0402")
		(tags "resistor SMD 0402")
		(property "Reference" "R162"
			(at -0.751 0.4 180)
			(layer "B.SilkS")
			(effects
				(font
					(size 0.7 0.7)
					(thickness 0.15)
				)
				(justify left bottom mirror)
			)
		)
		(property "Value" "R_33R_0402"
			(at 0 -1.4 180)
			(layer "B.Fab")
			(effects
				(font
					(size 0.7 0.7)
					(thickness 0.15)
				)
				(justify left bottom mirror)
			)
		)
		(property "Description" "SMD Chip Resistor, 33 ohm, ± 1%, 62.5 mW, 0402 [1005 Metric], Thick Film, General Purpose"
			(at 0 0 0)
			(layer "F.Fab")
			(hide yes)
			(effects
				(font
					(size 1.27 1.27)
					(thickness 0.15)
				)
			)
		)
		(property "Author" "Antmicro"
			(at 0 0 0)
			(layer "B.Fab")
			(hide yes)
			(effects
				(font
					(size 1 1)
					(thickness 0.15)
				)
				(justify mirror)
			)
		)
		(property "License" "Apache-2.0"
			(at 0 0 0)
			(layer "B.Fab")
			(hide yes)
			(effects
				(font
					(size 1 1)
					(thickness 0.15)
				)
				(justify mirror)
			)
		)
		(property "MPN" "CR0402-FX-33R0GLF"
			(at 0 0 0)
			(layer "B.Fab")
			(hide yes)
			(effects
				(font
					(size 1 1)
					(thickness 0.15)
				)
				(justify mirror)
			)
		)
		(property "Manufacturer" "Bourns"
			(at 0 0 0)
			(layer "B.Fab")
			(hide yes)
			(effects
				(font
					(size 1 1)
					(thickness 0.15)
				)
				(justify mirror)
			)
		)
		(property "Tolerance" "1%"
			(at 0 0 0)
			(layer "B.Fab")
			(hide yes)
			(effects
				(font
					(size 1 1)
					(thickness 0.15)
				)
				(justify mirror)
			)
		)
		(property "Val" "33R"
			(at 0 0 0)
			(layer "B.Fab")
			(hide yes)
			(effects
				(font
					(size 1 1)
					(thickness 0.15)
				)
				(justify mirror)
			)
		)
		(sheetname "USB PHY")
		(sheetfile "usb-phy.kicad_sch")
		(attr smd)
		(fp_rect
			(start -0.925 0.47)
			(end 0.925 -0.47)
			(stroke
				(width 0.05)
				(type default)
			)
			(fill no)
			(layer "B.CrtYd")
		)
		(fp_rect
			(start -0.5 0.25)
			(end 0.5 -0.25)
			(stroke
				(width 0.15)
				(type solid)
			)
			(fill no)
			(layer "B.Fab")
		)
		(pad "1" smd roundrect
			(at -0.48 0)
			(size 0.59 0.64)
			(layers "B.Cu" "B.Mask" "B.Paste")
			(roundrect_rratio 0.25)
			(net 922 "/USB PHY/FTDI_UART0_RX")
			(pintype "passive")
		)
		(pad "2" smd roundrect
			(at 0.48 0)
			(size 0.59 0.64)
			(layers "B.Cu" "B.Mask" "B.Paste")
			(roundrect_rratio 0.25)
			(net 55 "/FPGA Bank 12 & 13/UART0.TX")
			(pintype "passive")
		)
	)
	(footprint "antmicro-footprints:R_0402_1005Metric"
		(layer "B.Cu")
		(at 240.199999 84.699999 -90)
		(descr "Resistor SMD 0402")
		(tags "resistor SMD 0402")
		(property "Reference" "R117"
			(at 0.750001 -0.425001 90)
			(layer "B.SilkS")
			(effects
				(font
					(size 0.7 0.7)
					(thickness 0.15)
				)
				(justify left bottom mirror)
			)
		)
		(property "Value" "R_100R_0402"
			(at 0 -1.4 90)
			(layer "B.Fab")
			(effects
				(font
					(size 0.7 0.7)
					(thickness 0.15)
				)
				(justify left bottom mirror)
			)
		)
		(property "Description" "SMD Chip Resistor, 100 ohm, ± 1%, 62.5 mW, 0402 [1005 Metric], Thick Film, General Purpose"
			(at 0 0 270)
			(layer "F.Fab")
			(hide yes)
			(effects
				(font
					(size 1.27 1.27)
					(thickness 0.15)
				)
			)
		)
		(property "Author" "Antmicro"
			(at 155.5 324.899998 0)
			(layer "B.Fab")
			(hide yes)
			(effects
				(font
					(size 1 1)
					(thickness 0.15)
				)
				(justify mirror)
			)
		)
		(property "License" "Apache-2.0"
			(at 155.5 324.899998 0)
			(layer "B.Fab")
			(hide yes)
			(effects
				(font
					(size 1 1)
					(thickness 0.15)
				)
				(justify mirror)
			)
		)
		(property "MPN" "CR0402-FX-1000GLF"
			(at 155.5 324.899998 0)
			(layer "B.Fab")
			(hide yes)
			(effects
				(font
					(size 1 1)
					(thickness 0.15)
				)
				(justify mirror)
			)
		)
		(property "Manufacturer" "Bourns"
			(at 155.5 324.899998 0)
			(layer "B.Fab")
			(hide yes)
			(effects
				(font
					(size 1 1)
					(thickness 0.15)
				)
				(justify mirror)
			)
		)
		(property "Tolerance" "1%"
			(at 155.5 324.899998 0)
			(layer "B.Fab")
			(hide yes)
			(effects
				(font
					(size 1 1)
					(thickness 0.15)
				)
				(justify mirror)
			)
		)
		(property "Val" "100R"
			(at 155.5 324.899998 0)
			(layer "B.Fab")
			(hide yes)
			(effects
				(font
					(size 1 1)
					(thickness 0.15)
				)
				(justify mirror)
			)
		)
		(sheetname "User GPIO + LED + button + DIP switch")
		(sheetfile "user-gpio.kicad_sch")
		(attr smd)
		(fp_rect
			(start -0.925 0.47)
			(end 0.925 -0.47)
			(stroke
				(width 0.05)
				(type default)
			)
			(fill no)
			(layer "B.CrtYd")
		)
		(fp_rect
			(start -0.5 0.25)
			(end 0.5 -0.25)
			(stroke
				(width 0.15)
				(type solid)
			)
			(fill no)
			(layer "B.Fab")
		)
		(pad "1" smd roundrect
			(at -0.48 0 270)
			(size 0.59 0.64)
			(layers "B.Cu" "B.Mask" "B.Paste")
			(roundrect_rratio 0.25)
			(net 814 "/User GPIO + LED + button + DIP switch/PMOD_B_8")
			(pintype "passive")
		)
		(pad "2" smd roundrect
			(at 0.48 0 270)
			(size 0.59 0.64)
			(layers "B.Cu" "B.Mask" "B.Paste")
			(roundrect_rratio 0.25)
			(net 451 "/FPGA Bank 12 & 13/PMOD_B.IO8")
			(pintype "passive")
		)
	)
	(footprint "antmicro-footprints:C_0201"
		(layer "B.Cu")
		(at 201.5 131.25)
		(descr "Capacitor SMD 0201")
		(tags "capacitor SMD 0201")
		(property "Reference" "C127"
			(at 24.375 -28.65 0)
			(layer "B.SilkS")
			(effects
				(font
					(size 0.7 0.7)
					(thickness 0.15)
				)
				(justify right bottom mirror)
			)
		)
		(property "Value" "C_100n_0201"
			(at 0 -1.4 0)
			(layer "B.Fab")
			(effects
				(font
					(size 0.7 0.7)
					(thickness 0.15)
				)
				(justify right bottom mirror)
			)
		)
		(property "Description" "SMD Multilayer Ceramic Capacitor, 0.1 µF, 6.3 V, 0201 [0603 Metric], ± 10%, X6S, CC Series"
			(at 0 0 0)
			(layer "F.Fab")
			(hide yes)
			(effects
				(font
					(size 1.27 1.27)
					(thickness 0.15)
				)
			)
		)
		(property "Author" "Antmicro"
			(at 0 0 0)
			(layer "B.Fab")
			(hide yes)
			(effects
				(font
					(size 1 1)
					(thickness 0.15)
				)
				(justify mirror)
			)
		)
		(property "Dielectric" ""
			(at 0 0 0)
			(layer "B.Fab")
			(hide yes)
			(effects
				(font
					(size 1 1)
					(thickness 0.15)
				)
				(justify mirror)
			)
		)
		(property "License" "Apache-2.0"
			(at 0 0 0)
			(layer "B.Fab")
			(hide yes)
			(effects
				(font
					(size 1 1)
					(thickness 0.15)
				)
				(justify mirror)
			)
		)
		(property "MPN" "CC0201KRX6S5BB104"
			(at 0 0 0)
			(layer "B.Fab")
			(hide yes)
			(effects
				(font
					(size 1 1)
					(thickness 0.15)
				)
				(justify mirror)
			)
		)
		(property "Manufacturer" "YAGEO"
			(at 0 0 0)
			(layer "B.Fab")
			(hide yes)
			(effects
				(font
					(size 1 1)
					(thickness 0.15)
				)
				(justify mirror)
			)
		)
		(property "Val" "100n"
			(at 0 0 0)
			(layer "B.Fab")
			(hide yes)
			(effects
				(font
					(size 1 1)
					(thickness 0.15)
				)
				(justify mirror)
			)
		)
		(property "Voltage" ""
			(at 0 0 0)
			(layer "B.Fab")
			(hide yes)
			(effects
				(font
					(size 1 1)
					(thickness 0.15)
				)
				(justify mirror)
			)
		)
		(sheetname "FPGA supply")
		(sheetfile "fpga-supply.kicad_sch")
		(attr smd)
		(fp_rect
			(start -0.7 0.35)
			(end 0.7 -0.35)
			(stroke
				(width 0.05)
				(type default)
			)
			(fill no)
			(layer "B.CrtYd")
		)
		(fp_rect
			(start 0.3 -0.15)
			(end -0.301 0.149)
			(stroke
				(width 0.15)
				(type solid)
			)
			(fill no)
			(layer "B.Fab")
		)
		(pad "" smd roundrect
			(at -0.349 0.002)
			(size 0.318 0.36)
			(layers "B.Paste")
			(roundrect_rratio 0.25)
		)
		(pad "" smd roundrect
			(at 0.341 0.002)
			(size 0.318 0.36)
			(layers "B.Paste")
			(roundrect_rratio 0.25)
		)
		(pad "1" smd roundrect
			(at -0.321 0.002)
			(size 0.46 0.4)
			(layers "B.Cu" "B.Mask")
			(roundrect_rratio 0.25)
			(net 1 "GND")
			(pintype "passive")
		)
		(pad "2" smd roundrect
			(at 0.32 0.002)
			(size 0.46 0.4)
			(layers "B.Cu" "B.Mask")
			(roundrect_rratio 0.25)
			(net 650 "+1V0")
			(pintype "passive")
		)
	)
	(footprint "antmicro-footprints:R_0402_1005Metric"
		(layer "B.Cu")
		(at 221.715 148.2)
		(descr "Resistor SMD 0402")
		(tags "resistor SMD 0402")
		(property "Reference" "R222"
			(at 0.96 2.334 180)
			(layer "B.SilkS")
			(effects
				(font
					(size 0.7 0.7)
					(thickness 0.15)
				)
				(justify left bottom mirror)
			)
		)
		(property "Value" "R_10k_0402"
			(at 0 -1.4 180)
			(layer "B.Fab")
			(effects
				(font
					(size 0.7 0.7)
					(thickness 0.15)
				)
				(justify left bottom mirror)
			)
		)
		(property "Description" "SMD Chip Resistor, 10 kohm, ± 1%, 62.5 mW, 0402 [1005 Metric], Thick Film, General Purpose"
			(at 0 0 0)
			(layer "F.Fab")
			(hide yes)
			(effects
				(font
					(size 1.27 1.27)
					(thickness 0.15)
				)
			)
		)
		(property "Author" "Antmicro"
			(at 0 0 0)
			(layer "B.Fab")
			(hide yes)
			(effects
				(font
					(size 1 1)
					(thickness 0.15)
				)
				(justify mirror)
			)
		)
		(property "DNP" "DNP"
			(at 0 0 0)
			(layer "B.Fab")
			(hide yes)
			(effects
				(font
					(size 1 1)
					(thickness 0.15)
				)
				(justify mirror)
			)
		)
		(property "License" "Apache-2.0"
			(at 0 0 0)
			(layer "B.Fab")
			(hide yes)
			(effects
				(font
					(size 1 1)
					(thickness 0.15)
				)
				(justify mirror)
			)
		)
		(property "MPN" "CR0402-FX-1002GLF"
			(at 0 0 0)
			(layer "B.Fab")
			(hide yes)
			(effects
				(font
					(size 1 1)
					(thickness 0.15)
				)
				(justify mirror)
			)
		)
		(property "Manufacturer" "Bourns"
			(at 0 0 0)
			(layer "B.Fab")
			(hide yes)
			(effects
				(font
					(size 1 1)
					(thickness 0.15)
				)
				(justify mirror)
			)
		)
		(property "Tolerance" "1%"
			(at 0 0 0)
			(layer "B.Fab")
			(hide yes)
			(effects
				(font
					(size 1 1)
					(thickness 0.15)
				)
				(justify mirror)
			)
		)
		(property "Val" "10k"
			(at 0 0 0)
			(layer "B.Fab")
			(hide yes)
			(effects
				(font
					(size 1 1)
					(thickness 0.15)
				)
				(justify mirror)
			)
		)
		(property "dnp" ""
			(at 0 0 0)
			(layer "B.Fab")
			(hide yes)
			(effects
				(font
					(size 1 1)
					(thickness 0.15)
				)
				(justify mirror)
			)
		)
		(property "exclude_from_bom" ""
			(at 0 0 0)
			(layer "B.Fab")
			(hide yes)
			(effects
				(font
					(size 1 1)
					(thickness 0.15)
				)
				(justify mirror)
			)
		)
		(sheetname "HDMI + Ethernet")
		(sheetfile "hdmi-ethernet.kicad_sch")
		(attr smd exclude_from_bom)
		(fp_rect
			(start -0.925 0.47)
			(end 0.925 -0.47)
			(stroke
				(width 0.05)
				(type default)
			)
			(fill no)
			(layer "B.CrtYd")
		)
		(fp_rect
			(start -0.5 0.25)
			(end 0.5 -0.25)
			(stroke
				(width 0.15)
				(type solid)
			)
			(fill no)
			(layer "B.Fab")
		)
		(pad "1" smd roundrect
			(at -0.48 0)
			(size 0.59 0.64)
			(layers "B.Cu" "B.Mask" "B.Paste")
			(roundrect_rratio 0.25)
			(net 947 "/HDMI + Ethernet/ETH_PHY_RXER")
			(pintype "passive")
		)
		(pad "2" smd roundrect
			(at 0.48 0)
			(size 0.59 0.64)
			(layers "B.Cu" "B.Mask" "B.Paste")
			(roundrect_rratio 0.25)
			(net 26 "+1V8")
			(pintype "passive")
		)
	)
	(footprint "antmicro-footprints:R_0402_1005Metric"
		(layer "B.Cu")
		(at 181.05 168.7125 90)
		(descr "Resistor SMD 0402")
		(tags "resistor SMD 0402")
		(property "Reference" "R307"
			(at 3.6125 0.425 270)
			(layer "B.SilkS")
			(effects
				(font
					(size 0.7 0.7)
					(thickness 0.15)
				)
				(justify left bottom mirror)
			)
		)
		(property "Value" "R_0R_0402"
			(at 0 -1.4 270)
			(layer "B.Fab")
			(effects
				(font
					(size 0.7 0.7)
					(thickness 0.15)
				)
				(justify left bottom mirror)
			)
		)
		(property "Description" "SMD Chip Resistor, Jumper, 0 ohm, 100 mW, 0402 [1005 Metric], Thick Film, General Purpose"
			(at 0 0 90)
			(layer "F.Fab")
			(hide yes)
			(effects
				(font
					(size 1.27 1.27)
					(thickness 0.15)
				)
			)
		)
		(property "Author" "Antmicro"
			(at 349.7625 -12.3375 0)
			(layer "B.Fab")
			(hide yes)
			(effects
				(font
					(size 1 1)
					(thickness 0.15)
				)
				(justify mirror)
			)
		)
		(property "Current" "1A"
			(at 349.7625 -12.3375 0)
			(layer "B.Fab")
			(hide yes)
			(effects
				(font
					(size 1 1)
					(thickness 0.15)
				)
				(justify mirror)
			)
		)
		(property "DNP" "DNP"
			(at 349.7625 -12.3375 0)
			(layer "B.Fab")
			(hide yes)
			(effects
				(font
					(size 1 1)
					(thickness 0.15)
				)
				(justify mirror)
			)
		)
		(property "License" "Apache-2.0"
			(at 349.7625 -12.3375 0)
			(layer "B.Fab")
			(hide yes)
			(effects
				(font
					(size 1 1)
					(thickness 0.15)
				)
				(justify mirror)
			)
		)
		(property "MPN" "ERJ2GE0R00X"
			(at 349.7625 -12.3375 0)
			(layer "B.Fab")
			(hide yes)
			(effects
				(font
					(size 1 1)
					(thickness 0.15)
				)
				(justify mirror)
			)
		)
		(property "Manufacturer" "Panasonic"
			(at 349.7625 -12.3375 0)
			(layer "B.Fab")
			(hide yes)
			(effects
				(font
					(size 1 1)
					(thickness 0.15)
				)
				(justify mirror)
			)
		)
		(property "Tolerance" ""
			(at 349.7625 -12.3375 0)
			(layer "B.Fab")
			(hide yes)
			(effects
				(font
					(size 1 1)
					(thickness 0.15)
				)
				(justify mirror)
			)
		)
		(property "Val" "0R"
			(at 349.7625 -12.3375 0)
			(layer "B.Fab")
			(hide yes)
			(effects
				(font
					(size 1 1)
					(thickness 0.15)
				)
				(justify mirror)
			)
		)
		(property "dnp" ""
			(at 349.7625 -12.3375 0)
			(layer "B.Fab")
			(hide yes)
			(effects
				(font
					(size 1 1)
					(thickness 0.15)
				)
				(justify mirror)
			)
		)
		(property "exclude_from_bom" ""
			(at 349.7625 -12.3375 0)
			(layer "B.Fab")
			(hide yes)
			(effects
				(font
					(size 1 1)
					(thickness 0.15)
				)
				(justify mirror)
			)
		)
		(sheetname "DC-DC Converters")
		(sheetfile "dc-dc.kicad_sch")
		(attr smd exclude_from_bom)
		(fp_rect
			(start -0.925 0.47)
			(end 0.925 -0.47)
			(stroke
				(width 0.05)
				(type default)
			)
			(fill no)
			(layer "B.CrtYd")
		)
		(fp_rect
			(start -0.5 0.25)
			(end 0.5 -0.25)
			(stroke
				(width 0.15)
				(type solid)
			)
			(fill no)
			(layer "B.Fab")
		)
		(pad "1" smd roundrect
			(at -0.48 0 90)
			(size 0.59 0.64)
			(layers "B.Cu" "B.Mask" "B.Paste")
			(roundrect_rratio 0.25)
			(net 957 "/DC-DC Converters/FB6")
			(pintype "passive")
		)
		(pad "2" smd roundrect
			(at 0.48 0 90)
			(size 0.59 0.64)
			(layers "B.Cu" "B.Mask" "B.Paste")
			(roundrect_rratio 0.25)
			(net 1220 "/DC-DC Converters/SENSE_3V3_2_P")
			(pintype "passive")
		)
	)
	(footprint "antmicro-footprints:C_0402_1005Metric"
		(layer "B.Cu")
		(at 206 118.5 180)
		(descr "Capacitor SMD 0402")
		(tags "capacitor SMD 0402")
		(property "Reference" "C75"
			(at -1.15 0.475 0)
			(layer "B.SilkS")
			(effects
				(font
					(size 0.7 0.7)
					(thickness 0.15)
				)
				(justify left bottom mirror)
			)
		)
		(property "Value" "C_100n_0402"
			(at 0 -1.169 0)
			(layer "B.Fab")
			(effects
				(font
					(size 0.7 0.7)
					(thickness 0.15)
				)
				(justify left bottom mirror)
			)
		)
		(property "Description" "SMD Multilayer Ceramic Capacitor, 0.1 µF, 50 V, 0402 [1005 Metric], ± 10%, X5R, GRM Series"
			(at 0 0 180)
			(layer "F.Fab")
			(hide yes)
			(effects
				(font
					(size 1.27 1.27)
					(thickness 0.15)
				)
			)
		)
		(property "Author" "Antmicro"
			(at 412 237 0)
			(layer "B.Fab")
			(hide yes)
			(effects
				(font
					(size 1 1)
					(thickness 0.15)
				)
				(justify mirror)
			)
		)
		(property "Dielectric" "X5R"
			(at 412 237 0)
			(layer "B.Fab")
			(hide yes)
			(effects
				(font
					(size 1 1)
					(thickness 0.15)
				)
				(justify mirror)
			)
		)
		(property "License" "Apache-2.0"
			(at 412 237 0)
			(layer "B.Fab")
			(hide yes)
			(effects
				(font
					(size 1 1)
					(thickness 0.15)
				)
				(justify mirror)
			)
		)
		(property "MPN" "GRM155R61H104KE14D"
			(at 412 237 0)
			(layer "B.Fab")
			(hide yes)
			(effects
				(font
					(size 1 1)
					(thickness 0.15)
				)
				(justify mirror)
			)
		)
		(property "Manufacturer" "Murata"
			(at 412 237 0)
			(layer "B.Fab")
			(hide yes)
			(effects
				(font
					(size 1 1)
					(thickness 0.15)
				)
				(justify mirror)
			)
		)
		(property "Val" "100n"
			(at 412 237 0)
			(layer "B.Fab")
			(hide yes)
			(effects
				(font
					(size 1 1)
					(thickness 0.15)
				)
				(justify mirror)
			)
		)
		(property "Voltage" "50V"
			(at 412 237 0)
			(layer "B.Fab")
			(hide yes)
			(effects
				(font
					(size 1 1)
					(thickness 0.15)
				)
				(justify mirror)
			)
		)
		(sheetname "FPGA Bank 16 & 17")
		(sheetfile "fpga-bank-16-17.kicad_sch")
		(attr smd)
		(fp_rect
			(start -0.925 0.47)
			(end 0.925 -0.47)
			(stroke
				(width 0.05)
				(type default)
			)
			(fill no)
			(layer "B.CrtYd")
		)
		(fp_line
			(start 0.504 0.25)
			(end 0.504 -0.248)
			(stroke
				(width 0.15)
				(type solid)
			)
			(layer "B.Fab")
		)
		(fp_line
			(start 0.504 -0.248)
			(end -0.494 -0.248)
			(stroke
				(width 0.15)
				(type solid)
			)
			(layer "B.Fab")
		)
		(fp_line
			(start -0.494 0.25)
			(end 0.504 0.25)
			(stroke
				(width 0.15)
				(type solid)
			)
			(layer "B.Fab")
		)
		(fp_line
			(start -0.494 -0.248)
			(end -0.494 0.25)
			(stroke
				(width 0.15)
				(type solid)
			)
			(layer "B.Fab")
		)
		(pad "1" smd roundrect
			(at -0.48 0 180)
			(size 0.59 0.64)
			(layers "B.Cu" "B.Mask" "B.Paste")
			(roundrect_rratio 0.25)
			(net 1 "GND")
			(pintype "passive")
		)
		(pad "2" smd roundrect
			(at 0.48 0 180)
			(size 0.59 0.64)
			(layers "B.Cu" "B.Mask" "B.Paste")
			(roundrect_rratio 0.25)
			(net 24 "+3V3")
			(pintype "passive")
		)
	)
	(footprint "antmicro-footprints:C_0402_1005Metric"
		(layer "B.Cu")
		(at 214.64 115.92 90)
		(descr "Capacitor SMD 0402")
		(tags "capacitor SMD 0402")
		(property "Reference" "C21"
			(at 1.025 1.225 270)
			(layer "B.SilkS")
			(effects
				(font
					(size 0.7 0.7)
					(thickness 0.15)
				)
				(justify left bottom mirror)
			)
		)
		(property "Value" "C_100n_0402"
			(at 0 -1.169 270)
			(layer "B.Fab")
			(effects
				(font
					(size 0.7 0.7)
					(thickness 0.15)
				)
				(justify left bottom mirror)
			)
		)
		(property "Description" "SMD Multilayer Ceramic Capacitor, 0.1 µF, 50 V, 0402 [1005 Metric], ± 10%, X5R, GRM Series"
			(at 0 0 90)
			(layer "F.Fab")
			(hide yes)
			(effects
				(font
					(size 1.27 1.27)
					(thickness 0.15)
				)
			)
		)
		(property "Author" "Antmicro"
			(at 330.56 -98.72 0)
			(layer "B.Fab")
			(hide yes)
			(effects
				(font
					(size 1 1)
					(thickness 0.15)
				)
				(justify mirror)
			)
		)
		(property "Dielectric" "X5R"
			(at 330.56 -98.72 0)
			(layer "B.Fab")
			(hide yes)
			(effects
				(font
					(size 1 1)
					(thickness 0.15)
				)
				(justify mirror)
			)
		)
		(property "License" "Apache-2.0"
			(at 330.56 -98.72 0)
			(layer "B.Fab")
			(hide yes)
			(effects
				(font
					(size 1 1)
					(thickness 0.15)
				)
				(justify mirror)
			)
		)
		(property "MPN" "GRM155R61H104KE14D"
			(at 330.56 -98.72 0)
			(layer "B.Fab")
			(hide yes)
			(effects
				(font
					(size 1 1)
					(thickness 0.15)
				)
				(justify mirror)
			)
		)
		(property "Manufacturer" "Murata"
			(at 330.56 -98.72 0)
			(layer "B.Fab")
			(hide yes)
			(effects
				(font
					(size 1 1)
					(thickness 0.15)
				)
				(justify mirror)
			)
		)
		(property "Val" "100n"
			(at 330.56 -98.72 0)
			(layer "B.Fab")
			(hide yes)
			(effects
				(font
					(size 1 1)
					(thickness 0.15)
				)
				(justify mirror)
			)
		)
		(property "Voltage" "50V"
			(at 330.56 -98.72 0)
			(layer "B.Fab")
			(hide yes)
			(effects
				(font
					(size 1 1)
					(thickness 0.15)
				)
				(justify mirror)
			)
		)
		(sheetname "FPGA Bank 16 & 17")
		(sheetfile "fpga-bank-16-17.kicad_sch")
		(attr smd)
		(fp_rect
			(start -0.925 0.47)
			(end 0.925 -0.47)
			(stroke
				(width 0.05)
				(type default)
			)
			(fill no)
			(layer "B.CrtYd")
		)
		(fp_line
			(start 0.504 -0.248)
			(end -0.494 -0.248)
			(stroke
				(width 0.15)
				(type solid)
			)
			(layer "B.Fab")
		)
		(fp_line
			(start -0.494 -0.248)
			(end -0.494 0.25)
			(stroke
				(width 0.15)
				(type solid)
			)
			(layer "B.Fab")
		)
		(fp_line
			(start 0.504 0.25)
			(end 0.504 -0.248)
			(stroke
				(width 0.15)
				(type solid)
			)
			(layer "B.Fab")
		)
		(fp_line
			(start -0.494 0.25)
			(end 0.504 0.25)
			(stroke
				(width 0.15)
				(type solid)
			)
			(layer "B.Fab")
		)
		(pad "1" smd roundrect
			(at -0.48 0 90)
			(size 0.59 0.64)
			(layers "B.Cu" "B.Mask" "B.Paste")
			(roundrect_rratio 0.25)
			(net 1 "GND")
			(pintype "passive")
		)
		(pad "2" smd roundrect
			(at 0.48 0 90)
			(size 0.59 0.64)
			(layers "B.Cu" "B.Mask" "B.Paste")
			(roundrect_rratio 0.25)
			(net 3 "VCC_USR_B")
			(pintype "passive")
		)
	)
	(footprint "antmicro-footprints:R_0402_1005Metric"
		(layer "B.Cu")
		(at 200.891252 96.95 90)
		(descr "Resistor SMD 0402")
		(tags "resistor SMD 0402")
		(property "Reference" "R218"
			(at -3.35 0.333748 270)
			(layer "B.SilkS")
			(effects
				(font
					(size 0.7 0.7)
					(thickness 0.15)
				)
				(justify left bottom mirror)
			)
		)
		(property "Value" "R_2k2_0402"
			(at 0 -1.4 270)
			(layer "B.Fab")
			(effects
				(font
					(size 0.7 0.7)
					(thickness 0.15)
				)
				(justify left bottom mirror)
			)
		)
		(property "Description" "SMD Chip Resistor, 2.2 kohm, ± 1%, 62.5 mW, 0402 [1005 Metric], Thick Film, General Purpose"
			(at 0 0 90)
			(layer "F.Fab")
			(hide yes)
			(effects
				(font
					(size 1.27 1.27)
					(thickness 0.15)
				)
			)
		)
		(property "Author" "Antmicro"
			(at 297.841252 -103.941252 0)
			(layer "B.Fab")
			(hide yes)
			(effects
				(font
					(size 1 1)
					(thickness 0.15)
				)
				(justify mirror)
			)
		)
		(property "DNP" "DNP"
			(at 297.841252 -103.941252 0)
			(layer "B.Fab")
			(hide yes)
			(effects
				(font
					(size 1 1)
					(thickness 0.15)
				)
				(justify mirror)
			)
		)
		(property "License" "Apache-2.0"
			(at 297.841252 -103.941252 0)
			(layer "B.Fab")
			(hide yes)
			(effects
				(font
					(size 1 1)
					(thickness 0.15)
				)
				(justify mirror)
			)
		)
		(property "MPN" "CR0402-FX-2201GLF"
			(at 297.841252 -103.941252 0)
			(layer "B.Fab")
			(hide yes)
			(effects
				(font
					(size 1 1)
					(thickness 0.15)
				)
				(justify mirror)
			)
		)
		(property "Manufacturer" "Bourns"
			(at 297.841252 -103.941252 0)
			(layer "B.Fab")
			(hide yes)
			(effects
				(font
					(size 1 1)
					(thickness 0.15)
				)
				(justify mirror)
			)
		)
		(property "Tolerance" "1%"
			(at 297.841252 -103.941252 0)
			(layer "B.Fab")
			(hide yes)
			(effects
				(font
					(size 1 1)
					(thickness 0.15)
				)
				(justify mirror)
			)
		)
		(property "Val" "2k2"
			(at 297.841252 -103.941252 0)
			(layer "B.Fab")
			(hide yes)
			(effects
				(font
					(size 1 1)
					(thickness 0.15)
				)
				(justify mirror)
			)
		)
		(property "dnp" ""
			(at 297.841252 -103.941252 0)
			(layer "B.Fab")
			(hide yes)
			(effects
				(font
					(size 1 1)
					(thickness 0.15)
				)
				(justify mirror)
			)
		)
		(property "exclude_from_bom" ""
			(at 297.841252 -103.941252 0)
			(layer "B.Fab")
			(hide yes)
			(effects
				(font
					(size 1 1)
					(thickness 0.15)
				)
				(justify mirror)
			)
		)
		(sheetname "HDMI + Ethernet")
		(sheetfile "hdmi-ethernet.kicad_sch")
		(attr smd exclude_from_bom)
		(fp_rect
			(start -0.925 0.47)
			(end 0.925 -0.47)
			(stroke
				(width 0.05)
				(type default)
			)
			(fill no)
			(layer "B.CrtYd")
		)
		(fp_rect
			(start -0.5 0.25)
			(end 0.5 -0.25)
			(stroke
				(width 0.15)
				(type solid)
			)
			(fill no)
			(layer "B.Fab")
		)
		(pad "1" smd roundrect
			(at -0.48 0 90)
			(size 0.59 0.64)
			(layers "B.Cu" "B.Mask" "B.Paste")
			(roundrect_rratio 0.25)
			(net 510 "/FPGA Bank 16 & 17/GBE_RGMII.REFCLK")
			(pintype "passive")
		)
		(pad "2" smd roundrect
			(at 0.48 0 90)
			(size 0.59 0.64)
			(layers "B.Cu" "B.Mask" "B.Paste")
			(roundrect_rratio 0.25)
			(net 1 "GND")
			(pintype "passive")
		)
	)
	(footprint "antmicro-footprints:R_Array_4x0201_Panasonic_EXB18V"
		(layer "B.Cu")
		(at 165.999999 144.999999)
		(property "Reference" "R14"
			(at -4.299999 6.250001 0)
			(layer "B.SilkS")
			(effects
				(font
					(size 0.7 0.7)
					(thickness 0.15)
				)
				(justify left bottom mirror)
			)
		)
		(property "Value" "4x39R_0201_array"
			(at -1.1 -1.8 0)
			(layer "B.Fab")
			(effects
				(font
					(size 0.7 0.7)
					(thickness 0.15)
				)
				(justify right bottom mirror)
			)
		)
		(property "Description" "Fixed Network Resistor, 39 ohm, Isolated, 4 Resistors, 0502 [1406 Metric], Flat, ± 5%"
			(at 0 0 0)
			(layer "F.Fab")
			(hide yes)
			(effects
				(font
					(size 1.27 1.27)
					(thickness 0.15)
				)
			)
		)
		(property "Author" "Antmicro"
			(at 0 0 0)
			(layer "B.Fab")
			(hide yes)
			(effects
				(font
					(size 1 1)
					(thickness 0.15)
				)
				(justify mirror)
			)
		)
		(property "License" "Apache-2.0"
			(at 0 0 0)
			(layer "B.Fab")
			(hide yes)
			(effects
				(font
					(size 1 1)
					(thickness 0.15)
				)
				(justify mirror)
			)
		)
		(property "MPN" "EXB-18V390JX"
			(at 0 0 0)
			(layer "B.Fab")
			(hide yes)
			(effects
				(font
					(size 1 1)
					(thickness 0.15)
				)
				(justify mirror)
			)
		)
		(property "Manufacturer" "Panasonic"
			(at 0 0 0)
			(layer "B.Fab")
			(hide yes)
			(effects
				(font
					(size 1 1)
					(thickness 0.15)
				)
				(justify mirror)
			)
		)
		(property "Val" "4x39R_0201"
			(at 0 0 0)
			(layer "B.Fab")
			(hide yes)
			(effects
				(font
					(size 1 1)
					(thickness 0.15)
				)
				(justify mirror)
			)
		)
		(sheetname "DRAM + SRAM")
		(sheetfile "ram.kicad_sch")
		(attr smd)
		(fp_line
			(start -0.8 0.45)
			(end -0.8 -0.45)
			(stroke
				(width 0.12)
				(type solid)
			)
			(layer "B.SilkS")
		)
		(fp_line
			(start 0.8 0.45)
			(end 0.8 -0.45)
			(stroke
				(width 0.12)
				(type solid)
			)
			(layer "B.SilkS")
		)
		(fp_rect
			(start -0.898 0.66)
			(end 0.898 -0.65)
			(stroke
				(width 0.05)
				(type solid)
			)
			(fill no)
			(layer "B.CrtYd")
		)
		(pad "1" smd roundrect
			(at -0.6 -0.298)
			(size 0.2 0.4)
			(layers "B.Cu" "B.Mask" "B.Paste")
			(roundrect_rratio 0.25)
			(net 533 "/DRAM + SRAM/DDR.A2")
			(pinfunction "R1.1")
			(pintype "passive")
		)
		(pad "2" smd roundrect
			(at -0.202 -0.298)
			(size 0.2 0.4)
			(layers "B.Cu" "B.Mask" "B.Paste")
			(roundrect_rratio 0.25)
			(net 534 "/DRAM + SRAM/DDR.A3")
			(pinfunction "R2.1")
			(pintype "passive")
		)
		(pad "3" smd roundrect
			(at 0.2 -0.298)
			(size 0.2 0.4)
			(layers "B.Cu" "B.Mask" "B.Paste")
			(roundrect_rratio 0.25)
			(net 531 "/DRAM + SRAM/DDR.A0")
			(pinfunction "R3.1")
			(pintype "passive")
		)
		(pad "4" smd roundrect
			(at 0.598 -0.298)
			(size 0.2 0.4)
			(layers "B.Cu" "B.Mask" "B.Paste")
			(roundrect_rratio 0.25)
			(net 547 "/DRAM + SRAM/DDR.BA0")
			(pinfunction "R4.1")
			(pintype "passive")
		)
		(pad "5" smd roundrect
			(at 0.598 0.3)
			(size 0.2 0.4)
			(layers "B.Cu" "B.Mask" "B.Paste")
			(roundrect_rratio 0.25)
			(net 7 "+0V675_VTT")
			(pinfunction "R4.2")
			(pintype "passive")
		)
		(pad "6" smd roundrect
			(at 0.2 0.3)
			(size 0.2 0.4)
			(layers "B.Cu" "B.Mask" "B.Paste")
			(roundrect_rratio 0.25)
			(net 7 "+0V675_VTT")
			(pinfunction "R3.2")
			(pintype "passive")
		)
		(pad "7" smd roundrect
			(at -0.202 0.3)
			(size 0.2 0.4)
			(layers "B.Cu" "B.Mask" "B.Paste")
			(roundrect_rratio 0.25)
			(net 7 "+0V675_VTT")
			(pinfunction "R2.2")
			(pintype "passive")
		)
		(pad "8" smd roundrect
			(at -0.6 0.3)
			(size 0.2 0.4)
			(layers "B.Cu" "B.Mask" "B.Paste")
			(roundrect_rratio 0.25)
			(net 7 "+0V675_VTT")
			(pinfunction "R1.2")
			(pintype "passive")
		)
	)
	(footprint "antmicro-footprints:C_0402_1005Metric"
		(layer "B.Cu")
		(at 173.599999 147.999999 -90)
		(descr "Capacitor SMD 0402")
		(tags "capacitor SMD 0402")
		(property "Reference" "C187"
			(at 0.775001 -0.375001 90)
			(layer "B.SilkS")
			(effects
				(font
					(size 0.7 0.7)
					(thickness 0.15)
				)
				(justify left bottom mirror)
			)
		)
		(property "Value" "C_100n_0402"
			(at 0 -1.169 90)
			(layer "B.Fab")
			(effects
				(font
					(size 0.7 0.7)
					(thickness 0.15)
				)
				(justify left bottom mirror)
			)
		)
		(property "Description" "SMD Multilayer Ceramic Capacitor, 0.1 µF, 50 V, 0402 [1005 Metric], ± 10%, X5R, GRM Series"
			(at 0 0 270)
			(layer "F.Fab")
			(hide yes)
			(effects
				(font
					(size 1.27 1.27)
					(thickness 0.15)
				)
			)
		)
		(property "Author" "Antmicro"
			(at 25.6 321.599998 0)
			(layer "B.Fab")
			(hide yes)
			(effects
				(font
					(size 1 1)
					(thickness 0.15)
				)
				(justify mirror)
			)
		)
		(property "Dielectric" "X5R"
			(at 25.6 321.599998 0)
			(layer "B.Fab")
			(hide yes)
			(effects
				(font
					(size 1 1)
					(thickness 0.15)
				)
				(justify mirror)
			)
		)
		(property "License" "Apache-2.0"
			(at 25.6 321.599998 0)
			(layer "B.Fab")
			(hide yes)
			(effects
				(font
					(size 1 1)
					(thickness 0.15)
				)
				(justify mirror)
			)
		)
		(property "MPN" "GRM155R61H104KE14D"
			(at 25.6 321.599998 0)
			(layer "B.Fab")
			(hide yes)
			(effects
				(font
					(size 1 1)
					(thickness 0.15)
				)
				(justify mirror)
			)
		)
		(property "Manufacturer" "Murata"
			(at 25.6 321.599998 0)
			(layer "B.Fab")
			(hide yes)
			(effects
				(font
					(size 1 1)
					(thickness 0.15)
				)
				(justify mirror)
			)
		)
		(property "Val" "100n"
			(at 25.6 321.599998 0)
			(layer "B.Fab")
			(hide yes)
			(effects
				(font
					(size 1 1)
					(thickness 0.15)
				)
				(justify mirror)
			)
		)
		(property "Voltage" "50V"
			(at 25.6 321.599998 0)
			(layer "B.Fab")
			(hide yes)
			(effects
				(font
					(size 1 1)
					(thickness 0.15)
				)
				(justify mirror)
			)
		)
		(sheetname "DRAM + SRAM")
		(sheetfile "ram.kicad_sch")
		(attr smd)
		(fp_rect
			(start -0.925 0.47)
			(end 0.925 -0.47)
			(stroke
				(width 0.05)
				(type default)
			)
			(fill no)
			(layer "B.CrtYd")
		)
		(fp_line
			(start -0.494 0.25)
			(end 0.504 0.25)
			(stroke
				(width 0.15)
				(type solid)
			)
			(layer "B.Fab")
		)
		(fp_line
			(start 0.504 0.25)
			(end 0.504 -0.248)
			(stroke
				(width 0.15)
				(type solid)
			)
			(layer "B.Fab")
		)
		(fp_line
			(start -0.494 -0.248)
			(end -0.494 0.25)
			(stroke
				(width 0.15)
				(type solid)
			)
			(layer "B.Fab")
		)
		(fp_line
			(start 0.504 -0.248)
			(end -0.494 -0.248)
			(stroke
				(width 0.15)
				(type solid)
			)
			(layer "B.Fab")
		)
		(pad "1" smd roundrect
			(at -0.48 0 270)
			(size 0.59 0.64)
			(layers "B.Cu" "B.Mask" "B.Paste")
			(roundrect_rratio 0.25)
			(net 1 "GND")
			(pintype "passive")
		)
		(pad "2" smd roundrect
			(at 0.48 0 270)
			(size 0.59 0.64)
			(layers "B.Cu" "B.Mask" "B.Paste")
			(roundrect_rratio 0.25)
			(net 25 "+1V35")
			(pintype "passive")
		)
	)
	(footprint "antmicro-footprints:C_0603_1608Metric"
		(layer "B.Cu")
		(at 200 136.6 90)
		(descr "Capacitor SMD 0603")
		(tags "capacitor 0603")
		(property "Reference" "C386"
			(at 27.425 25.725 90)
			(layer "B.SilkS")
			(effects
				(font
					(size 0.7 0.7)
					(thickness 0.15)
				)
				(justify right bottom mirror)
			)
		)
		(property "Value" "C_47u_0603"
			(at 0 -1.6 90)
			(layer "B.Fab")
			(effects
				(font
					(size 0.7 0.7)
					(thickness 0.15)
				)
				(justify right bottom mirror)
			)
		)
		(property "Description" "SMD Multilayer Ceramic Capacitor, 47 µF, 6.3 V, 0603 [1608 Metric], ± 20%, X5R, GRM Series"
			(at 0 0 90)
			(layer "F.Fab")
			(hide yes)
			(effects
				(font
					(size 1.27 1.27)
					(thickness 0.15)
				)
			)
		)
		(property "Author" "Antmicro"
			(at 336.6 -63.4 0)
			(layer "B.Fab")
			(hide yes)
			(effects
				(font
					(size 1 1)
					(thickness 0.15)
				)
				(justify mirror)
			)
		)
		(property "Dielectric" ""
			(at 336.6 -63.4 0)
			(layer "B.Fab")
			(hide yes)
			(effects
				(font
					(size 1 1)
					(thickness 0.15)
				)
				(justify mirror)
			)
		)
		(property "License" "Apache-2.0"
			(at 336.6 -63.4 0)
			(layer "B.Fab")
			(hide yes)
			(effects
				(font
					(size 1 1)
					(thickness 0.15)
				)
				(justify mirror)
			)
		)
		(property "MPN" "GRM188R60J476ME15D"
			(at 336.6 -63.4 0)
			(layer "B.Fab")
			(hide yes)
			(effects
				(font
					(size 1 1)
					(thickness 0.15)
				)
				(justify mirror)
			)
		)
		(property "Manufacturer" "Murata"
			(at 336.6 -63.4 0)
			(layer "B.Fab")
			(hide yes)
			(effects
				(font
					(size 1 1)
					(thickness 0.15)
				)
				(justify mirror)
			)
		)
		(property "Val" "47u"
			(at 336.6 -63.4 0)
			(layer "B.Fab")
			(hide yes)
			(effects
				(font
					(size 1 1)
					(thickness 0.15)
				)
				(justify mirror)
			)
		)
		(property "Voltage" ""
			(at 336.6 -63.4 0)
			(layer "B.Fab")
			(hide yes)
			(effects
				(font
					(size 1 1)
					(thickness 0.15)
				)
				(justify mirror)
			)
		)
		(sheetname "FPGA supply")
		(sheetfile "fpga-supply.kicad_sch")
		(attr smd)
		(fp_line
			(start -0.15 -0.4)
			(end 0.15 -0.4)
			(stroke
				(width 0.15)
				(type solid)
			)
			(layer "B.SilkS")
		)
		(fp_line
			(start -0.15 0.4)
			(end 0.15 0.4)
			(stroke
				(width 0.15)
				(type solid)
			)
			(layer "B.SilkS")
		)
		(fp_rect
			(start -1.25 0.65)
			(end 1.25 -0.65)
			(stroke
				(width 0.05)
				(type solid)
			)
			(fill no)
			(layer "B.CrtYd")
		)
		(fp_rect
			(start -0.8 0.4)
			(end 0.8 -0.4)
			(stroke
				(width 0.15)
				(type solid)
			)
			(fill no)
			(layer "B.Fab")
		)
		(pad "1" smd roundrect
			(at -0.7 0 90)
			(size 0.8 1)
			(layers "B.Cu" "B.Mask" "B.Paste")
			(roundrect_rratio 0.2)
			(net 1 "GND")
			(pintype "passive")
		)
		(pad "2" smd roundrect
			(at 0.7 0 90)
			(size 0.8 1)
			(layers "B.Cu" "B.Mask" "B.Paste")
			(roundrect_rratio 0.2)
			(net 650 "+1V0")
			(pintype "passive")
		)
	)
	(footprint "antmicro-footprints:C_0603_1608Metric"
		(layer "B.Cu")
		(at 184.100001 133.000001)
		(descr "Capacitor SMD 0603")
		(tags "capacitor 0603")
		(property "Reference" "C120"
			(at -3.850001 0.369999 0)
			(layer "B.SilkS")
			(effects
				(font
					(size 0.7 0.7)
					(thickness 0.15)
				)
				(justify right bottom mirror)
			)
		)
		(property "Value" "C_47u_0603"
			(at 0 -1.6 0)
			(layer "B.Fab")
			(effects
				(font
					(size 0.7 0.7)
					(thickness 0.15)
				)
				(justify right bottom mirror)
			)
		)
		(property "Description" "SMD Multilayer Ceramic Capacitor, 47 µF, 6.3 V, 0603 [1608 Metric], ± 20%, X5R, GRM Series"
			(at 0 0 0)
			(layer "F.Fab")
			(hide yes)
			(effects
				(font
					(size 1.27 1.27)
					(thickness 0.15)
				)
			)
		)
		(property "Author" "Antmicro"
			(at 0 0 0)
			(layer "B.Fab")
			(hide yes)
			(effects
				(font
					(size 1 1)
					(thickness 0.15)
				)
				(justify mirror)
			)
		)
		(property "Dielectric" ""
			(at 0 0 0)
			(layer "B.Fab")
			(hide yes)
			(effects
				(font
					(size 1 1)
					(thickness 0.15)
				)
				(justify mirror)
			)
		)
		(property "License" "Apache-2.0"
			(at 0 0 0)
			(layer "B.Fab")
			(hide yes)
			(effects
				(font
					(size 1 1)
					(thickness 0.15)
				)
				(justify mirror)
			)
		)
		(property "MPN" "GRM188R60J476ME15D"
			(at 0 0 0)
			(layer "B.Fab")
			(hide yes)
			(effects
				(font
					(size 1 1)
					(thickness 0.15)
				)
				(justify mirror)
			)
		)
		(property "Manufacturer" "Murata"
			(at 0 0 0)
			(layer "B.Fab")
			(hide yes)
			(effects
				(font
					(size 1 1)
					(thickness 0.15)
				)
				(justify mirror)
			)
		)
		(property "Val" "47u"
			(at 0 0 0)
			(layer "B.Fab")
			(hide yes)
			(effects
				(font
					(size 1 1)
					(thickness 0.15)
				)
				(justify mirror)
			)
		)
		(property "Voltage" ""
			(at 0 0 0)
			(layer "B.Fab")
			(hide yes)
			(effects
				(font
					(size 1 1)
					(thickness 0.15)
				)
				(justify mirror)
			)
		)
		(sheetname "FPGA supply")
		(sheetfile "fpga-supply.kicad_sch")
		(attr smd)
		(fp_line
			(start -0.15 -0.4)
			(end 0.15 -0.4)
			(stroke
				(width 0.15)
				(type solid)
			)
			(layer "B.SilkS")
		)
		(fp_line
			(start -0.15 0.4)
			(end 0.15 0.4)
			(stroke
				(width 0.15)
				(type solid)
			)
			(layer "B.SilkS")
		)
		(fp_rect
			(start -1.25 0.65)
			(end 1.25 -0.65)
			(stroke
				(width 0.05)
				(type solid)
			)
			(fill no)
			(layer "B.CrtYd")
		)
		(fp_rect
			(start -0.8 0.4)
			(end 0.8 -0.4)
			(stroke
				(width 0.15)
				(type solid)
			)
			(fill no)
			(layer "B.Fab")
		)
		(pad "1" smd roundrect
			(at -0.7 0)
			(size 0.8 1)
			(layers "B.Cu" "B.Mask" "B.Paste")
			(roundrect_rratio 0.2)
			(net 1 "GND")
			(pintype "passive")
		)
		(pad "2" smd roundrect
			(at 0.7 0)
			(size 0.8 1)
			(layers "B.Cu" "B.Mask" "B.Paste")
			(roundrect_rratio 0.2)
			(net 8 "+1V2_MGTAVTT")
			(pintype "passive")
		)
	)
	(footprint "antmicro-footprints:C_0402_1005Metric"
		(layer "B.Cu")
		(at 169.6 147.999999 90)
		(descr "Capacitor SMD 0402")
		(tags "capacitor SMD 0402")
		(property "Reference" "C181"
			(at 0.124999 -1 0)
			(layer "B.SilkS")
			(effects
				(font
					(size 0.7 0.7)
					(thickness 0.15)
				)
				(justify left bottom mirror)
			)
		)
		(property "Value" "C_100n_0402"
			(at 0 -1.169 270)
			(layer "B.Fab")
			(effects
				(font
					(size 0.7 0.7)
					(thickness 0.15)
				)
				(justify left bottom mirror)
			)
		)
		(property "Description" "SMD Multilayer Ceramic Capacitor, 0.1 µF, 50 V, 0402 [1005 Metric], ± 10%, X5R, GRM Series"
			(at 0 0 90)
			(layer "F.Fab")
			(hide yes)
			(effects
				(font
					(size 1.27 1.27)
					(thickness 0.15)
				)
			)
		)
		(property "Author" "Antmicro"
			(at 317.599999 -21.600001 0)
			(layer "B.Fab")
			(hide yes)
			(effects
				(font
					(size 1 1)
					(thickness 0.15)
				)
				(justify mirror)
			)
		)
		(property "Dielectric" "X5R"
			(at 317.599999 -21.600001 0)
			(layer "B.Fab")
			(hide yes)
			(effects
				(font
					(size 1 1)
					(thickness 0.15)
				)
				(justify mirror)
			)
		)
		(property "License" "Apache-2.0"
			(at 317.599999 -21.600001 0)
			(layer "B.Fab")
			(hide yes)
			(effects
				(font
					(size 1 1)
					(thickness 0.15)
				)
				(justify mirror)
			)
		)
		(property "MPN" "GRM155R61H104KE14D"
			(at 317.599999 -21.600001 0)
			(layer "B.Fab")
			(hide yes)
			(effects
				(font
					(size 1 1)
					(thickness 0.15)
				)
				(justify mirror)
			)
		)
		(property "Manufacturer" "Murata"
			(at 317.599999 -21.600001 0)
			(layer "B.Fab")
			(hide yes)
			(effects
				(font
					(size 1 1)
					(thickness 0.15)
				)
				(justify mirror)
			)
		)
		(property "Val" "100n"
			(at 317.599999 -21.600001 0)
			(layer "B.Fab")
			(hide yes)
			(effects
				(font
					(size 1 1)
					(thickness 0.15)
				)
				(justify mirror)
			)
		)
		(property "Voltage" "50V"
			(at 317.599999 -21.600001 0)
			(layer "B.Fab")
			(hide yes)
			(effects
				(font
					(size 1 1)
					(thickness 0.15)
				)
				(justify mirror)
			)
		)
		(sheetname "DRAM + SRAM")
		(sheetfile "ram.kicad_sch")
		(attr smd)
		(fp_rect
			(start -0.925 0.47)
			(end 0.925 -0.47)
			(stroke
				(width 0.05)
				(type default)
			)
			(fill no)
			(layer "B.CrtYd")
		)
		(fp_line
			(start 0.504 -0.248)
			(end -0.494 -0.248)
			(stroke
				(width 0.15)
				(type solid)
			)
			(layer "B.Fab")
		)
		(fp_line
			(start -0.494 -0.248)
			(end -0.494 0.25)
			(stroke
				(width 0.15)
				(type solid)
			)
			(layer "B.Fab")
		)
		(fp_line
			(start 0.504 0.25)
			(end 0.504 -0.248)
			(stroke
				(width 0.15)
				(type solid)
			)
			(layer "B.Fab")
		)
		(fp_line
			(start -0.494 0.25)
			(end 0.504 0.25)
			(stroke
				(width 0.15)
				(type solid)
			)
			(layer "B.Fab")
		)
		(pad "1" smd roundrect
			(at -0.48 0 90)
			(size 0.59 0.64)
			(layers "B.Cu" "B.Mask" "B.Paste")
			(roundrect_rratio 0.25)
			(net 1 "GND")
			(pintype "passive")
		)
		(pad "2" smd roundrect
			(at 0.48 0 90)
			(size 0.59 0.64)
			(layers "B.Cu" "B.Mask" "B.Paste")
			(roundrect_rratio 0.25)
			(net 25 "+1V35")
			(pintype "passive")
		)
	)
	(footprint "antmicro-footprints:C_0603_1608Metric"
		(layer "B.Cu")
		(at 200 123.55 -90)
		(descr "Capacitor SMD 0603")
		(tags "capacitor 0603")
		(property "Reference" "C378"
			(at -31.575 -25.775 90)
			(layer "B.SilkS")
			(effects
				(font
					(size 0.7 0.7)
					(thickness 0.15)
				)
				(justify left bottom mirror)
			)
		)
		(property "Value" "C_47u_0603"
			(at 0 -1.6 90)
			(layer "B.Fab")
			(effects
				(font
					(size 0.7 0.7)
					(thickness 0.15)
				)
				(justify left bottom mirror)
			)
		)
		(property "Description" "SMD Multilayer Ceramic Capacitor, 47 µF, 6.3 V, 0603 [1608 Metric], ± 20%, X5R, GRM Series"
			(at 0 0 270)
			(layer "F.Fab")
			(hide yes)
			(effects
				(font
					(size 1.27 1.27)
					(thickness 0.15)
				)
			)
		)
		(property "Author" "Antmicro"
			(at 76.45 323.55 0)
			(layer "B.Fab")
			(hide yes)
			(effects
				(font
					(size 1 1)
					(thickness 0.15)
				)
				(justify mirror)
			)
		)
		(property "Dielectric" ""
			(at 76.45 323.55 0)
			(layer "B.Fab")
			(hide yes)
			(effects
				(font
					(size 1 1)
					(thickness 0.15)
				)
				(justify mirror)
			)
		)
		(property "License" "Apache-2.0"
			(at 76.45 323.55 0)
			(layer "B.Fab")
			(hide yes)
			(effects
				(font
					(size 1 1)
					(thickness 0.15)
				)
				(justify mirror)
			)
		)
		(property "MPN" "GRM188R60J476ME15D"
			(at 76.45 323.55 0)
			(layer "B.Fab")
			(hide yes)
			(effects
				(font
					(size 1 1)
					(thickness 0.15)
				)
				(justify mirror)
			)
		)
		(property "Manufacturer" "Murata"
			(at 76.45 323.55 0)
			(layer "B.Fab")
			(hide yes)
			(effects
				(font
					(size 1 1)
					(thickness 0.15)
				)
				(justify mirror)
			)
		)
		(property "Val" "47u"
			(at 76.45 323.55 0)
			(layer "B.Fab")
			(hide yes)
			(effects
				(font
					(size 1 1)
					(thickness 0.15)
				)
				(justify mirror)
			)
		)
		(property "Voltage" ""
			(at 76.45 323.55 0)
			(layer "B.Fab")
			(hide yes)
			(effects
				(font
					(size 1 1)
					(thickness 0.15)
				)
				(justify mirror)
			)
		)
		(sheetname "FPGA supply")
		(sheetfile "fpga-supply.kicad_sch")
		(attr smd)
		(fp_line
			(start -0.15 0.4)
			(end 0.15 0.4)
			(stroke
				(width 0.15)
				(type solid)
			)
			(layer "B.SilkS")
		)
		(fp_line
			(start -0.15 -0.4)
			(end 0.15 -0.4)
			(stroke
				(width 0.15)
				(type solid)
			)
			(layer "B.SilkS")
		)
		(fp_rect
			(start -1.25 0.65)
			(end 1.25 -0.65)
			(stroke
				(width 0.05)
				(type solid)
			)
			(fill no)
			(layer "B.CrtYd")
		)
		(fp_rect
			(start -0.8 0.4)
			(end 0.8 -0.4)
			(stroke
				(width 0.15)
				(type solid)
			)
			(fill no)
			(layer "B.Fab")
		)
		(pad "1" smd roundrect
			(at -0.7 0 270)
			(size 0.8 1)
			(layers "B.Cu" "B.Mask" "B.Paste")
			(roundrect_rratio 0.2)
			(net 1 "GND")
			(pintype "passive")
		)
		(pad "2" smd roundrect
			(at 0.7 0 270)
			(size 0.8 1)
			(layers "B.Cu" "B.Mask" "B.Paste")
			(roundrect_rratio 0.2)
			(net 650 "+1V0")
			(pintype "passive")
		)
	)
	(footprint "antmicro-footprints:C_0402_1005Metric"
		(layer "B.Cu")
		(at 195.68 144.6 -45)
		(descr "Capacitor SMD 0402")
		(tags "capacitor SMD 0402")
		(property "Reference" "C84"
			(at 1.145513 1.223295 315)
			(unlocked yes)
			(layer "B.SilkS")
			(effects
				(font
					(size 0.7 0.7)
					(thickness 0.15)
				)
				(justify left bottom mirror)
			)
		)
		(property "Value" "C_100n_0402"
			(at 0 -1.169 135)
			(layer "B.Fab")
			(effects
				(font
					(size 0.7 0.7)
					(thickness 0.15)
				)
				(justify left bottom mirror)
			)
		)
		(property "Description" "SMD Multilayer Ceramic Capacitor, 0.1 µF, 50 V, 0402 [1005 Metric], ± 10%, X5R, GRM Series"
			(at 0 0 315)
			(layer "F.Fab")
			(hide yes)
			(effects
				(font
					(size 1.27 1.27)
					(thickness 0.15)
				)
			)
		)
		(property "Author" "Antmicro"
			(at -44.934295 180.719015 0)
			(layer "B.Fab")
			(hide yes)
			(effects
				(font
					(size 1 1)
					(thickness 0.15)
				)
				(justify mirror)
			)
		)
		(property "Dielectric" "X5R"
			(at -44.934295 180.719015 0)
			(layer "B.Fab")
			(hide yes)
			(effects
				(font
					(size 1 1)
					(thickness 0.15)
				)
				(justify mirror)
			)
		)
		(property "License" "Apache-2.0"
			(at -44.934295 180.719015 0)
			(layer "B.Fab")
			(hide yes)
			(effects
				(font
					(size 1 1)
					(thickness 0.15)
				)
				(justify mirror)
			)
		)
		(property "MPN" "GRM155R61H104KE14D"
			(at -44.934295 180.719015 0)
			(layer "B.Fab")
			(hide yes)
			(effects
				(font
					(size 1 1)
					(thickness 0.15)
				)
				(justify mirror)
			)
		)
		(property "Manufacturer" "Murata"
			(at -44.934295 180.719015 0)
			(layer "B.Fab")
			(hide yes)
			(effects
				(font
					(size 1 1)
					(thickness 0.15)
				)
				(justify mirror)
			)
		)
		(property "Val" "100n"
			(at -44.934295 180.719015 0)
			(layer "B.Fab")
			(hide yes)
			(effects
				(font
					(size 1 1)
					(thickness 0.15)
				)
				(justify mirror)
			)
		)
		(property "Voltage" "50V"
			(at -44.934295 180.719015 0)
			(layer "B.Fab")
			(hide yes)
			(effects
				(font
					(size 1 1)
					(thickness 0.15)
				)
				(justify mirror)
			)
		)
		(sheetname "FPGA Bank 33 & 34")
		(sheetfile "fpga-bank-33-34.kicad_sch")
		(attr smd)
		(fp_poly
			(pts
				(xy -0.925 0.47) (xy 0.925 0.47) (xy 0.925 -0.47) (xy -0.925 -0.47)
			)
			(stroke
				(width 0.05)
				(type default)
			)
			(fill no)
			(layer "B.CrtYd")
		)
		(fp_line
			(start -0.494 0.25)
			(end 0.504 0.25)
			(stroke
				(width 0.15)
				(type solid)
			)
			(layer "B.Fab")
		)
		(fp_line
			(start -0.494 -0.248)
			(end -0.494 0.25)
			(stroke
				(width 0.15)
				(type solid)
			)
			(layer "B.Fab")
		)
		(fp_line
			(start 0.504 0.25)
			(end 0.504 -0.248)
			(stroke
				(width 0.15)
				(type solid)
			)
			(layer "B.Fab")
		)
		(fp_line
			(start 0.504 -0.248)
			(end -0.494 -0.248)
			(stroke
				(width 0.15)
				(type solid)
			)
			(layer "B.Fab")
		)
		(pad "1" smd roundrect
			(at -0.48 0 315)
			(size 0.59 0.64)
			(layers "B.Cu" "B.Mask" "B.Paste")
			(roundrect_rratio 0.25)
			(net 1 "GND")
			(pintype "passive")
		)
		(pad "2" smd roundrect
			(at 0.48 0 315)
			(size 0.59 0.64)
			(layers "B.Cu" "B.Mask" "B.Paste")
			(roundrect_rratio 0.25)
			(net 26 "+1V8")
			(pintype "passive")
		)
	)
	(footprint "antmicro-footprints:C_0201"
		(layer "B.Cu")
		(at 191.2 128.2 -45)
		(descr "Capacitor SMD 0201")
		(tags "capacitor SMD 0201")
		(property "Reference" "C66"
			(at -4.030509 -35.532116 315)
			(unlocked yes)
			(layer "B.SilkS")
			(effects
				(font
					(size 0.7 0.7)
					(thickness 0.15)
				)
				(justify left bottom mirror)
			)
		)
		(property "Value" "C_4u7_0201"
			(at 0 -1.399999 135)
			(layer "B.Fab")
			(effects
				(font
					(size 0.7 0.7)
					(thickness 0.15)
				)
				(justify left bottom mirror)
			)
		)
		(property "Description" "SMD Multilayer Ceramic Capacitor, 4.7 µF, 6.3 V, 0201 [0603 Metric], ± 20%, X5R, GRM Series"
			(at 0 0 315)
			(layer "F.Fab")
			(hide yes)
			(effects
				(font
					(size 1.27 1.27)
					(thickness 0.15)
				)
			)
		)
		(property "Author" "Antmicro"
			(at -34.649906 172.747727 0)
			(layer "B.Fab")
			(hide yes)
			(effects
				(font
					(size 1 1)
					(thickness 0.15)
				)
				(justify mirror)
			)
		)
		(property "Dielectric" ""
			(at -34.649906 172.747727 0)
			(layer "B.Fab")
			(hide yes)
			(effects
				(font
					(size 1 1)
					(thickness 0.15)
				)
				(justify mirror)
			)
		)
		(property "License" "Apache-2.0"
			(at -34.649906 172.747727 0)
			(layer "B.Fab")
			(hide yes)
			(effects
				(font
					(size 1 1)
					(thickness 0.15)
				)
				(justify mirror)
			)
		)
		(property "MPN" "GRM035R60J475ME15D"
			(at -34.649906 172.747727 0)
			(layer "B.Fab")
			(hide yes)
			(effects
				(font
					(size 1 1)
					(thickness 0.15)
				)
				(justify mirror)
			)
		)
		(property "Manufacturer" "Murata"
			(at -34.649906 172.747727 0)
			(layer "B.Fab")
			(hide yes)
			(effects
				(font
					(size 1 1)
					(thickness 0.15)
				)
				(justify mirror)
			)
		)
		(property "Val" "4u7"
			(at -34.649906 172.747727 0)
			(layer "B.Fab")
			(hide yes)
			(effects
				(font
					(size 1 1)
					(thickness 0.15)
				)
				(justify mirror)
			)
		)
		(property "Voltage" ""
			(at -34.649906 172.747727 0)
			(layer "B.Fab")
			(hide yes)
			(effects
				(font
					(size 1 1)
					(thickness 0.15)
				)
				(justify mirror)
			)
		)
		(sheetname "FPGA supply")
		(sheetfile "fpga-supply.kicad_sch")
		(attr smd)
		(fp_poly
			(pts
				(xy -0.7 0.35) (xy 0.7 0.35) (xy 0.7 -0.35) (xy -0.7 -0.35)
			)
			(stroke
				(width 0.05)
				(type default)
			)
			(fill no)
			(layer "B.CrtYd")
		)
		(fp_poly
			(pts
				(xy 0.3 -0.15) (xy -0.301 -0.15) (xy -0.301 0.149) (xy 0.3 0.149)
			)
			(stroke
				(width 0.15)
				(type solid)
			)
			(fill no)
			(layer "B.Fab")
		)
		(pad "" smd roundrect
			(at -0.349 0.002 315)
			(size 0.318 0.36)
			(layers "B.Paste")
			(roundrect_rratio 0.25)
		)
		(pad "" smd roundrect
			(at 0.341 0.002 315)
			(size 0.318 0.36)
			(layers "B.Paste")
			(roundrect_rratio 0.25)
		)
		(pad "1" smd roundrect
			(at -0.321 0.002 315)
			(size 0.46 0.4)
			(layers "B.Cu" "B.Mask")
			(roundrect_rratio 0.25)
			(net 1 "GND")
			(pintype "passive")
		)
		(pad "2" smd roundrect
			(at 0.32 0.002 315)
			(size 0.46 0.4)
			(layers "B.Cu" "B.Mask")
			(roundrect_rratio 0.25)
			(net 6 "+1V0_MGTAVCC")
			(pintype "passive")
		)
	)
	(footprint "antmicro-footprints:NetTie-2_SMD_Pad0.127mm"
		(layer "B.Cu")
		(at 208.100001 147.257 90)
		(descr "Net tie, 2 pin, 0.127mm  SMD pads")
		(tags "net tie")
		(property "Reference" "NT31"
			(at -0.128 1.345 270)
			(layer "B.SilkS")
			(hide yes)
			(effects
				(font
					(size 0.7 0.7)
					(thickness 0.15)
				)
				(justify left bottom mirror)
			)
		)
		(property "Value" "Net-Tie_2"
			(at 0 -1.199 270)
			(layer "B.Fab")
			(effects
				(font
					(size 0.7 0.7)
					(thickness 0.15)
				)
				(justify left bottom mirror)
			)
		)
		(property "Description" "Net tie, 2 pins"
			(at 0 0 90)
			(layer "F.Fab")
			(hide yes)
			(effects
				(font
					(size 1.27 1.27)
					(thickness 0.15)
				)
			)
		)
		(property "Author" "Antmicro"
			(at 355.357001 -60.843001 0)
			(layer "B.Fab")
			(hide yes)
			(effects
				(font
					(size 1 1)
					(thickness 0.15)
				)
				(justify mirror)
			)
		)
		(property "License" "Apache-2.0"
			(at 355.357001 -60.843001 0)
			(layer "B.Fab")
			(hide yes)
			(effects
				(font
					(size 1 1)
					(thickness 0.15)
				)
				(justify mirror)
			)
		)
		(property "MPN" ""
			(at 355.357001 -60.843001 0)
			(layer "B.Fab")
			(hide yes)
			(effects
				(font
					(size 1 1)
					(thickness 0.15)
				)
				(justify mirror)
			)
		)
		(property "Manufacturer" ""
			(at 355.357001 -60.843001 0)
			(layer "B.Fab")
			(hide yes)
			(effects
				(font
					(size 1 1)
					(thickness 0.15)
				)
				(justify mirror)
			)
		)
		(sheetname "DC-DC Converters")
		(sheetfile "dc-dc.kicad_sch")
		(attr exclude_from_pos_files)
		(net_tie_pad_groups "1, 2")
		(fp_poly
			(pts
				(xy -0.0635 0.0635) (xy 0.0625 0.0635) (xy 0.0625 -0.0635) (xy -0.0635 -0.0635)
			)
			(stroke
				(width 0)
				(type solid)
			)
			(fill yes)
			(layer "B.Cu")
		)
		(pad "1" smd roundrect
			(at -0.127 0 270)
			(size 0.127 0.127)
			(layers "B.Cu")
			(roundrect_rratio 0.5)
			(chamfer_ratio 0)
			(chamfer top_left bottom_left)
			(net 1219 "/DC-DC Converters/SENSE_3V3_1_P")
			(pinfunction "1")
			(pintype "passive")
		)
		(pad "2" smd roundrect
			(at 0.126 0 90)
			(size 0.127 0.127)
			(layers "B.Cu")
			(roundrect_rratio 0.5)
			(chamfer_ratio 0)
			(chamfer top_left bottom_left)
			(net 24 "+3V3")
			(pinfunction "2")
			(pintype "passive")
		)
	)
	(footprint "antmicro-footprints:C_0402_1005Metric"
		(layer "B.Cu")
		(at 196.75 127.825)
		(descr "Capacitor SMD 0402")
		(tags "capacitor SMD 0402")
		(property "Reference" "C72"
			(at 25.075 -28.75 180)
			(layer "B.SilkS")
			(effects
				(font
					(size 0.7 0.7)
					(thickness 0.15)
				)
				(justify left bottom mirror)
			)
		)
		(property "Value" "C_100n_0402"
			(at 0 -1.169 180)
			(layer "B.Fab")
			(effects
				(font
					(size 0.7 0.7)
					(thickness 0.15)
				)
				(justify left bottom mirror)
			)
		)
		(property "Description" "SMD Multilayer Ceramic Capacitor, 0.1 µF, 50 V, 0402 [1005 Metric], ± 10%, X5R, GRM Series"
			(at 0 0 0)
			(layer "F.Fab")
			(hide yes)
			(effects
				(font
					(size 1.27 1.27)
					(thickness 0.15)
				)
			)
		)
		(property "Author" "Antmicro"
			(at 0 0 0)
			(layer "B.Fab")
			(hide yes)
			(effects
				(font
					(size 1 1)
					(thickness 0.15)
				)
				(justify mirror)
			)
		)
		(property "Dielectric" "X5R"
			(at 0 0 0)
			(layer "B.Fab")
			(hide yes)
			(effects
				(font
					(size 1 1)
					(thickness 0.15)
				)
				(justify mirror)
			)
		)
		(property "License" "Apache-2.0"
			(at 0 0 0)
			(layer "B.Fab")
			(hide yes)
			(effects
				(font
					(size 1 1)
					(thickness 0.15)
				)
				(justify mirror)
			)
		)
		(property "MPN" "GRM155R61H104KE14D"
			(at 0 0 0)
			(layer "B.Fab")
			(hide yes)
			(effects
				(font
					(size 1 1)
					(thickness 0.15)
				)
				(justify mirror)
			)
		)
		(property "Manufacturer" "Murata"
			(at 0 0 0)
			(layer "B.Fab")
			(hide yes)
			(effects
				(font
					(size 1 1)
					(thickness 0.15)
				)
				(justify mirror)
			)
		)
		(property "Val" "100n"
			(at 0 0 0)
			(layer "B.Fab")
			(hide yes)
			(effects
				(font
					(size 1 1)
					(thickness 0.15)
				)
				(justify mirror)
			)
		)
		(property "Voltage" "50V"
			(at 0 0 0)
			(layer "B.Fab")
			(hide yes)
			(effects
				(font
					(size 1 1)
					(thickness 0.15)
				)
				(justify mirror)
			)
		)
		(sheetname "FPGA supply")
		(sheetfile "fpga-supply.kicad_sch")
		(attr smd)
		(fp_rect
			(start -0.925 0.47)
			(end 0.925 -0.47)
			(stroke
				(width 0.05)
				(type default)
			)
			(fill no)
			(layer "B.CrtYd")
		)
		(fp_line
			(start -0.494 -0.248)
			(end -0.494 0.25)
			(stroke
				(width 0.15)
				(type solid)
			)
			(layer "B.Fab")
		)
		(fp_line
			(start -0.494 0.25)
			(end 0.504 0.25)
			(stroke
				(width 0.15)
				(type solid)
			)
			(layer "B.Fab")
		)
		(fp_line
			(start 0.504 -0.248)
			(end -0.494 -0.248)
			(stroke
				(width 0.15)
				(type solid)
			)
			(layer "B.Fab")
		)
		(fp_line
			(start 0.504 0.25)
			(end 0.504 -0.248)
			(stroke
				(width 0.15)
				(type solid)
			)
			(layer "B.Fab")
		)
		(pad "1" smd roundrect
			(at -0.48 0)
			(size 0.59 0.64)
			(layers "B.Cu" "B.Mask" "B.Paste")
			(roundrect_rratio 0.25)
			(net 1 "GND")
			(pintype "passive")
		)
		(pad "2" smd roundrect
			(at 0.48 0)
			(size 0.59 0.64)
			(layers "B.Cu" "B.Mask" "B.Paste")
			(roundrect_rratio 0.25)
			(net 26 "+1V8")
			(pintype "passive")
		)
	)
	(footprint "antmicro-footprints:C_0603_1608Metric"
		(layer "B.Cu")
		(at 200 115.65 -90)
		(descr "Capacitor SMD 0603")
		(tags "capacitor 0603")
		(property "Reference" "C2"
			(at -2.65 -0.375 90)
			(layer "B.SilkS")
			(effects
				(font
					(size 0.7 0.7)
					(thickness 0.15)
				)
				(justify left bottom mirror)
			)
		)
		(property "Value" "C_47u_0603"
			(at 0 -1.6 90)
			(layer "B.Fab")
			(effects
				(font
					(size 0.7 0.7)
					(thickness 0.15)
				)
				(justify left bottom mirror)
			)
		)
		(property "Description" "SMD Multilayer Ceramic Capacitor, 47 µF, 6.3 V, 0603 [1608 Metric], ± 20%, X5R, GRM Series"
			(at 0 0 270)
			(layer "F.Fab")
			(hide yes)
			(effects
				(font
					(size 1.27 1.27)
					(thickness 0.15)
				)
			)
		)
		(property "Author" "Antmicro"
			(at 84.35 315.65 0)
			(layer "B.Fab")
			(hide yes)
			(effects
				(font
					(size 1 1)
					(thickness 0.15)
				)
				(justify mirror)
			)
		)
		(property "Dielectric" ""
			(at 84.35 315.65 0)
			(layer "B.Fab")
			(hide yes)
			(effects
				(font
					(size 1 1)
					(thickness 0.15)
				)
				(justify mirror)
			)
		)
		(property "License" "Apache-2.0"
			(at 84.35 315.65 0)
			(layer "B.Fab")
			(hide yes)
			(effects
				(font
					(size 1 1)
					(thickness 0.15)
				)
				(justify mirror)
			)
		)
		(property "MPN" "GRM188R60J476ME15D"
			(at 84.35 315.65 0)
			(layer "B.Fab")
			(hide yes)
			(effects
				(font
					(size 1 1)
					(thickness 0.15)
				)
				(justify mirror)
			)
		)
		(property "Manufacturer" "Murata"
			(at 84.35 315.65 0)
			(layer "B.Fab")
			(hide yes)
			(effects
				(font
					(size 1 1)
					(thickness 0.15)
				)
				(justify mirror)
			)
		)
		(property "Val" "47u"
			(at 84.35 315.65 0)
			(layer "B.Fab")
			(hide yes)
			(effects
				(font
					(size 1 1)
					(thickness 0.15)
				)
				(justify mirror)
			)
		)
		(property "Voltage" ""
			(at 84.35 315.65 0)
			(layer "B.Fab")
			(hide yes)
			(effects
				(font
					(size 1 1)
					(thickness 0.15)
				)
				(justify mirror)
			)
		)
		(sheetname "FPGA Config")
		(sheetfile "fpga-config.kicad_sch")
		(attr smd)
		(fp_line
			(start -0.15 0.4)
			(end 0.15 0.4)
			(stroke
				(width 0.15)
				(type solid)
			)
			(layer "B.SilkS")
		)
		(fp_line
			(start -0.15 -0.4)
			(end 0.15 -0.4)
			(stroke
				(width 0.15)
				(type solid)
			)
			(layer "B.SilkS")
		)
		(fp_rect
			(start -1.25 0.65)
			(end 1.25 -0.65)
			(stroke
				(width 0.05)
				(type solid)
			)
			(fill no)
			(layer "B.CrtYd")
		)
		(fp_rect
			(start -0.8 0.4)
			(end 0.8 -0.4)
			(stroke
				(width 0.15)
				(type solid)
			)
			(fill no)
			(layer "B.Fab")
		)
		(pad "1" smd roundrect
			(at -0.7 0 270)
			(size 0.8 1)
			(layers "B.Cu" "B.Mask" "B.Paste")
			(roundrect_rratio 0.2)
			(net 1 "GND")
			(pintype "passive")
		)
		(pad "2" smd roundrect
			(at 0.7 0 270)
			(size 0.8 1)
			(layers "B.Cu" "B.Mask" "B.Paste")
			(roundrect_rratio 0.2)
			(net 24 "+3V3")
			(pintype "passive")
		)
	)
	(footprint "antmicro-footprints:C_0402_1005Metric"
		(layer "B.Cu")
		(at 213.5 121.025 -90)
		(descr "Capacitor SMD 0402")
		(tags "capacitor SMD 0402")
		(property "Reference" "C44"
			(at -1.1 -1.3 90)
			(layer "B.SilkS")
			(effects
				(font
					(size 0.7 0.7)
					(thickness 0.15)
				)
				(justify left bottom mirror)
			)
		)
		(property "Value" "C_100n_0402"
			(at 0 -1.169 90)
			(layer "B.Fab")
			(effects
				(font
					(size 0.7 0.7)
					(thickness 0.15)
				)
				(justify left bottom mirror)
			)
		)
		(property "Description" "SMD Multilayer Ceramic Capacitor, 0.1 µF, 50 V, 0402 [1005 Metric], ± 10%, X5R, GRM Series"
			(at 0 0 270)
			(layer "F.Fab")
			(hide yes)
			(effects
				(font
					(size 1.27 1.27)
					(thickness 0.15)
				)
			)
		)
		(property "Author" "Antmicro"
			(at 92.475 334.525 0)
			(layer "B.Fab")
			(hide yes)
			(effects
				(font
					(size 1 1)
					(thickness 0.15)
				)
				(justify mirror)
			)
		)
		(property "Dielectric" "X5R"
			(at 92.475 334.525 0)
			(layer "B.Fab")
			(hide yes)
			(effects
				(font
					(size 1 1)
					(thickness 0.15)
				)
				(justify mirror)
			)
		)
		(property "License" "Apache-2.0"
			(at 92.475 334.525 0)
			(layer "B.Fab")
			(hide yes)
			(effects
				(font
					(size 1 1)
					(thickness 0.15)
				)
				(justify mirror)
			)
		)
		(property "MPN" "GRM155R61H104KE14D"
			(at 92.475 334.525 0)
			(layer "B.Fab")
			(hide yes)
			(effects
				(font
					(size 1 1)
					(thickness 0.15)
				)
				(justify mirror)
			)
		)
		(property "Manufacturer" "Murata"
			(at 92.475 334.525 0)
			(layer "B.Fab")
			(hide yes)
			(effects
				(font
					(size 1 1)
					(thickness 0.15)
				)
				(justify mirror)
			)
		)
		(property "Val" "100n"
			(at 92.475 334.525 0)
			(layer "B.Fab")
			(hide yes)
			(effects
				(font
					(size 1 1)
					(thickness 0.15)
				)
				(justify mirror)
			)
		)
		(property "Voltage" "50V"
			(at 92.475 334.525 0)
			(layer "B.Fab")
			(hide yes)
			(effects
				(font
					(size 1 1)
					(thickness 0.15)
				)
				(justify mirror)
			)
		)
		(sheetname "FPGA Bank 16 & 17")
		(sheetfile "fpga-bank-16-17.kicad_sch")
		(attr smd)
		(fp_rect
			(start -0.925 0.47)
			(end 0.925 -0.47)
			(stroke
				(width 0.05)
				(type default)
			)
			(fill no)
			(layer "B.CrtYd")
		)
		(fp_line
			(start -0.494 0.25)
			(end 0.504 0.25)
			(stroke
				(width 0.15)
				(type solid)
			)
			(layer "B.Fab")
		)
		(fp_line
			(start 0.504 0.25)
			(end 0.504 -0.248)
			(stroke
				(width 0.15)
				(type solid)
			)
			(layer "B.Fab")
		)
		(fp_line
			(start -0.494 -0.248)
			(end -0.494 0.25)
			(stroke
				(width 0.15)
				(type solid)
			)
			(layer "B.Fab")
		)
		(fp_line
			(start 0.504 -0.248)
			(end -0.494 -0.248)
			(stroke
				(width 0.15)
				(type solid)
			)
			(layer "B.Fab")
		)
		(pad "1" smd roundrect
			(at -0.48 0 270)
			(size 0.59 0.64)
			(layers "B.Cu" "B.Mask" "B.Paste")
			(roundrect_rratio 0.25)
			(net 1 "GND")
			(pintype "passive")
		)
		(pad "2" smd roundrect
			(at 0.48 0 270)
			(size 0.59 0.64)
			(layers "B.Cu" "B.Mask" "B.Paste")
			(roundrect_rratio 0.25)
			(net 3 "VCC_USR_B")
			(pintype "passive")
		)
	)
	(footprint "antmicro-footprints:R_0402_1005Metric"
		(layer "B.Cu")
		(at 162.1625 175.3 90)
		(descr "Resistor SMD 0402")
		(tags "resistor SMD 0402")
		(property "Reference" "R310"
			(at -0.7 0.3875 270)
			(layer "B.SilkS")
			(effects
				(font
					(size 0.7 0.7)
					(thickness 0.15)
				)
				(justify left bottom mirror)
			)
		)
		(property "Value" "R_0R_0402"
			(at 0 -1.4 270)
			(layer "B.Fab")
			(effects
				(font
					(size 0.7 0.7)
					(thickness 0.15)
				)
				(justify left bottom mirror)
			)
		)
		(property "Description" "SMD Chip Resistor, Jumper, 0 ohm, 100 mW, 0402 [1005 Metric], Thick Film, General Purpose"
			(at 0 0 90)
			(layer "F.Fab")
			(hide yes)
			(effects
				(font
					(size 1.27 1.27)
					(thickness 0.15)
				)
			)
		)
		(property "Author" "Antmicro"
			(at 337.4625 13.1375 0)
			(layer "B.Fab")
			(hide yes)
			(effects
				(font
					(size 1 1)
					(thickness 0.15)
				)
				(justify mirror)
			)
		)
		(property "Current" "1A"
			(at 337.4625 13.1375 0)
			(layer "B.Fab")
			(hide yes)
			(effects
				(font
					(size 1 1)
					(thickness 0.15)
				)
				(justify mirror)
			)
		)
		(property "DNP" "DNP"
			(at 337.4625 13.1375 0)
			(layer "B.Fab")
			(hide yes)
			(effects
				(font
					(size 1 1)
					(thickness 0.15)
				)
				(justify mirror)
			)
		)
		(property "License" "Apache-2.0"
			(at 337.4625 13.1375 0)
			(layer "B.Fab")
			(hide yes)
			(effects
				(font
					(size 1 1)
					(thickness 0.15)
				)
				(justify mirror)
			)
		)
		(property "MPN" "ERJ2GE0R00X"
			(at 337.4625 13.1375 0)
			(layer "B.Fab")
			(hide yes)
			(effects
				(font
					(size 1 1)
					(thickness 0.15)
				)
				(justify mirror)
			)
		)
		(property "Manufacturer" "Panasonic"
			(at 337.4625 13.1375 0)
			(layer "B.Fab")
			(hide yes)
			(effects
				(font
					(size 1 1)
					(thickness 0.15)
				)
				(justify mirror)
			)
		)
		(property "Tolerance" ""
			(at 337.4625 13.1375 0)
			(layer "B.Fab")
			(hide yes)
			(effects
				(font
					(size 1 1)
					(thickness 0.15)
				)
				(justify mirror)
			)
		)
		(property "Val" "0R"
			(at 337.4625 13.1375 0)
			(layer "B.Fab")
			(hide yes)
			(effects
				(font
					(size 1 1)
					(thickness 0.15)
				)
				(justify mirror)
			)
		)
		(property "dnp" ""
			(at 337.4625 13.1375 0)
			(layer "B.Fab")
			(hide yes)
			(effects
				(font
					(size 1 1)
					(thickness 0.15)
				)
				(justify mirror)
			)
		)
		(property "exclude_from_bom" ""
			(at 337.4625 13.1375 0)
			(layer "B.Fab")
			(hide yes)
			(effects
				(font
					(size 1 1)
					(thickness 0.15)
				)
				(justify mirror)
			)
		)
		(sheetname "DC-DC Converters")
		(sheetfile "dc-dc.kicad_sch")
		(attr smd exclude_from_bom)
		(fp_rect
			(start -0.925 0.47)
			(end 0.925 -0.47)
			(stroke
				(width 0.05)
				(type default)
			)
			(fill no)
			(layer "B.CrtYd")
		)
		(fp_rect
			(start -0.5 0.25)
			(end 0.5 -0.25)
			(stroke
				(width 0.15)
				(type solid)
			)
			(fill no)
			(layer "B.Fab")
		)
		(pad "1" smd roundrect
			(at -0.48 0 90)
			(size 0.59 0.64)
			(layers "B.Cu" "B.Mask" "B.Paste")
			(roundrect_rratio 0.25)
			(net 1225 "/DC-DC Converters/SENSE_1V2_N")
			(pintype "passive")
		)
		(pad "2" smd roundrect
			(at 0.48 0 90)
			(size 0.59 0.64)
			(layers "B.Cu" "B.Mask" "B.Paste")
			(roundrect_rratio 0.25)
			(net 962 "/DC-DC Converters/FB3")
			(pintype "passive")
		)
	)
	(gr_rect
		(start 150 70)
		(end 270 190)
		(stroke
			(width 0.12)
			(type solid)
		)
		(fill no)
		(layer "Edge.Cuts")
	)
	(segment
		(start 244.615 119.365)
		(end 244.625 119.375)
		(width 0.4)
		(layer "F.Cu")
		(net 1)
	)
	(segment
		(start 168.985001 119.335001)
		(end 168.350001 119.970001)
		(width 0.256)
		(layer "F.Cu")
		(net 1)
	)
	(segment
		(start 194.575 108)
		(end 192.85 108)
		(width 0.182)
		(layer "F.Cu")
		(net 1)
	)
	(segment
		(start 161.365001 87.585001)
		(end 160.730001 86.950001)
		(width 0.201)
		(layer "F.Cu")
		(net 1)
	)
	(segment
		(start 169.620001 99.650001)
		(end 170.255001 100.285001)
		(width 0.201)
		(layer "F.Cu")
		(net 1)
	)
	(segment
		(start 196.5 128.5)
		(end 196 128)
		(width 0.4)
		(layer "F.Cu")
		(net 1)
	)
	(segment
		(start 167.715001 130.765001)
		(end 168.350001 130.130001)
		(width 0.256)
		(layer "F.Cu")
		(net 1)
	)
	(segment
		(start 166.98 164.65)
		(end 166.41 165.22)
		(width 0.4)
		(layer "F.Cu")
		(net 1)
	)
	(segment
		(start 219.875 130.275)
		(end 220.25 130.65)
		(width 0.184)
		(layer "F.Cu")
		(net 1)
	)
	(segment
		(start 166.445001 119.335001)
		(end 165.810001 119.970001)
		(width 0.256)
		(layer "F.Cu")
		(net 1)
	)
	(segment
		(start 248.65 135.65)
		(end 248.4 135.9)
		(width 0.201)
		(layer "F.Cu")
		(net 1)
	)
	(segment
		(start 234.7995 132.76)
		(end 233.9145 131.875)
		(width 0.4)
		(layer "F.Cu")
		(net 1)
	)
	(segment
		(start 246.15 128.9)
		(end 246.65 128.9)
		(width 0.201)
		(layer "F.Cu")
		(net 1)
	)
	(segment
		(start 156.285001 118.070001)
		(end 155.650001 117.435001)
		(width 0.256)
		(layer "F.Cu")
		(net 1)
	)
	(segment
		(start 204.5 143.5)
		(end 205 144)
		(width 0.4)
		(layer "F.Cu")
		(net 1)
	)
	(segment
		(start 190.4 152.885001)
		(end 191.485001 152.885001)
		(width 0.4)
		(layer "F.Cu")
		(net 1)
	)
	(segment
		(start 168.985001 109.175001)
		(end 168.350001 109.810001)
		(width 0.256)
		(layer "F.Cu")
		(net 1)
	)
	(segment
		(start 161.365001 82.505001)
		(end 162.000001 81.870001)
		(width 0.256)
		(layer "F.Cu")
		(net 1)
	)
	(segment
		(start 192.015 183.764999)
		(end 191.525 183.274999)
		(width 0.182)
		(layer "F.Cu")
		(net 1)
	)
	(segment
		(start 162.000001 117.430001)
		(end 161.365001 118.065001)
		(width 0.256)
		(layer "F.Cu")
		(net 1)
	)
	(segment
		(start 157.555001 90.125001)
		(end 158.190001 89.490001)
		(width 0.256)
		(layer "F.Cu")
		(net 1)
	)
	(segment
		(start 173.2 143.2)
		(end 173.2 142.4)
		(width 0.4)
		(layer "F.Cu")
		(net 1)
	)
	(segment
		(start 166.445001 83.775001)
		(end 165.810001 84.410001)
		(width 0.201)
		(layer "F.Cu")
		(net 1)
	)
	(segment
		(start 167.6 188.203)
		(end 167.547 188.15)
		(width 0.198)
		(layer "F.Cu")
		(net 1)
	)
	(segment
		(start 244.615 118.9)
		(end 244.615 119.365)
		(width 0.4)
		(layer "F.Cu")
		(net 1)
	)
	(segment
		(start 169.620001 112.350001)
		(end 168.985001 112.985001)
		(width 0.201)
		(layer "F.Cu")
		(net 1)
	)
	(segment
		(start 243.3 136.6)
		(end 243.3 136.95)
		(width 0.201)
		(layer "F.Cu")
		(net 1)
	)
	(segment
		(start 156.285001 95.200001)
		(end 155.655001 94.570001)
		(width 0.201)
		(layer "F.Cu")
		(net 1)
	)
	(segment
		(start 201.182504 99.9)
		(end 200.291252 99.9)
		(width 0.4)
		(layer "F.Cu")
		(net 1)
	)
	(segment
		(start 254.9 98.5)
		(end 254.3 98.5)
		(width 0.182)
		(layer "F.Cu")
		(net 1)
	)
	(segment
		(start 167.715001 95.205001)
		(end 167.080001 94.570001)
		(width 0.201)
		(layer "F.Cu")
		(net 1)
	)
	(segment
		(start 254.85 140.45)
		(end 254.5 140.1)
		(width 0.4)
		(layer "F.Cu")
		(net 1)
	)
	(segment
		(start 207.9 91.1)
		(end 207.552499 91.1)
		(width 0.182)
		(layer "F.Cu")
		(net 1)
	)
	(segment
		(start 167.715001 95.205001)
		(end 168.350001 94.570001)
		(width 0.201)
		(layer "F.Cu")
		(net 1)
	)
	(segment
		(start 173.2 142.4)
		(end 173.2 142.175)
		(width 0.4)
		(layer "F.Cu")
		(net 1)
	)
	(segment
		(start 225.7 147)
		(end 226.2 146.5)
		(width 0.256)
		(layer "F.Cu")
		(net 1)
	)
	(segment
		(start 167.715001 86.315001)
		(end 168.350001 86.950001)
		(width 0.256)
		(layer "F.Cu")
		(net 1)
	)
	(segment
		(start 195.600001 163.749999)
		(end 195.600001 164.115001)
		(width 0.177)
		(layer "F.Cu")
		(net 1)
	)
	(segment
		(start 165.175001 105.365001)
		(end 165.810001 104.730001)
		(width 0.201)
		(layer "F.Cu")
		(net 1)
	)
	(segment
		(start 164.540001 112.350001)
		(end 163.905001 111.715001)
		(width 0.201)
		(layer "F.Cu")
		(net 1)
	)
	(segment
		(start 245.15 150.075)
		(end 244.675 150.075)
		(width 0.256)
		(layer "F.Cu")
		(net 1)
	)
	(segment
		(start 254.85 141.75)
		(end 254.85 140.45)
		(width 0.4)
		(layer "F.Cu")
		(net 1)
	)
	(segment
		(start 221 146.7)
		(end 220.55 146.7)
		(width 0.256)
		(layer "F.Cu")
		(net 1)
	)
	(segment
		(start 200.241252 99.85)
		(end 200.241252 100.541252)
		(width 0.4)
		(layer "F.Cu")
		(net 1)
	)
	(segment
		(start 202.5 137.5)
		(end 203 138)
		(width 0.4)
		(layer "F.Cu")
		(net 1)
	)
	(segment
		(start 153.745001 91.395001)
		(end 154.380001 92.030001)
		(width 0.256)
		(layer "F.Cu")
		(net 1)
	)
	(segment
		(start 166.445001 112.985001)
		(end 165.810001 112.350001)
		(width 0.256)
		(layer "F.Cu")
		(net 1)
	)
	(segment
		(start 225.775 116.45)
		(end 227.17 115.055)
		(width 0.4)
		(layer "F.Cu")
		(net 1)
	)
	(segment
		(start 199.3 102.5)
		(end 198.7 101.9)
		(width 0.182)
		(layer "F.Cu")
		(net 1)
	)
	(segment
		(start 162.635001 101.555001)
		(end 162.000001 102.190001)
		(width 0.256)
		(layer "F.Cu")
		(net 1)
	)
	(segment
		(start 257.45 91.65)
		(end 258.235 91.65)
		(width 0.256)
		(layer "F.Cu")
		(net 1)
	)
	(segment
		(start 156.2 143.78)
		(end 156.21 143.77)
		(width 0.4)
		(layer "F.Cu")
		(net 1)
	)
	(segment
		(start 194.445001 84.287501)
		(end 194.445001 86.145001)
		(width 0.201)
		(layer "F.Cu")
		(net 1)
	)
	(segment
		(start 155.6 149.5625)
		(end 155.6 149)
		(width 0.201)
		(layer "F.Cu")
		(net 1)
	)
	(segment
		(start 155.020001 112.985001)
		(end 154.385001 112.350001)
		(width 0.256)
		(layer "F.Cu")
		(net 1)
	)
	(segment
		(start 165.175001 125.685001)
		(end 165.810001 125.050001)
		(width 0.256)
		(layer "F.Cu")
		(net 1)
	)
	(segment
		(start 258.4075 138.135)
		(end 257.13 138.135)
		(width 0.201)
		(layer "F.Cu")
		(net 1)
	)
	(segment
		(start 209.365 157.56)
		(end 209.35 157.575)
		(width 0.4)
		(layer "F.Cu")
		(net 1)
	)
	(segment
		(start 165.175001 115.525001)
		(end 164.540001 114.890001)
		(width 0.256)
		(layer "F.Cu")
		(net 1)
	)
	(segment
		(start 168.985001 129.495001)
		(end 168.350001 130.130001)
		(width 0.256)
		(layer "F.Cu")
		(net 1)
	)
	(segment
		(start 153.745001 120.605001)
		(end 154.380001 119.970001)
		(width 0.256)
		(layer "F.Cu")
		(net 1)
	)
	(segment
		(start 196.585 166.74)
		(end 196.525 166.8)
		(width 0.201)
		(layer "F.Cu")
		(net 1)
	)
	(segment
		(start 200.5 126.5)
		(end 201 126)
		(width 0.4)
		(layer "F.Cu")
		(net 1)
	)
	(segment
		(start 193.5 125.5)
		(end 193.3 125.7)
		(width 0.4)
		(layer "F.Cu")
		(net 1)
	)
	(segment
		(start 261.7 76.15)
		(end 261.7 71.85)
		(width 0.4)
		(layer "F.Cu")
		(net 1)
	)
	(segment
		(start 160.095001 130.765001)
		(end 160.730001 130.130001)
		(width 0.256)
		(layer "F.Cu")
		(net 1)
	)
	(segment
		(start 245.65 150.075)
		(end 245.65 149.15)
		(width 0.256)
		(layer "F.Cu")
		(net 1)
	)
	(segment
		(start 190.85 176.15)
		(end 191.325 175.675)
		(width 0.182)
		(layer "F.Cu")
		(net 1)
	)
	(segment
		(start 155.015001 112.985001)
		(end 155.020001 112.985001)
		(width 0.256)
		(layer "F.Cu")
		(net 1)
	)
	(segment
		(start 255.385 101)
		(end 256.65 101)
		(width 0.4)
		(layer "F.Cu")
		(net 1)
	)
	(segment
		(start 233.5995 128.5485)
		(end 233.5995 128.9845)
		(width 0.182)
		(layer "F.Cu")
		(net 1)
	)
	(segment
		(start 158.825001 87.585001)
		(end 159.460001 86.950001)
		(width 0.256)
		(layer "F.Cu")
		(net 1)
	)
	(segment
		(start 268.85 87.8)
		(end 268.8 87.8)
		(width 0.1)
		(layer "F.Cu")
		(net 1)
	)
	(segment
		(start 256.82 140.32)
		(end 256.4 139.9)
		(width 0.201)
		(layer "F.Cu")
		(net 1)
	)
	(segment
		(start 261.2 101.25)
		(end 261.25 101.3)
		(width 0.182)
		(layer "F.Cu")
		(net 1)
	)
	(segment
		(start 221.3 165.685)
		(end 221.285 165.7)
		(width 0.201)
		(layer "F.Cu")
		(net 1)
	)
	(segment
		(start 166.445001 128.225001)
		(end 165.810001 127.590001)
		(width 0.256)
		(layer "F.Cu")
		(net 1)
	)
	(segment
		(start 198.022851 93.1)
		(end 200.7 93.1)
		(width 0.4)
		(layer "F.Cu")
		(net 1)
	)
	(segment
		(start 205.076252 99.45)
		(end 205.091252 99.435)
		(width 0.182)
		(layer "F.Cu")
		(net 1)
	)
	(segment
		(start 245.485 113.9)
		(end 244.735 113.15)
		(width 0.1)
		(layer "F.Cu")
		(net 1)
	)
	(segment
		(start 258.85 145.65)
		(end 258.4 145.2)
		(width 0.4)
		(layer "F.Cu")
		(net 1)
	)
	(segment
		(start 207.5 142.5)
		(end 208 143)
		(width 0.4)
		(layer "F.Cu")
		(net 1)
	)
	(segment
		(start 207.891252 97.535)
		(end 207.876252 97.55)
		(width 0.182)
		(layer "F.Cu")
		(net 1)
	)
	(segment
		(start 170.255001 96.475001)
		(end 169.620001 97.110001)
		(width 0.256)
		(layer "F.Cu")
		(net 1)
	)
	(segment
		(start 223.4475 161.3475)
		(end 223.55 161.45)
		(width 0.201)
		(layer "F.Cu")
		(net 1)
	)
	(segment
		(start 209.5 138.5)
		(end 210 139)
		(width 0.4)
		(layer "F.Cu")
		(net 1)
	)
	(segment
		(start 155.015001 87.585001)
		(end 155.650001 86.950001)
		(width 0.256)
		(layer "F.Cu")
		(net 1)
	)
	(segment
		(start 165.175001 100.285001)
		(end 165.810001 99.650001)
		(width 0.201)
		(layer "F.Cu")
		(net 1)
	)
	(segment
		(start 169.620001 119.970001)
		(end 168.985001 119.335001)
		(width 0.256)
		(layer "F.Cu")
		(net 1)
	)
	(segment
		(start 215.35 163.15)
		(end 215.4 163.1)
		(width 0.201)
		(layer "F.Cu")
		(net 1)
	)
	(segment
		(start 167.080001 99.650001)
		(end 167.715001 100.285001)
		(width 0.201)
		(layer "F.Cu")
		(net 1)
	)
	(segment
		(start 207.341252 102.508748)
		(end 207.35 102.5)
		(width 0.4)
		(layer "F.Cu")
		(net 1)
	)
	(segment
		(start 170.255001 81.235001)
		(end 169.620001 81.870001)
		(width 0.256)
		(layer "F.Cu")
		(net 1)
	)
	(segment
		(start 168.985001 87.585001)
		(end 169.620001 86.950001)
		(width 0.256)
		(layer "F.Cu")
		(net 1)
	)
	(segment
		(start 156.285001 82.505001)
		(end 155.650001 81.870001)
		(width 0.201)
		(layer "F.Cu")
		(net 1)
	)
	(segment
		(start 172.05 169.2125)
		(end 172.9625 169.2125)
		(width 0.182)
		(layer "F.Cu")
		(net 1)
	)
	(segment
		(start 167.715001 125.685001)
		(end 168.350001 125.050001)
		(width 0.256)
		(layer "F.Cu")
		(net 1)
	)
	(segment
		(start 204.93 105.03)
		(end 204.925 105.025)
		(width 0.4)
		(layer "F.Cu")
		(net 1)
	)
	(segment
		(start 201.206252 101.9)
		(end 200.316752 101.9)
		(width 0.4)
		(layer "F.Cu")
		(net 1)
	)
	(segment
		(start 218.8 155.585)
		(end 219.485 155.585)
		(width 0.256)
		(layer "F.Cu")
		(net 1)
	)
	(segment
		(start 183.77 187.84)
		(end 183.77 188.63)
		(width 0.4)
		(layer "F.Cu")
		(net 1)
	)
	(segment
		(start 228.94 140.05)
		(end 228.725 140.265)
		(width 0.256)
		(layer "F.Cu")
		(net 1)
	)
	(segment
		(start 168.985001 107.905001)
		(end 168.350001 107.270001)
		(width 0.256)
		(layer "F.Cu")
		(net 1)
	)
	(segment
		(start 165.175001 106.635001)
		(end 164.540001 107.270001)
		(width 0.256)
		(layer "F.Cu")
		(net 1)
	)
	(segment
		(start 155.015001 99.015001)
		(end 155.650001 99.650001)
		(width 0.201)
		(layer "F.Cu")
		(net 1)
	)
	(segment
		(start 261.95 150.55)
		(end 262.05 150.55)
		(width 0.201)
		(layer "F.Cu")
		(net 1)
	)
	(segment
		(start 167.599999 148.800003)
		(end 168 149.200004)
		(width 0.177)
		(layer "F.Cu")
		(net 1)
	)
	(segment
		(start 160.095001 85.045001)
		(end 160.730001 84.410001)
		(width 0.256)
		(layer "F.Cu")
		(net 1)
	)
	(segment
		(start 238.375 139.6)
		(end 238.375 139.925)
		(width 0.182)
		(layer "F.Cu")
		(net 1)
	)
	(segment
		(start 163.905001 129.495001)
		(end 163.270001 130.130001)
		(width 0.256)
		(layer "F.Cu")
		(net 1)
	)
	(segment
		(start 156.285001 129.495001)
		(end 155.650001 130.130001)
		(width 0.256)
		(layer "F.Cu")
		(net 1)
	)
	(segment
		(start 153.1 154.7)
		(end 153 154.6)
		(width 0.256)
		(layer "F.Cu")
		(net 1)
	)
	(segment
		(start 167.6 188.9)
		(end 167.6 188.203)
		(width 0.198)
		(layer "F.Cu")
		(net 1)
	)
	(segment
		(start 162.635001 81.235001)
		(end 163.270001 81.870001)
		(width 0.256)
		(layer "F.Cu")
		(net 1)
	)
	(segment
		(start 253.965 140.635)
		(end 253.545 140.635)
		(width 0.201)
		(layer "F.Cu")
		(net 1)
	)
	(segment
		(start 164.4 148.8)
		(end 164.4 148.925)
		(width 0.4)
		(layer "F.Cu")
		(net 1)
	)
	(segment
		(start 200.7 93.1)
		(end 201.45 93.85)
		(width 0.4)
		(layer "F.Cu")
		(net 1)
	)
	(segment
		(start 191.925 176.165)
		(end 191.815 176.165)
		(width 0.182)
		(layer "F.Cu")
		(net 1)
	)
	(segment
		(start 201.5 131.5)
		(end 202 132)
		(width 0.4)
		(layer "F.Cu")
		(net 1)
	)
	(segment
		(start 159.95 188.203)
		(end 159.947 188.2)
		(width 0.182)
		(layer "F.Cu")
		(net 1)
	)
	(segment
		(start 168.985001 124.415001)
		(end 168.350001 125.050001)
		(width 0.256)
		(layer "F.Cu")
		(net 1)
	)
	(segment
		(start 156.285001 82.505001)
		(end 156.920001 81.870001)
		(width 0.256)
		(layer "F.Cu")
		(net 1)
	)
	(segment
		(start 190.775 183.749999)
		(end 191.05 183.749999)
		(width 0.182)
		(layer "F.Cu")
		(net 1)
	)
	(segment
		(start 167.78 164.65)
		(end 168.58 164.65)
		(width 0.4)
		(layer "F.Cu")
		(net 1)
	)
	(segment
		(start 168.985001 128.225001)
		(end 168.350001 127.590001)
		(width 0.256)
		(layer "F.Cu")
		(net 1)
	)
	(segment
		(start 155.015001 99.015001)
		(end 154.380001 99.650001)
		(width 0.256)
		(layer "F.Cu")
		(net 1)
	)
	(segment
		(start 164.4 142.4)
		(end 163.9 141.9)
		(width 0.4)
		(layer "F.Cu")
		(net 1)
	)
	(segment
		(start 263.65 134.15)
		(end 263.65 133.75)
		(width 0.201)
		(layer "F.Cu")
		(net 1)
	)
	(segment
		(start 152.175 146.325)
		(end 152.5 146.65)
		(width 0.201)
		(layer "F.Cu")
		(net 1)
	)
	(segment
		(start 259.45 145.65)
		(end 258.85 145.65)
		(width 0.4)
		(layer "F.Cu")
		(net 1)
	)
	(segment
		(start 172.9625 169.2125)
		(end 172.975 169.2)
		(width 0.182)
		(layer "F.Cu")
		(net 1)
	)
	(segment
		(start 153.745001 116.795001)
		(end 154.380001 117.430001)
		(width 0.256)
		(layer "F.Cu")
		(net 1)
	)
	(segment
		(start 257.45 82.05)
		(end 258.235 82.05)
		(width 0.256)
		(layer "F.Cu")
		(net 1)
	)
	(segment
		(start 160.095001 81.235001)
		(end 160.730001 81.870001)
		(width 0.256)
		(layer "F.Cu")
		(net 1)
	)
	(segment
		(start 192.5 116.5)
		(end 193.5 116.5)
		(width 0.4)
		(layer "F.Cu")
		(net 1)
	)
	(segment
		(start 167.715001 100.285001)
		(end 168.350001 99.650001)
		(width 0.201)
		(layer "F.Cu")
		(net 1)
	)
	(segment
		(start 192.125 183.764999)
		(end 192.015 183.764999)
		(width 0.182)
		(layer "F.Cu")
		(net 1)
	)
	(segment
		(start 167.715001 101.555001)
		(end 167.080001 102.190001)
		(width 0.256)
		(layer "F.Cu")
		(net 1)
	)
	(segment
		(start 245.275 149)
		(end 245.15 149.125)
		(width 0.256)
		(layer "F.Cu")
		(net 1)
	)
	(segment
		(start 196.5 130.5)
		(end 196 131)
		(width 0.4)
		(layer "F.Cu")
		(net 1)
	)
	(segment
		(start 163.9 140.3)
		(end 164.2 140)
		(width 0.4)
		(layer "F.Cu")
		(net 1)
	)
	(segment
		(start 199.35 87.2)
		(end 199.35 87.825)
		(width 0.182)
		(layer "F.Cu")
		(net 1)
	)
	(segment
		(start 195.5 127.5)
		(end 195 127)
		(width 0.4)
		(layer "F.Cu")
		(net 1)
	)
	(segment
		(start 201.5 127.5)
		(end 202 127)
		(width 0.4)
		(layer "F.Cu")
		(net 1)
	)
	(segment
		(start 207.891252 92.65)
		(end 207.65 92.65)
		(width 0.182)
		(layer "F.Cu")
		(net 1)
	)
	(segment
		(start 229.62 121.83)
		(end 226.97235 121.83)
		(width 0.4)
		(layer "F.Cu")
		(net 1)
	)
	(segment
		(start 196.07 175.2)
		(end 195.5 175.2)
		(width 0.1)
		(layer "F.Cu")
		(net 1)
	)
	(segment
		(start 170.255001 110.445001)
		(end 169.620001 109.810001)
		(width 0.256)
		(layer "F.Cu")
		(net 1)
	)
	(segment
		(start 247.6 118.9)
		(end 248.225 118.9)
		(width 0.4)
		(layer "F.Cu")
		(net 1)
	)
	(segment
		(start 228.15 161.5)
		(end 228.15 163.18)
		(width 0.201)
		(layer "F.Cu")
		(net 1)
	)
	(segment
		(start 156.285001 110.445001)
		(end 156.920001 109.810001)
		(width 0.201)
		(layer "F.Cu")
		(net 1)
	)
	(segment
		(start 191.05 182.799999)
		(end 191.525 183.274999)
		(width 0.182)
		(layer "F.Cu")
		(net 1)
	)
	(segment
		(start 160.095001 93.935001)
		(end 159.460001 94.570001)
		(width 0.256)
		(layer "F.Cu")
		(net 1)
	)
	(segment
		(start 245.65 128.85)
		(end 245.7 128.9)
		(width 0.201)
		(layer "F.Cu")
		(net 1)
	)
	(segment
		(start 166.175 142.225)
		(end 166.275 142.225)
		(width 0.1)
		(layer "F.Cu")
		(net 1)
	)
	(segment
		(start 167.715001 106.635001)
		(end 168.350001 107.270001)
		(width 0.201)
		(layer "F.Cu")
		(net 1)
	)
	(segment
		(start 151.625 156.225)
		(end 151.49 156.225)
		(width 0.4)
		(layer "F.Cu")
		(net 1)
	)
	(segment
		(start 200.5 141.5)
		(end 201 142)
		(width 0.4)
		(layer "F.Cu")
		(net 1)
	)
	(segment
		(start 165.175001 101.555001)
		(end 164.540001 102.190001)
		(width 0.256)
		(layer "F.Cu")
		(net 1)
	)
	(segment
		(start 153.745001 101.555001)
		(end 154.380001 102.190001)
		(width 0.256)
		(layer "F.Cu")
		(net 1)
	)
	(segment
		(start 167.715001 106.635001)
		(end 167.080001 107.270001)
		(width 0.256)
		(layer "F.Cu")
		(net 1)
	)
	(segment
		(start 168.985001 112.985001)
		(end 168.350001 112.350001)
		(width 0.256)
		(layer "F.Cu")
		(net 1)
	)
	(segment
		(start 193.5 134.5)
		(end 193 134)
		(width 0.4)
		(layer "F.Cu")
		(net 1)
	)
	(segment
		(start 156.285001 110.445001)
		(end 155.650001 109.810001)
		(width 0.256)
		(layer "F.Cu")
		(net 1)
	)
	(segment
		(start 201.5 134.5)
		(end 202 135)
		(width 0.4)
		(layer "F.Cu")
		(net 1)
	)
	(segment
		(start 233.9145 131.875)
		(end 232.3 131.875)
		(width 0.4)
		(layer "F.Cu")
		(net 1)
	)
	(segment
		(start 163.905001 129.495001)
		(end 164.540001 130.130001)
		(width 0.256)
		(layer "F.Cu")
		(net 1)
	)
	(segment
		(start 162.635001 124.415001)
		(end 162.000001 125.050001)
		(width 0.256)
		(layer "F.Cu")
		(net 1)
	)
	(segment
		(start 205.101 76.383)
		(end 205.101 72.083)
		(width 0.4)
		(layer "F.Cu")
		(net 1)
	)
	(segment
		(start 222.4543 161.3475)
		(end 223.4475 161.3475)
		(width 0.201)
		(layer "F.Cu")
		(net 1)
	)
	(segment
		(start 153.745001 115.525001)
		(end 154.380001 114.890001)
		(width 0.256)
		(layer "F.Cu")
		(net 1)
	)
	(segment
		(start 259.115 128.5)
		(end 258.4 128.5)
		(width 0.201)
		(layer "F.Cu")
		(net 1)
	)
	(segment
		(start 170.255001 85.045001)
		(end 168.985001 83.775001)
		(width 0.256)
		(layer "F.Cu")
		(net 1)
	)
	(segment
		(start 161.365001 110.445001)
		(end 160.730001 109.810001)
		(width 0.256)
		(layer "F.Cu")
		(net 1)
	)
	(segment
		(start 158.825001 87.585001)
		(end 158.190001 86.950001)
		(width 0.201)
		(layer "F.Cu")
		(net 1)
	)
	(segment
		(start 153.745001 125.685001)
		(end 154.380001 125.050001)
		(width 0.256)
		(layer "F.Cu")
		(net 1)
	)
	(segment
		(start 256.845 134.285)
		(end 256.845 133.75)
		(width 0.198)
		(layer "F.Cu")
		(net 1)
	)
	(segment
		(start 227.15 161.5)
		(end 227.15 162.18)
		(width 0.201)
		(layer "F.Cu")
		(net 1)
	)
	(segment
		(start 166.445001 118.065001)
		(end 165.810001 117.430001)
		(width 0.256)
		(layer "F.Cu")
		(net 1)
	)
	(segment
		(start 160.2 143.75)
		(end 160.2 144.854)
		(width 0.1)
		(layer "F.Cu")
		(net 1)
	)
	(segment
		(start 166.445001 99.015001)
		(end 165.810001 99.650001)
		(width 0.256)
		(layer "F.Cu")
		(net 1)
	)
	(segment
		(start 153.745001 126.955001)
		(end 154.380001 127.590001)
		(width 0.256)
		(layer "F.Cu")
		(net 1)
	)
	(segment
		(start 162.635001 112.985001)
		(end 163.270001 112.350001)
		(width 0.256)
		(layer "F.Cu")
		(net 1)
	)
	(segment
		(start 157.215 147.9)
		(end 157.1 147.9)
		(width 0.4)
		(layer "F.Cu")
		(net 1)
	)
	(segment
		(start 156.285001 106.635001)
		(end 156.920001 107.270001)
		(width 0.256)
		(layer "F.Cu")
		(net 1)
	)
	(segment
		(start 164.215 139)
		(end 164 139)
		(width 0.4)
		(layer "F.Cu")
		(net 1)
	)
	(segment
		(start 240.6 133.1)
		(end 240.8 133.3)
		(width 0.182)
		(layer "F.Cu")
		(net 1)
	)
	(segment
		(start 222.4 149.487636)
		(end 222.386864 149.4745)
		(width 0.201)
		(layer "F.Cu")
		(net 1)
	)
	(segment
		(start 218.715 138.425)
		(end 218.715 139.21)
		(width 0.256)
		(layer "F.Cu")
		(net 1)
	)
	(segment
		(start 170 143.2)
		(end 170.4 143.6)
		(width 0.4)
		(layer "F.Cu")
		(net 1)
	)
	(segment
		(start 240.85 138.2)
		(end 239.725 138.2)
		(width 0.256)
		(layer "F.Cu")
		(net 1)
	)
	(segment
		(start 230.425 121.025)
		(end 229.62 121.83)
		(width 0.4)
		(layer "F.Cu")
		(net 1)
	)
	(segment
		(start 163.905001 100.285001)
		(end 164.540001 99.650001)
		(width 0.256)
		(layer "F.Cu")
		(net 1)
	)
	(segment
		(start 155.015001 104.095001)
		(end 154.380001 104.730001)
		(width 0.256)
		(layer "F.Cu")
		(net 1)
	)
	(segment
		(start 168.985001 104.095001)
		(end 168.350001 104.730001)
		(width 0.256)
		(layer "F.Cu")
		(net 1)
	)
	(segment
		(start 166.445001 123.145001)
		(end 167.080001 122.510001)
		(width 0.256)
		(layer "F.Cu")
		(net 1)
	)
	(segment
		(start 225.985 131.185)
		(end 225.5 131.185)
		(width 0.256)
		(layer "F.Cu")
		(net 1)
	)
	(segment
		(start 245.15 128.75)
		(end 245.3 128.9)
		(width 0.201)
		(layer "F.Cu")
		(net 1)
	)
	(segment
		(start 193.29 115.71)
		(end 193.29 116.29)
		(width 0.4)
		(layer "F.Cu")
		(net 1)
	)
	(segment
		(start 268.095 138.55)
		(end 267.335 139.31)
		(width 0.182)
		(layer "F.Cu")
		(net 1)
	)
	(segment
		(start 186.5 139.5)
		(end 186 140)
		(width 0.4)
		(layer "F.Cu")
		(net 1)
	)
	(segment
		(start 165.175001 120.605001)
		(end 165.810001 119.970001)
		(width 0.256)
		(layer "F.Cu")
		(net 1)
	)
	(segment
		(start 199.5 138.5)
		(end 199 139)
		(width 0.4)
		(layer "F.Cu")
		(net 1)
	)
	(segment
		(start 221.3 165.05)
		(end 221.3 165.685)
		(width 0.201)
		(layer "F.Cu")
		(net 1)
	)
	(segment
		(start 232.6 140.25)
		(end 231.45 140.25)
		(width 0.182)
		(layer "F.Cu")
		(net 1)
	)
	(segment
		(start 252.901498 134.65)
		(end 249.65 134.65)
		(width 0.201)
		(layer "F.Cu")
		(net 1)
	)
	(segment
		(start 228.725 137.315)
		(end 228.815 137.315)
		(width 0.256)
		(layer "F.Cu")
		(net 1)
	)
	(segment
		(start 170.255001 105.365001)
		(end 169.620001 104.730001)
		(width 0.201)
		(layer "F.Cu")
		(net 1)
	)
	(segment
		(start 165.175001 95.205001)
		(end 165.810001 94.570001)
		(width 0.201)
		(layer "F.Cu")
		(net 1)
	)
	(segment
		(start 206.5 129.5)
		(end 207 129)
		(width 0.4)
		(layer "F.Cu")
		(net 1)
	)
	(segment
		(start 201.5 144.5)
		(end 202 145)
		(width 0.4)
		(layer "F.Cu")
		(net 1)
	)
	(segment
		(start 195.85 104.2)
		(end 195.85 103.7088)
		(width 0.182)
		(layer "F.Cu")
		(net 1)
	)
	(segment
		(start 161.365001 110.445001)
		(end 162.000001 109.810001)
		(width 0.201)
		(layer "F.Cu")
		(net 1)
	)
	(segment
		(start 223.4225 160.0775)
		(end 223.55 159.95)
		(width 0.201)
		(layer "F.Cu")
		(net 1)
	)
	(segment
		(start 167.080001 89.490001)
		(end 166.445001 88.855001)
		(width 0.201)
		(layer "F.Cu")
		(net 1)
	)
	(segment
		(start 166.445001 92.665001)
		(end 167.080001 92.030001)
		(width 0.201)
		(layer "F.Cu")
		(net 1)
	)
	(segment
		(start 202.5 132.5)
		(end 203 133)
		(width 0.4)
		(layer "F.Cu")
		(net 1)
	)
	(segment
		(start 158.825001 125.685001)
		(end 158.190001 125.050001)
		(width 0.256)
		(layer "F.Cu")
		(net 1)
	)
	(segment
		(start 245.5 149)
		(end 245.275 149)
		(width 0.256)
		(layer "F.Cu")
		(net 1)
	)
	(segment
		(start 203.641252 101.875)
		(end 203.735 101.875)
		(width 0.4)
		(layer "F.Cu")
		(net 1)
	)
	(segment
		(start 165.175001 101.555001)
		(end 165.810001 102.190001)
		(width 0.256)
		(layer "F.Cu")
		(net 1)
	)
	(segment
		(start 257.45 89.25)
		(end 258.235 89.25)
		(width 0.256)
		(layer "F.Cu")
		(net 1)
	)
	(segment
		(start 268.1 138.55)
		(end 268.095 138.55)
		(width 0.182)
		(layer "F.Cu")
		(net 1)
	)
	(segment
		(start 249.65 134.65)
		(end 248.4 135.9)
		(width 0.201)
		(layer "F.Cu")
		(net 1)
	)
	(segment
		(start 258.235 89.25)
		(end 258.4 89.085)
		(width 0.256)
		(layer "F.Cu")
		(net 1)
	)
	(segment
		(start 164.215 139)
		(end 164.215 139.985)
		(width 0.4)
		(layer "F.Cu")
		(net 1)
	)
	(segment
		(start 168.985001 124.415001)
		(end 169.620001 125.050001)
		(width 0.256)
		(layer "F.Cu")
		(net 1)
	)
	(segment
		(start 167.715001 126.955001)
		(end 167.080001 127.590001)
		(width 0.256)
		(layer "F.Cu")
		(net 1)
	)
	(segment
		(start 161.365001 114.255001)
		(end 162.000001 114.890001)
		(width 0.256)
		(layer "F.Cu")
		(net 1)
	)
	(segment
		(start 156.285001 83.775001)
		(end 155.650001 84.410001)
		(width 0.256)
		(layer "F.Cu")
		(net 1)
	)
	(segment
		(start 202.5 117.5)
		(end 203 117)
		(width 0.4)
		(layer "F.Cu")
		(net 1)
	)
	(segment
		(start 170.255001 115.525001)
		(end 169.620001 114.890001)
		(width 0.256)
		(layer "F.Cu")
		(net 1)
	)
	(segment
		(start 168.58 164.65)
		(end 169.15 164.08)
		(width 0.4)
		(layer "F.Cu")
		(net 1)
	)
	(segment
		(start 257.13 138.135)
		(end 256.83 137.835)
		(width 0.201)
		(layer "F.Cu")
		(net 1)
	)
	(segment
		(start 160.095001 124.415001)
		(end 160.730001 125.050001)
		(width 0.256)
		(layer "F.Cu")
		(net 1)
	)
	(segment
		(start 197.5 142.5)
		(end 197 143)
		(width 0.4)
		(layer "F.Cu")
		(net 1)
	)
	(segment
		(start 170.255001 101.555001)
		(end 169.620001 102.190001)
		(width 0.256)
		(layer "F.Cu")
		(net 1)
	)
	(segment
		(start 153.745001 95.205001)
		(end 154.380001 94.570001)
		(width 0.201)
		(layer "F.Cu")
		(net 1)
	)
	(segment
		(start 196.585 166.2)
		(end 196.585 166.74)
		(width 0.201)
		(layer "F.Cu")
		(net 1)
	)
	(segment
		(start 215.9625 160.7125)
		(end 215.95 160.7)
		(width 0.201)
		(layer "F.Cu")
		(net 1)
	)
	(segment
		(start 197.5 122.5)
		(end 197 122)
		(width 0.4)
		(layer "F.Cu")
		(net 1)
	)
	(segment
		(start 167.715001 111.715001)
		(end 167.080001 112.350001)
		(width 0.256)
		(layer "F.Cu")
		(net 1)
	)
	(segment
		(start 261.535 139.935)
		(end 261.995 139.935)
		(width 0.201)
		(layer "F.Cu")
		(net 1)
	)
	(segment
		(start 165.175001 81.235001)
		(end 165.810001 81.870001)
		(width 0.201)
		(layer "F.Cu")
		(net 1)
	)
	(segment
		(start 160.095001 124.415001)
		(end 159.460001 125.050001)
		(width 0.256)
		(layer "F.Cu")
		(net 1)
	)
	(segment
		(start 227.9995 128.5485)
		(end 227.9995 134.3485)
		(width 0.182)
		(layer "F.Cu")
		(net 1)
	)
	(segment
		(start 220.4 146.2)
		(end 220.4 145.85)
		(width 0.256)
		(layer "F.Cu")
		(net 1)
	)
	(segment
		(start 170.255001 130.765001)
		(end 169.620001 130.130001)
		(width 0.256)
		(layer "F.Cu")
		(net 1)
	)
	(segment
		(start 217.1457 160.7125)
		(end 215.9625 160.7125)
		(width 0.201)
		(layer "F.Cu")
		(net 1)
	)
	(segment
		(start 195.8 186.2)
		(end 196.2 185.8)
		(width 0.1)
		(layer "F.Cu")
		(net 1)
	)
	(segment
		(start 158.825001 121.875001)
		(end 158.190001 122.510001)
		(width 0.256)
		(layer "F.Cu")
		(net 1)
	)
	(segment
		(start 169.620001 117.430001)
		(end 168.985001 118.065001)
		(width 0.256)
		(layer "F.Cu")
		(net 1)
	)
	(segment
		(start 153.745001 86.315001)
		(end 154.380001 86.950001)
		(width 0.256)
		(layer "F.Cu")
		(net 1)
	)
	(segment
		(start 168.985001 102.825001)
		(end 169.620001 102.190001)
		(width 0.201)
		(layer "F.Cu")
		(net 1)
	)
	(segment
		(start 158.825001 102.825001)
		(end 158.190001 102.190001)
		(width 0.201)
		(layer "F.Cu")
		(net 1)
	)
	(segment
		(start 204.2 89.6124)
		(end 204.2036 89.6088)
		(width 0.182)
		(layer "F.Cu")
		(net 1)
	)
	(segment
		(start 166.445001 99.015001)
		(end 167.080001 99.650001)
		(width 0.256)
		(layer "F.Cu")
		(net 1)
	)
	(segment
		(start 253.385 98.31)
		(end 253.575 98.5)
		(width 0.182)
		(layer "F.Cu")
		(net 1)
	)
	(segment
		(start 164.540001 114.890001)
		(end 163.905001 115.525001)
		(width 0.256)
		(layer "F.Cu")
		(net 1)
	)
	(segment
		(start 227 137.675)
		(end 228.365 137.675)
		(width 0.256)
		(layer "F.Cu")
		(net 1)
	)
	(segment
		(start 158.190001 117.430001)
		(end 157.555001 116.795001)
		(width 0.256)
		(layer "F.Cu")
		(net 1)
	)
	(segment
		(start 163.905001 83.775001)
		(end 164.540001 84.410001)
		(width 0.256)
		(layer "F.Cu")
		(net 1)
	)
	(segment
		(start 154.1 140.45)
		(end 154.1 139.3)
		(width 0.4)
		(layer "F.Cu")
		(net 1)
	)
	(segment
		(start 247.15 128.75)
		(end 247 128.9)
		(width 0.201)
		(layer "F.Cu")
		(net 1)
	)
	(segment
		(start 250.4 101)
		(end 250.5 101.1)
		(width 0.4)
		(layer "F.Cu")
		(net 1)
	)
	(segment
		(start 162.635001 105.365001)
		(end 163.270001 104.730001)
		(width 0.201)
		(layer "F.Cu")
		(net 1)
	)
	(segment
		(start 239.85 136.2)
		(end 239.85 137.075)
		(width 0.256)
		(layer "F.Cu")
		(net 1)
	)
	(segment
		(start 155.015001 82.505001)
		(end 155.650001 81.870001)
		(width 0.256)
		(layer "F.Cu")
		(net 1)
	)
	(segment
		(start 232.6 145.1)
		(end 232.885 144.815)
		(width 0.201)
		(layer "F.Cu")
		(net 1)
	)
	(segment
		(start 157.555001 109.175001)
		(end 158.190001 109.810001)
		(width 0.201)
		(layer "F.Cu")
		(net 1)
	)
	(segment
		(start 239.725 138.2)
		(end 239.6 138.075)
		(width 0.256)
		(layer "F.Cu")
		(net 1)
	)
	(segment
		(start 193.29 121.71)
		(end 193.29 122.29)
		(width 0.4)
		(layer "F.Cu")
		(net 1)
	)
	(segment
		(start 174 148)
		(end 174.4 147.6)
		(width 0.4)
		(layer "F.Cu")
		(net 1)
	)
	(segment
		(start 191.75 153.15)
		(end 191.115001 152.515001)
		(width 0.4)
		(layer "F.Cu")
		(net 1)
	)
	(segment
		(start 157.555001 124.415001)
		(end 156.920001 125.050001)
		(width 0.256)
		(layer "F.Cu")
		(net 1)
	)
	(segment
		(start 165.175001 111.715001)
		(end 164.540001 112.350001)
		(width 0.256)
		(layer "F.Cu")
		(net 1)
	)
	(segment
		(start 190.775 182.799999)
		(end 191.05 182.799999)
		(width 0.182)
		(layer "F.Cu")
		(net 1)
	)
	(segment
		(start 153.75 154.7)
		(end 153.1 154.7)
		(width 0.256)
		(layer "F.Cu")
		(net 1)
	)
	(segment
		(start 198.7 101.9)
		(end 197.65 101.9)
		(width 0.182)
		(layer "F.Cu")
		(net 1)
	)
	(segment
		(start 165.175001 121.875001)
		(end 165.810001 122.510001)
		(width 0.256)
		(layer "F.Cu")
		(net 1)
	)
	(segment
		(start 155.1 141)
		(end 154.125 141)
		(width 0.4)
		(layer "F.Cu")
		(net 1)
	)
	(segment
		(start 194.5 143.5)
		(end 194 144)
		(width 0.4)
		(layer "F.Cu")
		(net 1)
	)
	(segment
		(start 198.5 128.5)
		(end 198 128)
		(width 0.4)
		(layer "F.Cu")
		(net 1)
	)
	(segment
		(start 166.445001 114.255001)
		(end 165.810001 114.890001)
		(width 0.256)
		(layer "F.Cu")
		(net 1)
	)
	(segment
		(start 155.015001 107.905001)
		(end 154.380001 107.270001)
		(width 0.201)
		(layer "F.Cu")
		(net 1)
	)
	(segment
		(start 155.015001 107.905001)
		(end 155.650001 107.270001)
		(width 0.256)
		(layer "F.Cu")
		(net 1)
	)
	(segment
		(start 262.085 127)
		(end 261.315 127)
		(width 0.1)
		(layer "F.Cu")
		(net 1)
	)
	(segment
		(start 198.5 129.5)
		(end 198 129)
		(width 0.4)
		(layer "F.Cu")
		(net 1)
	)
	(segment
		(start 235.415 114.665)
		(end 235.415 114.575)
		(width 0.1)
		(layer "F.Cu")
		(net 1)
	)
	(segment
		(start 168.985001 123.145001)
		(end 168.350001 122.510001)
		(width 0.256)
		(layer "F.Cu")
		(net 1)
	)
	(segment
		(start 153.76 146.165)
		(end 153.7 146.225)
		(width 0.201)
		(layer "F.Cu")
		(net 1)
	)
	(segment
		(start 254.5 140.1)
		(end 253.965 140.635)
		(width 0.201)
		(layer "F.Cu")
		(net 1)
	)
	(segment
		(start 190.189 175.2)
		(end 190.85 175.2)
		(width 0.182)
		(layer "F.Cu")
		(net 1)
	)
	(segment
		(start 157.555001 86.315001)
		(end 158.190001 86.950001)
		(width 0.256)
		(layer "F.Cu")
		(net 1)
	)
	(segment
		(start 191.115001 152.515001)
		(end 191.115001 151.685)
		(width 0.4)
		(layer "F.Cu")
		(net 1)
	)
	(segment
		(start 261.7 71.85)
		(end 261.7 71.05)
		(width 0.4)
		(layer "F.Cu")
		(net 1)
	)
	(segment
		(start 195.291252 93.55)
		(end 194.591252 93.55)
		(width 0.182)
		(layer "F.Cu")
		(net 1)
	)
	(segment
		(start 204.925 105.025)
		(end 204.126252 105.025)
		(width 0.4)
		(layer "F.Cu")
		(net 1)
	)
	(segment
		(start 188.985 148.665)
		(end 189.5 148.15)
		(width 0.4)
		(layer "F.Cu")
		(net 1)
	)
	(segment
		(start 165.810001 117.430001)
		(end 165.175001 116.795001)
		(width 0.256)
		(layer "F.Cu")
		(net 1)
	)
	(segment
		(start 167.715001 96.475001)
		(end 168.350001 97.110001)
		(width 0.201)
		(layer "F.Cu")
		(net 1)
	)
	(segment
		(start 260.7075 139.935)
		(end 261.535 139.935)
		(width 0.201)
		(layer "F.Cu")
		(net 1)
	)
	(segment
		(start 186.225 175.65)
		(end 186.25 175.65)
		(width 0.1)
		(layer "F.Cu")
		(net 1)
	)
	(segment
		(start 155.015001 128.225001)
		(end 155.650001 127.590001)
		(width 0.256)
		(layer "F.Cu")
		(net 1)
	)
	(segment
		(start 229.3 148.015)
		(end 229.915 147.4)
		(width 0.182)
		(layer "F.Cu")
		(net 1)
	)
	(segment
		(start 209.5 128.5)
		(end 210 128)
		(width 0.4)
		(layer "F.Cu")
		(net 1)
	)
	(segment
		(start 199.3 103.365)
		(end 198.95 103.715)
		(width 0.182)
		(layer "F.Cu")
		(net 1)
	)
	(segment
		(start 213.5 130.5)
		(end 214.004834 131.004834)
		(width 0.4)
		(layer "F.Cu")
		(net 1)
	)
	(segment
		(start 155.015001 114.255001)
		(end 155.650001 114.890001)
		(width 0.256)
		(layer "F.Cu")
		(net 1)
	)
	(segment
		(start 162.635001 105.365001)
		(end 162.000001 104.730001)
		(width 0.256)
		(layer "F.Cu")
		(net 1)
	)
	(segment
		(start 166.445001 114.255001)
		(end 167.080001 114.890001)
		(width 0.256)
		(layer "F.Cu")
		(net 1)
	)
	(segment
		(start 245.15 127.775)
		(end 245.15 128.75)
		(width 0.201)
		(layer "F.Cu")
		(net 1)
	)
	(segment
		(start 222.4 155.585)
		(end 221.715 155.585)
		(width 0.256)
		(layer "F.Cu")
		(net 1)
	)
	(segment
		(start 193.59 168.715)
		(end 193.1 168.225)
		(width 0.182)
		(layer "F.Cu")
		(net 1)
	)
	(segment
		(start 158.825001 95.205001)
		(end 159.460001 94.570001)
		(width 0.201)
		(layer "F.Cu")
		(net 1)
	)
	(segment
		(start 158.825001 125.685001)
		(end 159.460001 125.050001)
		(width 0.256)
		(layer "F.Cu")
		(net 1)
	)
	(segment
		(start 200.241252 100.541252)
		(end 200.25 100.55)
		(width 0.4)
		(layer "F.Cu")
		(net 1)
	)
	(segment
		(start 165.175001 110.445001)
		(end 165.810001 109.810001)
		(width 0.201)
		(layer "F.Cu")
		(net 1)
	)
	(segment
		(start 249.065 130.735)
		(end 249.645 130.735)
		(width 0.201)
		(layer "F.Cu")
		(net 1)
	)
	(segment
		(start 162.635001 130.765001)
		(end 163.270001 130.130001)
		(width 0.256)
		(layer "F.Cu")
		(net 1)
	)
	(segment
		(start 170.255001 90.125001)
		(end 169.620001 89.490001)
		(width 0.256)
		(layer "F.Cu")
		(net 1)
	)
	(segment
		(start 191.000001 71.870001)
		(end 191 72)
		(width 0.1)
		(layer "F.Cu")
		(net 1)
	)
	(segment
		(start 200.5 128.5)
		(end 201 128)
		(width 0.4)
		(layer "F.Cu")
		(net 1)
	)
	(segment
		(start 193.3 126.3)
		(end 193.5 126.5)
		(width 0.4)
		(layer "F.Cu")
		(net 1)
	)
	(segment
		(start 170.255001 106.635001)
		(end 169.620001 107.270001)
		(width 0.256)
		(layer "F.Cu")
		(net 1)
	)
	(segment
		(start 167.715001 86.315001)
		(end 167.080001 86.950001)
		(width 0.256)
		(layer "F.Cu")
		(net 1)
	)
	(segment
		(start 168.985001 109.175001)
		(end 169.620001 109.810001)
		(width 0.201)
		(layer "F.Cu")
		(net 1)
	)
	(segment
		(start 155.015001 87.585001)
		(end 154.380001 86.950001)
		(width 0.201)
		(layer "F.Cu")
		(net 1)
	)
	(segment
		(start 168.985001 93.935001)
		(end 168.350001 94.570001)
		(width 0.256)
		(layer "F.Cu")
		(net 1)
	)
	(segment
		(start 226.015 92.765)
		(end 226 92.75)
		(width 0.201)
		(layer "F.Cu")
		(net 1)
	)
	(segment
		(start 218.715 139.21)
		(end 218.7 139.225)
		(width 0.256)
		(layer "F.Cu")
		(net 1)
	)
	(segment
		(start 164.4 148.925)
		(end 164.325 149)
		(width 0.4)
		(layer "F.Cu")
		(net 1)
	)
	(segment
		(start 195.5 131.5)
		(end 195 132)
		(width 0.4)
		(layer "F.Cu")
		(net 1)
	)
	(segment
		(start 207.891252 96.55)
		(end 207.891252 97.535)
		(width 0.182)
		(layer "F.Cu")
		(net 1)
	)
	(segment
		(start 155.015001 102.825001)
		(end 154.380001 102.190001)
		(width 0.201)
		(layer "F.Cu")
		(net 1)
	)
	(segment
		(start 167.715003 85.045001)
		(end 168.985001 83.775001)
		(width 0.256)
		(layer "F.Cu")
		(net 1)
	)
	(segment
		(start 157.555001 85.045001)
		(end 158.190001 84.410001)
		(width 0.256)
		(layer "F.Cu")
		(net 1)
	)
	(segment
		(start 158.825001 99.015001)
		(end 158.190001 99.650001)
		(width 0.256)
		(layer "F.Cu")
		(net 1)
	)
	(segment
		(start 232.27 86.2225)
		(end 232.27 87.37)
		(width 0.256)
		(layer "F.Cu")
		(net 1)
	)
	(segment
		(start 154.380001 84.410001)
		(end 155.015001 83.775001)
		(width 0.201)
		(layer "F.Cu")
		(net 1)
	)
	(segment
		(start 220.84 85.485)
		(end 220.84 86.2225)
		(width 0.256)
		(layer "F.Cu")
		(net 1)
	)
	(segment
		(start 238.05 132.7)
		(end 238.05 133.1)
		(width 0.182)
		(layer "F.Cu")
		(net 1)
	)
	(segment
		(start 155.6 150.2375)
		(end 155.6 150.8)
		(width 0.201)
		(layer "F.Cu")
		(net 1)
	)
	(segment
		(start 200.5 121.5)
		(end 201 121)
		(width 0.4)
		(layer "F.Cu")
		(net 1)
	)
	(segment
		(start 227.17 115.055)
		(end 228.57 115.055)
		(width 0.4)
		(layer "F.Cu")
		(net 1)
	)
	(segment
		(start 208.5 135.5)
		(end 209 136)
		(width 0.4)
		(layer "F.Cu")
		(net 1)
	)
	(segment
		(start 239.91 148.16)
		(end 240.48 148.16)
		(width 0.4)
		(layer "F.Cu")
		(net 1)
	)
	(segment
		(start 165.175001 85.045001)
		(end 164.540001 84.410001)
		(width 0.256)
		(layer "F.Cu")
		(net 1)
	)
	(segment
		(start 195.5 116.5)
		(end 195 116)
		(width 0.4)
		(layer "F.Cu")
		(net 1)
	)
	(segment
		(start 208.5 125.5)
		(end 209 125)
		(width 0.4)
		(layer "F.Cu")
		(net 1)
	)
	(segment
		(start 160.730001 84.410001)
		(end 161.365001 83.775001)
		(width 0.201)
		(layer "F.Cu")
		(net 1)
	)
	(segment
		(start 261.995 139.935)
		(end 262.145 139.785)
		(width 0.201)
		(layer "F.Cu")
		(net 1)
	)
	(segment
		(start 228.2 148.75)
		(end 229.25 148.75)
		(width 0.182)
		(layer "F.Cu")
		(net 1)
	)
	(segment
		(start 167.715001 120.605001)
		(end 167.080001 119.970001)
		(width 0.256)
		(layer "F.Cu")
		(net 1)
	)
	(segment
		(start 197.5 127.5)
		(end 197 127)
		(width 0.4)
		(layer "F.Cu")
		(net 1)
	)
	(segment
		(start 197 132)
		(end 197.5 131.5)
		(width 0.4)
		(layer "F.Cu")
		(net 1)
	)
	(segment
		(start 268.1 134.65)
		(end 267.35 133.9)
		(width 0.182)
		(layer "F.Cu")
		(net 1)
	)
	(segment
		(start 232.3 130.315)
		(end 232.285 130.3)
		(width 0.4)
		(layer "F.Cu")
		(net 1)
	)
	(segment
		(start 224.4 154.485)
		(end 223.785 154.485)
		(width 0.256)
		(layer "F.Cu")
		(net 1)
	)
	(segment
		(start 261.315 146)
		(end 262.085 146)
		(width 0.201)
		(layer "F.Cu")
		(net 1)
	)
	(segment
		(start 158.825001 110.445001)
		(end 158.190001 109.810001)
		(width 0.256)
		(layer "F.Cu")
		(net 1)
	)
	(segment
		(start 192.5 120.5)
		(end 193.5 120.5)
		(width 0.4)
		(layer "F.Cu")
		(net 1)
	)
	(segment
		(start 154.380001 112.350001)
		(end 153.745001 111.715001)
		(width 0.201)
		(layer "F.Cu")
		(net 1)
	)
	(segment
		(start 268.85 83.2)
		(end 268.875 83.2)
		(width 0.1)
		(layer "F.Cu")
		(net 1)
	)
	(segment
		(start 166.445001 123.145001)
		(end 165.810001 122.510001)
		(width 0.256)
		(layer "F.Cu")
		(net 1)
	)
	(segment
		(start 170.215 152)
		(end 170.215 151.44)
		(width 0.4)
		(layer "F.Cu")
		(net 1)
	)
	(segment
		(start 240.48 148.16)
		(end 240.75 147.89)
		(width 0.4)
		(layer "F.Cu")
		(net 1)
	)
	(segment
		(start 155.015001 92.665001)
		(end 155.650001 92.030001)
		(width 0.256)
		(layer "F.Cu")
		(net 1)
	)
	(segment
		(start 170.255001 86.315001)
		(end 169.620001 86.950001)
		(width 0.256)
		(layer "F.Cu")
		(net 1)
	)
	(segment
		(start 239.55 129.3)
		(end 239.55 130.175)
		(width 0.256)
		(layer "F.Cu")
		(net 1)
	)
	(segment
		(start 248.65 131.9625)
		(end 248.65 131.15)
		(width 0.201)
		(layer "F.Cu")
		(net 1)
	)
	(segment
		(start 156.285001 114.255001)
		(end 155.650001 114.890001)
		(width 0.256)
		(layer "F.Cu")
		(net 1)
	)
	(segment
		(start 165.175001 86.315001)
		(end 165.810001 86.950001)
		(width 0.201)
		(layer "F.Cu")
		(net 1)
	)
	(segment
		(start 204.5 133.5)
		(end 205 134)
		(width 0.4)
		(layer "F.Cu")
		(net 1)
	)
	(segment
		(start 207.891252 95.541252)
		(end 207.6 95.25)
		(width 0.182)
		(layer "F.Cu")
		(net 1)
	)
	(segment
		(start 170.255001 125.685001)
		(end 169.620001 125.050001)
		(width 0.256)
		(layer "F.Cu")
		(net 1)
	)
	(segment
		(start 199.3 102.5)
		(end 199.3 103.365)
		(width 0.182)
		(layer "F.Cu")
		(net 1)
	)
	(segment
		(start 245.65 149.15)
		(end 245.5 149)
		(width 0.256)
		(layer "F.Cu")
		(net 1)
	)
	(segment
		(start 205.091252 99.435)
		(end 205.091252 100.028748)
		(width 0.182)
		(layer "F.Cu")
		(net 1)
	)
	(segment
		(start 168.985001 129.495001)
		(end 169.620001 130.130001)
		(width 0.256)
		(layer "F.Cu")
		(net 1)
	)
	(segment
		(start 155.015001 93.935001)
		(end 155.020001 93.935001)
		(width 0.256)
		(layer "F.Cu")
		(net 1)
	)
	(segment
		(start 151.2 146.165)
		(end 152.14 146.165)
		(width 0.201)
		(layer "F.Cu")
		(net 1)
	)
	(segment
		(start 157.555001 116.795001)
		(end 156.920001 117.430001)
		(width 0.256)
		(layer "F.Cu")
		(net 1)
	)
	(segment
		(start 229.45 150.55)
		(end 229.4 150.6)
		(width 0.182)
		(layer "F.Cu")
		(net 1)
	)
	(segment
		(start 166.445001 109.175001)
		(end 165.810001 109.810001)
		(width 0.256)
		(layer "F.Cu")
		(net 1)
	)
	(segment
		(start 252.5 101)
		(end 252.8 101.3)
		(width 0.4)
		(layer "F.Cu")
		(net 1)
	)
	(segment
		(start 191.485001 152.885001)
		(end 191.75 153.15)
		(width 0.4)
		(layer "F.Cu")
		(net 1)
	)
	(segment
		(start 153.745001 85.045001)
		(end 154.380001 84.410001)
		(width 0.256)
		(layer "F.Cu")
		(net 1)
	)
	(segment
		(start 222.11 84.74)
		(end 222.5 84.35)
		(width 0.201)
		(layer "F.Cu")
		(net 1)
	)
	(segment
		(start 166.445001 104.095001)
		(end 165.810001 104.730001)
		(width 0.256)
		(layer "F.Cu")
		(net 1)
	)
	(segment
		(start 156.285001 99.015001)
		(end 155.650001 99.650001)
		(width 0.256)
		(layer "F.Cu")
		(net 1)
	)
	(segment
		(start 156.285001 125.685001)
		(end 156.920001 125.050001)
		(width 0.256)
		(layer "F.Cu")
		(net 1)
	)
	(segment
		(start 192.5 118.5)
		(end 193.5 118.5)
		(width 0.4)
		(layer "F.Cu")
		(net 1)
	)
	(segment
		(start 167.080001 112.350001)
		(end 166.445001 112.985001)
		(width 0.201)
		(layer "F.Cu")
		(net 1)
	)
	(segment
		(start 219.315 137.825)
		(end 218.715 138.425)
		(width 0.256)
		(layer "F.Cu")
		(net 1)
	)
	(segment
		(start 165.175001 106.635001)
		(end 165.810001 107.270001)
		(width 0.201)
		(layer "F.Cu")
		(net 1)
	)
	(segment
		(start 233.8 144.9)
		(end 232.8 144.9)
		(width 0.4)
		(layer "F.Cu")
		(net 1)
	)
	(segment
		(start 163.905001 126.955001)
		(end 164.540001 127.590001)
		(width 0.256)
		(layer "F.Cu")
		(net 1)
	)
	(segment
		(start 261.315 127)
		(end 260.7 127)
		(width 0.1)
		(layer "F.Cu")
		(net 1)
	)
	(segment
		(start 165.175001 105.365001)
		(end 164.540001 104.730001)
		(width 0.256)
		(layer "F.Cu")
		(net 1)
	)
	(segment
		(start 158.190001 130.130001)
		(end 158.825001 129.495001)
		(width 0.256)
		(layer "F.Cu")
		(net 1)
	)
	(segment
		(start 241.5 118.9)
		(end 241.5 118.15)
		(width 0.4)
		(layer "F.Cu")
		(net 1)
	)
	(segment
		(start 157.555001 128.225001)
		(end 158.190001 127.590001)
		(width 0.256)
		(layer "F.Cu")
		(net 1)
	)
	(segment
		(start 209.5 118.5)
		(end 210 118)
		(width 0.4)
		(layer "F.Cu")
		(net 1)
	)
	(segment
		(start 189.227 146.59)
		(end 189.24 146.59)
		(width 0.114)
		(layer "F.Cu")
		(net 1)
	)
	(segment
		(start 161.365001 125.685001)
		(end 162.000001 125.050001)
		(width 0.256)
		(layer "F.Cu")
		(net 1)
	)
	(segment
		(start 228.15 163.18)
		(end 228.4 163.43)
		(width 0.201)
		(layer "F.Cu")
		(net 1)
	)
	(segment
		(start 262.8 130.2)
		(end 262.7 130.1)
		(width 0.201)
		(layer "F.Cu")
		(net 1)
	)
	(segment
		(start 155.015001 123.145001)
		(end 154.380001 122.510001)
		(width 0.256)
		(layer "F.Cu")
		(net 1)
	)
	(segment
		(start 163.905001 104.095001)
		(end 164.540001 104.730001)
		(width 0.201)
		(layer "F.Cu")
		(net 1)
	)
	(segment
		(start 170.215 151.44)
		(end 170.2 151.425)
		(width 0.4)
		(layer "F.Cu")
		(net 1)
	)
	(segment
		(start 164 139)
		(end 163.3 138.3)
		(width 0.4)
		(layer "F.Cu")
		(net 1)
	)
	(segment
		(start 262.085 127)
		(end 260.7 127)
		(width 0.256)
		(layer "F.Cu")
		(net 1)
	)
	(segment
		(start 168.985001 88.855001)
		(end 168.350001 89.490001)
		(width 0.256)
		(layer "F.Cu")
		(net 1)
	)
	(segment
		(start 213.5 140.5)
		(end 214 141)
		(width 0.4)
		(layer "F.Cu")
		(net 1)
	)
	(segment
		(start 246.5 116.4)
		(end 247.6 116.4)
		(width 0.4)
		(layer "F.Cu")
		(net 1)
	)
	(segment
		(start 156.285001 83.775001)
		(end 156.920001 84.410001)
		(width 0.256)
		(layer "F.Cu")
		(net 1)
	)
	(segment
		(start 163.905001 104.095001)
		(end 163.270001 104.730001)
		(width 0.256)
		(layer "F.Cu")
		(net 1)
	)
	(segment
		(start 157.555001 97.745001)
		(end 158.190001 97.110001)
		(width 0.256)
		(layer "F.Cu")
		(net 1)
	)
	(segment
		(start 155.015001 118.065001)
		(end 154.380001 117.430001)
		(width 0.256)
		(layer "F.Cu")
		(net 1)
	)
	(segment
		(start 166.445001 97.745001)
		(end 167.080001 97.110001)
		(width 0.201)
		(layer "F.Cu")
		(net 1)
	)
	(segment
		(start 193.5 140.5)
		(end 193.075 140.925)
		(width 0.4)
		(layer "F.Cu")
		(net 1)
	)
	(segment
		(start 198.5 135.5)
		(end 198 136)
		(width 0.4)
		(layer "F.Cu")
		(net 1)
	)
	(segment
		(start 160.095001 86.315001)
		(end 160.730001 86.950001)
		(width 0.256)
		(layer "F.Cu")
		(net 1)
	)
	(segment
		(start 200.5 130.5)
		(end 201 131)
		(width 0.4)
		(layer "F.Cu")
		(net 1)
	)
	(segment
		(start 207.341252 102.51)
		(end 207.341252 102.508748)
		(width 0.4)
		(layer "F.Cu")
		(net 1)
	)
	(segment
		(start 166.445001 102.825001)
		(end 165.810001 102.190001)
		(width 0.201)
		(layer "F.Cu")
		(net 1)
	)
	(segment
		(start 163.905001 88.855001)
		(end 163.270001 89.490001)
		(width 0.256)
		(layer "F.Cu")
		(net 1)
	)
	(segment
		(start 262.085 146)
		(end 262.6 146)
		(width 0.201)
		(layer "F.Cu")
		(net 1)
	)
	(segment
		(start 221.4 137.675)
		(end 220.35 137.675)
		(width 0.256)
		(layer "F.Cu")
		(net 1)
	)
	(segment
		(start 240.85 139.6)
		(end 240.85 140)
		(width 0.182)
		(layer "F.Cu")
		(net 1)
	)
	(segment
		(start 163.9 141.9)
		(end 163.9 141.05)
		(width 0.4)
		(layer "F.Cu")
		(net 1)
	)
	(segment
		(start 214.5 133.5)
		(end 215 134)
		(width 0.4)
		(layer "F.Cu")
		(net 1)
	)
	(segment
		(start 153.745001 96.475001)
		(end 154.380001 97.110001)
		(width 0.256)
		(layer "F.Cu")
		(net 1)
	)
	(segment
		(start 228.65 163.68)
		(end 228.4 163.43)
		(width 0.201)
		(layer "F.Cu")
		(net 1)
	)
	(segment
		(start 230.425 119.925)
		(end 230.425 121.025)
		(width 0.4)
		(layer "F.Cu")
		(net 1)
	)
	(segment
		(start 229.735 142.75)
		(end 229.7005 142.75)
		(width 0.256)
		(layer "F.Cu")
		(net 1)
	)
	(segment
		(start 226.47 162.18)
		(end 227.15 162.18)
		(width 0.201)
		(layer "F.Cu")
		(net 1)
	)
	(segment
		(start 161.365001 99.015001)
		(end 160.730001 99.650001)
		(width 0.256)
		(layer "F.Cu")
		(net 1)
	)
	(segment
		(start 166.445001 82.505001)
		(end 167.080001 81.870001)
		(width 0.256)
		(layer "F.Cu")
		(net 1)
	)
	(segment
		(start 167.4 139.99)
		(end 167.21 139.99)
		(width 0.4)
		(layer "F.Cu")
		(net 1)
	)
	(segment
		(start 192.625 167.75)
		(end 193.1 168.225)
		(width 0.182)
		(layer "F.Cu")
		(net 1)
	)
	(segment
		(start 220.4 153.9)
		(end 220.1 153.6)
		(width 0.1)
		(layer "F.Cu")
		(net 1)
	)
	(segment
		(start 220.935 94.51)
		(end 220.935 92.715)
		(width 0.201)
		(layer "F.Cu")
		(net 1)
	)
	(segment
		(start 165.175001 121.875001)
		(end 164.540001 122.510001)
		(width 0.256)
		(layer "F.Cu")
		(net 1)
	)
	(segment
		(start 167.715001 96.475001)
		(end 167.080001 97.110001)
		(width 0.256)
		(layer "F.Cu")
		(net 1)
	)
	(segment
		(start 156.285001 87.585001)
		(end 156.920001 86.950001)
		(width 0.256)
		(layer "F.Cu")
		(net 1)
	)
	(segment
		(start 226.7 147)
		(end 226.2 146.5)
		(width 0.256)
		(layer "F.Cu")
		(net 1)
	)
	(segment
		(start 263.61 123.8)
		(end 262.7 123.8)
		(width 0.201)
		(layer "F.Cu")
		(net 1)
	)
	(segment
		(start 232.27 87.37)
		(end 232.3 87.4)
		(width 0.256)
		(layer "F.Cu")
		(net 1)
	)
	(segment
		(start 162.635001 86.315001)
		(end 163.270001 86.950001)
		(width 0.201)
		(layer "F.Cu")
		(net 1)
	)
	(segment
		(start 210.5 121.5)
		(end 211 121)
		(width 0.4)
		(layer "F.Cu")
		(net 1)
	)
	(segment
		(start 155.015001 93.935001)
		(end 154.380001 94.570001)
		(width 0.256)
		(layer "F.Cu")
		(net 1)
	)
	(segment
		(start 259.6 136)
		(end 260.1 136)
		(width 0.182)
		(layer "F.Cu")
		(net 1)
	)
	(segment
		(start 168.215 151.61)
		(end 168.125 151.7)
		(width 0.4)
		(layer "F.Cu")
		(net 1)
	)
	(segment
		(start 187.5 142.5)
		(end 187 143)
		(width 0.4)
		(layer "F.Cu")
		(net 1)
	)
	(segment
		(start 164.215 139.985)
		(end 164.2 140)
		(width 0.4)
		(layer "F.Cu")
		(net 1)
	)
	(segment
		(start 157.555001 97.745001)
		(end 156.920001 97.110001)
		(width 0.256)
		(layer "F.Cu")
		(net 1)
	)
	(segment
		(start 231.4 140.3)
		(end 231.4 141.085)
		(width 0.182)
		(layer "F.Cu")
		(net 1)
	)
	(segment
		(start 166.98 164.65)
		(end 166.41 164.08)
		(width 0.4)
		(layer "F.Cu")
		(net 1)
	)
	(segment
		(start 195.5 133.5)
		(end 195 134)
		(width 0.4)
		(layer "F.Cu")
		(net 1)
	)
	(segment
		(start 194.5 123.5)
		(end 194 123)
		(width 0.4)
		(layer "F.Cu")
		(net 1)
	)
	(segment
		(start 157.555001 128.225001)
		(end 156.920001 127.590001)
		(width 0.256)
		(layer "F.Cu")
		(net 1)
	)
	(segment
		(start 240.9 146.2)
		(end 240.75 146.35)
		(width 0.4)
		(layer "F.Cu")
		(net 1)
	)
	(segment
		(start 226.015 94.51)
		(end 226.015 92.765)
		(width 0.201)
		(layer "F.Cu")
		(net 1)
	)
	(segment
		(start 166.445001 83.775001)
		(end 167.080001 84.410001)
		(width 0.256)
		(layer "F.Cu")
		(net 1)
	)
	(segment
		(start 159.95 188.95)
		(end 159.95 188.203)
		(width 0.182)
		(layer "F.Cu")
		(net 1)
	)
	(segment
		(start 186.525 183.624999)
		(end 186.6 183.7)
		(width 0.1)
		(layer "F.Cu")
		(net 1)
	)
	(segment
		(start 193.5 133.5)
		(end 193 134)
		(width 0.4)
		(layer "F.Cu")
		(net 1)
	)
	(segment
		(start 166.445001 102.825001)
		(end 167.080001 102.190001)
		(width 0.201)
		(layer "F.Cu")
		(net 1)
	)
	(segment
		(start 193.29 119.71)
		(end 193.29 120.29)
		(width 0.4)
		(layer "F.Cu")
		(net 1)
	)
	(segment
		(start 155.015001 97.745001)
		(end 154.380001 97.110001)
		(width 0.201)
		(layer "F.Cu")
		(net 1)
	)
	(segment
		(start 155.015001 129.495001)
		(end 154.380001 130.130001)
		(width 0.256)
		(layer "F.Cu")
		(net 1)
	)
	(segment
		(start 198.5 126.5)
		(end 198 126)
		(width 0.4)
		(layer "F.Cu")
		(net 1)
	)
	(segment
		(start 232.3085 134.3485)
		(end 227.9995 134.3485)
		(width 0.182)
		(layer "F.Cu")
		(net 1)
	)
	(segment
		(start 192.85 108)
		(end 191.55 108)
		(width 0.182)
		(layer "F.Cu")
		(net 1)
	)
	(segment
		(start 204.15 99.45)
		(end 205.076252 99.45)
		(width 0.182)
		(layer "F.Cu")
		(net 1)
	)
	(segment
		(start 228.715 140.275)
		(end 228.725 140.265)
		(width 0.256)
		(layer "F.Cu")
		(net 1)
	)
	(segment
		(start 165.175001 81.235001)
		(end 164.540001 81.870001)
		(width 0.256)
		(layer "F.Cu")
		(net 1)
	)
	(segment
		(start 161.365001 95.205001)
		(end 162.000001 94.570001)
		(width 0.201)
		(layer "F.Cu")
		(net 1)
	)
	(segment
		(start 232.2995 134.3395)
		(end 232.2995 131.8235)
		(width 0.182)
		(layer "F.Cu")
		(net 1)
	)
	(segment
		(start 193.5 124.5)
		(end 192.5 124.5)
		(width 0.4)
		(layer "F.Cu")
		(net 1)
	)
	(segment
		(start 220.385 140.275)
		(end 221.4 140.275)
		(width 0.256)
		(layer "F.Cu")
		(net 1)
	)
	(segment
		(start 224.745 94.51)
		(end 224.745 92.795)
		(width 0.201)
		(layer "F.Cu")
		(net 1)
	)
	(segment
		(start 228.65 165.36)
		(end 228.65 163.68)
		(width 0.201)
		(layer "F.Cu")
		(net 1)
	)
	(segment
		(start 200.5 132.5)
		(end 201 133)
		(width 0.4)
		(layer "F.Cu")
		(net 1)
	)
	(segment
		(start 201.5 133.5)
		(end 202 134)
		(width 0.4)
		(layer "F.Cu")
		(net 1)
	)
	(segment
		(start 220.85 85.475)
		(end 220.84 85.485)
		(width 0.256)
		(layer "F.Cu")
		(net 1)
	)
	(segment
		(start 167.715001 110.445001)
		(end 167.080001 109.810001)
		(width 0.256)
		(layer "F.Cu")
		(net 1)
	)
	(segment
		(start 263.61 149.2)
		(end 262.8 149.2)
		(width 0.201)
		(layer "F.Cu")
		(net 1)
	)
	(segment
		(start 202.5 128.5)
		(end 203 128)
		(width 0.4)
		(layer "F.Cu")
		(net 1)
	)
	(segment
		(start 246.15 127.775)
		(end 246.15 128.9)
		(width 0.201)
		(layer "F.Cu")
		(net 1)
	)
	(segment
		(start 188.985 148.8)
		(end 188.985 148.665)
		(width 0.4)
		(layer "F.Cu")
		(net 1)
	)
	(segment
		(start 165.175001 85.045001)
		(end 165.810001 84.410001)
		(width 0.256)
		(layer "F.Cu")
		(net 1)
	)
	(segment
		(start 167.715001 90.125001)
		(end 167.080001 89.490001)
		(width 0.256)
		(layer "F.Cu")
		(net 1)
	)
	(segment
		(start 160.095001 112.985001)
		(end 160.730001 112.350001)
		(width 0.256)
		(layer "F.Cu")
		(net 1)
	)
	(segment
		(start 158.825001 83.775001)
		(end 159.460001 84.410001)
		(width 0.256)
		(layer "F.Cu")
		(net 1)
	)
	(segment
		(start 156.285001 102.825001)
		(end 156.920001 102.190001)
		(width 0.201)
		(layer "F.Cu")
		(net 1)
	)
	(segment
		(start 244.4625 138.65)
		(end 245.65 138.65)
		(width 0.201)
		(layer "F.Cu")
		(net 1)
	)
	(segment
		(start 174.77 187.84)
		(end 174.77 188.63)
		(width 0.4)
		(layer "F.Cu")
		(net 1)
	)
	(segment
		(start 200.4 106.2)
		(end 200.4 105.8837)
		(width 0.182)
		(layer "F.Cu")
		(net 1)
	)
	(segment
		(start 162.635001 85.045001)
		(end 162.000001 84.410001)
		(width 0.256)
		(layer "F.Cu")
		(net 1)
	)
	(segment
		(start 171.6 148.8)
		(end 171.6 148.4)
		(width 0.4)
		(layer "F.Cu")
		(net 1)
	)
	(segment
		(start 161.365001 95.205001)
		(end 160.730001 94.570001)
		(width 0.256)
		(layer "F.Cu")
		(net 1)
	)
	(segment
		(start 211.5 134.5)
		(end 212 135)
		(width 0.4)
		(layer "F.Cu")
		(net 1)
	)
	(segment
		(start 263.61 142.8)
		(end 262.8 142.8)
		(width 0.201)
		(layer "F.Cu")
		(net 1)
	)
	(segment
		(start 201.65 87.2)
		(end 201.65 87.825)
		(width 0.182)
		(layer "F.Cu")
		(net 1)
	)
	(segment
		(start 198.5 125.5)
		(end 198 125)
		(width 0.4)
		(layer "F.Cu")
		(net 1)
	)
	(segment
		(start 170.255001 126.955001)
		(end 169.620001 127.590001)
		(width 0.256)
		(layer "F.Cu")
		(net 1)
	)
	(segment
		(start 262.05 150.55)
		(end 262.5 150.1)
		(width 0.201)
		(layer "F.Cu")
		(net 1)
	)
	(segment
		(start 166 142.4)
		(end 166.175 142.225)
		(width 0.1)
		(layer "F.Cu")
		(net 1)
	)
	(segment
		(start 203.5 120.5)
		(end 204 120)
		(width 0.4)
		(layer "F.Cu")
		(net 1)
	)
	(segment
		(start 155.650001 117.435001)
		(end 155.645001 117.435001)
		(width 0.256)
		(layer "F.Cu")
		(net 1)
	)
	(segment
		(start 162.2 150.1)
		(end 162.2 150.7)
		(width 0.4)
		(layer "F.Cu")
		(net 1)
	)
	(segment
		(start 223.625 131.025)
		(end 223.25 130.65)
		(width 0.184)
		(layer "F.Cu")
		(net 1)
	)
	(segment
		(start 163.905001 87.585001)
		(end 164.540001 86.950001)
		(width 0.201)
		(layer "F.Cu")
		(net 1)
	)
	(segment
		(start 152.175 146.2)
		(end 152.175 146.325)
		(width 0.201)
		(layer "F.Cu")
		(net 1)
	)
	(segment
		(start 247.15 127.775)
		(end 247.15 128.75)
		(width 0.201)
		(layer "F.Cu")
		(net 1)
	)
	(segment
		(start 168.985001 92.665001)
		(end 169.620001 92.030001)
		(width 0.256)
		(layer "F.Cu")
		(net 1)
	)
	(segment
		(start 238.05 133.1)
		(end 237.85 133.3)
		(width 0.182)
		(layer "F.Cu")
		(net 1)
	)
	(segment
		(start 241.765 117.885)
		(end 241.5 118.15)
		(width 0.4)
		(layer "F.Cu")
		(net 1)
	)
	(segment
		(start 220.2 137.825)
		(end 219.315 137.825)
		(width 0.256)
		(layer "F.Cu")
		(net 1)
	)
	(segment
		(start 268.1 134.65)
		(end 267.35 135.4)
		(width 0.182)
		(layer "F.Cu")
		(net 1)
	)
	(segment
		(start 170.255001 121.875001)
		(end 169.620001 122.510001)
		(width 0.256)
		(layer "F.Cu")
		(net 1)
	)
	(segment
		(start 165.175001 130.765001)
		(end 164.540001 130.130001)
		(width 0.256)
		(layer "F.Cu")
		(net 1)
	)
	(segment
		(start 162.8 185.75)
		(end 162.8 185.2)
		(width 0.182)
		(layer "F.Cu")
		(net 1)
	)
	(segment
		(start 231.4 141.085)
		(end 230.885 141.6)
		(width 0.182)
		(layer "F.Cu")
		(net 1)
	)
	(segment
		(start 231.4 137.815)
		(end 232.115 137.1)
		(width 0.182)
		(layer "F.Cu")
		(net 1)
	)
	(segment
		(start 152.14 146.165)
		(end 152.175 146.2)
		(width 0.201)
		(layer "F.Cu")
		(net 1)
	)
	(segment
		(start 232.365 94.51)
		(end 232.365 95.765)
		(width 0.256)
		(layer "F.Cu")
		(net 1)
	)
	(segment
		(start 161.365001 102.825001)
		(end 160.730001 102.190001)
		(width 0.201)
		(layer "F.Cu")
		(net 1)
	)
	(segment
		(start 235.45 114.7)
		(end 235.415 114.665)
		(width 0.1)
		(layer "F.Cu")
		(net 1)
	)
	(segment
		(start 193.5 118.5)
		(end 193.3 118.3)
		(width 0.4)
		(layer "F.Cu")
		(net 1)
	)
	(segment
		(start 194.5762 102.435)
		(end 195.212 103.0708)
		(width 0.182)
		(layer "F.Cu")
		(net 1)
	)
	(segment
		(start 191.58 144.58)
		(end 191.58 145.18)
		(width 0.4)
		(layer "F.Cu")
		(net 1)
	)
	(segment
		(start 163.905001 107.905001)
		(end 164.540001 107.270001)
		(width 0.201)
		(layer "F.Cu")
		(net 1)
	)
	(segment
		(start 170.255001 111.715001)
		(end 169.620001 112.350001)
		(width 0.256)
		(layer "F.Cu")
		(net 1)
	)
	(segment
		(start 258.235 84.45)
		(end 258.4 84.285)
		(width 0.256)
		(layer "F.Cu")
		(net 1)
	)
	(segment
		(start 158.825001 95.205001)
		(end 158.190001 94.570001)
		(width 0.256)
		(layer "F.Cu")
		(net 1)
	)
	(segment
		(start 245.65 138.65)
		(end 248.4 135.9)
		(width 0.201)
		(layer "F.Cu")
		(net 1)
	)
	(segment
		(start 197.5 129.5)
		(end 197 129)
		(width 0.4)
		(layer "F.Cu")
		(net 1)
	)
	(segment
		(start 256.65 101)
		(end 256.95 101.3)
		(width 0.4)
		(layer "F.Cu")
		(net 1)
	)
	(segment
		(start 169.620001 89.490001)
		(end 168.985001 88.855001)
		(width 0.201)
		(layer "F.Cu")
		(net 1)
	)
	(segment
		(start 163.905001 92.665001)
		(end 163.270001 92.030001)
		(width 0.256)
		(layer "F.Cu")
		(net 1)
	)
	(segment
		(start 193.3 117.7)
		(end 193.5 117.5)
		(width 0.4)
		(layer "F.Cu")
		(net 1)
	)
	(segment
		(start 187.000001 71.870001)
		(end 187 72)
		(width 0.1)
		(layer "F.Cu")
		(net 1)
	)
	(segment
		(start 161.365001 106.635001)
		(end 162.000001 107.270001)
		(width 0.256)
		(layer "F.Cu")
		(net 1)
	)
	(segment
		(start 163.905001 100.285001)
		(end 163.270001 99.650001)
		(width 0.256)
		(layer "F.Cu")
		(net 1)
	)
	(segment
		(start 232.3 124.515)
		(end 232.285 124.5)
		(width 0.4)
		(layer "F.Cu")
		(net 1)
	)
	(segment
		(start 258.235 79.65)
		(end 258.4 79.485)
		(width 0.256)
		(layer "F.Cu")
		(net 1)
	)
	(segment
		(start 163.905001 92.665001)
		(end 164.540001 92.030001)
		(width 0.256)
		(layer "F.Cu")
		(net 1)
	)
	(segment
		(start 162.635001 128.225001)
		(end 163.270001 127.590001)
		(width 0.256)
		(layer "F.Cu")
		(net 1)
	)
	(segment
		(start 195.291252 95.65)
		(end 194.587783 95.65)
		(width 0.182)
		(layer "F.Cu")
		(net 1)
	)
	(segment
		(start 245.7 128.9)
		(end 246.15 128.9)
		(width 0.201)
		(layer "F.Cu")
		(net 1)
	)
	(segment
		(start 155.020001 93.935001)
		(end 155.655001 94.570001)
		(width 0.256)
		(layer "F.Cu")
		(net 1)
	)
	(segment
		(start 165.810001 92.030001)
		(end 166.445001 92.665001)
		(width 0.201)
		(layer "F.Cu")
		(net 1)
	)
	(segment
		(start 222.205 94.51)
		(end 222.205 92.705)
		(width 0.201)
		(layer "F.Cu")
		(net 1)
	)
	(segment
		(start 201.206252 99.876252)
		(end 201.182504 99.9)
		(width 0.4)
		(layer "F.Cu")
		(net 1)
	)
	(segment
		(start 165.175001 128.225001)
		(end 165.810001 127.590001)
		(width 0.256)
		(layer "F.Cu")
		(net 1)
	)
	(segment
		(start 259.7 188.55)
		(end 259.7 189)
		(width 0.4)
		(layer "F.Cu")
		(net 1)
	)
	(segment
		(start 166.445001 93.935001)
		(end 167.080001 94.570001)
		(width 0.256)
		(layer "F.Cu")
		(net 1)
	)
	(segment
		(start 155.015001 124.415001)
		(end 154.380001 125.050001)
		(width 0.256)
		(layer "F.Cu")
		(net 1)
	)
	(segment
		(start 158.825001 118.065001)
		(end 158.190001 117.430001)
		(width 0.256)
		(layer "F.Cu")
		(net 1)
	)
	(segment
		(start 199.241252 99.85)
		(end 200.241252 99.85)
		(width 0.4)
		(layer "F.Cu")
		(net 1)
	)
	(segment
		(start 230.3 138.45)
		(end 231.35 138.45)
		(width 0.182)
		(layer "F.Cu")
		(net 1)
	)
	(segment
		(start 168.985001 99.015001)
		(end 169.620001 99.650001)
		(width 0.256)
		(layer "F.Cu")
		(net 1)
	)
	(segment
		(start 194.585 167.1)
		(end 194.9 167.1)
		(width 0.177)
		(layer "F.Cu")
		(net 1)
	)
	(segment
		(start 225.775 116.75)
		(end 225.775 116.45)
		(width 0.4)
		(layer "F.Cu")
		(net 1)
	)
	(segment
		(start 258.235 94.05)
		(end 258.4 93.885)
		(width 0.256)
		(layer "F.Cu")
		(net 1)
	)
	(segment
		(start 168.58 164.65)
		(end 169.15 165.22)
		(width 0.4)
		(layer "F.Cu")
		(net 1)
	)
	(segment
		(start 245.65 127.775)
		(end 245.65 128.85)
		(width 0.201)
		(layer "F.Cu")
		(net 1)
	)
	(segment
		(start 253.2 134.351498)
		(end 252.901498 134.65)
		(width 0.201)
		(layer "F.Cu")
		(net 1)
	)
	(segment
		(start 161.365001 91.395001)
		(end 162.000001 92.030001)
		(width 0.256)
		(layer "F.Cu")
		(net 1)
	)
	(segment
		(start 193.29 116.29)
		(end 193.5 116.5)
		(width 0.4)
		(layer "F.Cu")
		(net 1)
	)
	(segment
		(start 258.36 119.88)
		(end 258.62 119.62)
		(width 0.114)
		(layer "F.Cu")
		(net 1)
	)
	(segment
		(start 153.745001 106.635001)
		(end 154.380001 107.270001)
		(width 0.256)
		(layer "F.Cu")
		(net 1)
	)
	(segment
		(start 165.175001 100.285001)
		(end 164.540001 99.650001)
		(width 0.201)
		(layer "F.Cu")
		(net 1)
	)
	(segment
		(start 238.375 139.925)
		(end 238.1 140.2)
		(width 0.182)
		(layer "F.Cu")
		(net 1)
	)
	(segment
		(start 167.080001 81.870001)
		(end 167.715001 81.235001)
		(width 0.201)
		(layer "F.Cu")
		(net 1)
	)
	(segment
		(start 160.095001 120.605001)
		(end 160.730001 119.970001)
		(width 0.256)
		(layer "F.Cu")
		(net 1)
	)
	(segment
		(start 158.825001 106.635001)
		(end 159.460001 107.270001)
		(width 0.256)
		(layer "F.Cu")
		(net 1)
	)
	(segment
		(start 226.7 147.015)
		(end 226.7 147)
		(width 0.256)
		(layer "F.Cu")
		(net 1)
	)
	(segment
		(start 168.985001 123.145001)
		(end 169.620001 122.510001)
		(width 0.256)
		(layer "F.Cu")
		(net 1)
	)
	(segment
		(start 158.7 144.5)
		(end 158.7 143.3)
		(width 0.4)
		(layer "F.Cu")
		(net 1)
	)
	(segment
		(start 214.004834 131.004834)
		(end 214.004834 131.025)
		(width 0.4)
		(layer "F.Cu")
		(net 1)
	)
	(segment
		(start 245.6 142.1)
		(end 245.13 142.1)
		(width 0.201)
		(layer "F.Cu")
		(net 1)
	)
	(segment
		(start 160.095001 105.365001)
		(end 160.730001 104.730001)
		(width 0.256)
		(layer "F.Cu")
		(net 1)
	)
	(segment
		(start 167.599999 148.800003)
		(end 167.199998 149.200004)
		(width 0.177)
		(layer "F.Cu")
		(net 1)
	)
	(segment
		(start 228.365 137.675)
		(end 228.725 137.315)
		(width 0.256)
		(layer "F.Cu")
		(net 1)
	)
	(segment
		(start 157.555001 101.555001)
		(end 156.920001 102.190001)
		(width 0.256)
		(layer "F.Cu")
		(net 1)
	)
	(segment
		(start 259.7 184.45)
		(end 259.7 184.5)
		(width 0.4)
		(layer "F.Cu")
		(net 1)
	)
	(segment
		(start 193.5 126.5)
		(end 192.5 126.5)
		(width 0.4)
		(layer "F.Cu")
		(net 1)
	)
	(segment
		(start 155.015001 92.665001)
		(end 154.380001 92.030001)
		(width 0.201)
		(layer "F.Cu")
		(net 1)
	)
	(segment
		(start 233.5995 128.9845)
		(end 232.284 130.3)
		(width 0.182)
		(layer "F.Cu")
		(net 1)
	)
	(segment
		(start 153.745001 90.125001)
		(end 154.380001 89.490001)
		(width 0.256)
		(layer "F.Cu")
		(net 1)
	)
	(segment
		(start 255.2515 135.2415)
		(end 254.945 134.935)
		(width 0.198)
		(layer "F.Cu")
		(net 1)
	)
	(segment
		(start 168.985001 104.095001)
		(end 169.620001 104.730001)
		(width 0.256)
		(layer "F.Cu")
		(net 1)
	)
	(segment
		(start 260.1 136)
		(end 260.3 136.2)
		(width 0.182)
		(layer "F.Cu")
		(net 1)
	)
	(segment
		(start 214.5 143.5)
		(end 215 144)
		(width 0.4)
		(layer "F.Cu")
		(net 1)
	)
	(segment
		(start 229.4 150.6)
		(end 229.4 151.235)
		(width 0.182)
		(layer "F.Cu")
		(net 1)
	)
	(segment
		(start 168.985001 118.065001)
		(end 168.350001 117.430001)
		(width 0.256)
		(layer "F.Cu")
		(net 1)
	)
	(segment
		(start 165.175001 91.395001)
		(end 165.810001 92.030001)
		(width 0.256)
		(layer "F.Cu")
		(net 1)
	)
	(segment
		(start 165.810001 97.110001)
		(end 166.445001 97.745001)
		(width 0.201)
		(layer "F.Cu")
		(net 1)
	)
	(segment
		(start 248.225 118.9)
		(end 248.25 118.925)
		(width 0.4)
		(layer "F.Cu")
		(net 1)
	)
	(segment
		(start 158.825001 121.875001)
		(end 159.460001 122.510001)
		(width 0.256)
		(layer "F.Cu")
		(net 1)
	)
	(segment
		(start 160.2 144.854)
		(end 160.646 145.3)
		(width 0.1)
		(layer "F.Cu")
		(net 1)
	)
	(segment
		(start 170.255001 85.045001)
		(end 169.620001 84.410001)
		(width 0.256)
		(layer "F.Cu")
		(net 1)
	)
	(segment
		(start 167.715001 130.765001)
		(end 167.080001 130.130001)
		(width 0.256)
		(layer "F.Cu")
		(net 1)
	)
	(segment
		(start 243.6 142.085)
		(end 245.115 142.085)
		(width 0.201)
		(layer "F.Cu")
		(net 1)
	)
	(segment
		(start 193.29 120.29)
		(end 193.5 120.5)
		(width 0.4)
		(layer "F.Cu")
		(net 1)
	)
	(segment
		(start 233.05 126.075)
		(end 233.1 126.025)
		(width 0.4)
		(layer "F.Cu")
		(net 1)
	)
	(segment
		(start 162.635001 90.125001)
		(end 163.270001 89.490001)
		(width 0.201)
		(layer "F.Cu")
		(net 1)
	)
	(segment
		(start 207.5 132.5)
		(end 208 133)
		(width 0.4)
		(layer "F.Cu")
		(net 1)
	)
	(segment
		(start 208.05 79.853)
		(end 208.679 80.482)
		(width 0.182)
		(layer "F.Cu")
		(net 1)
	)
	(segment
		(start 158.825001 114.255001)
		(end 159.460001 114.890001)
		(width 0.256)
		(layer "F.Cu")
		(net 1)
	)
	(segment
		(start 170.255001 120.605001)
		(end 169.620001 119.970001)
		(width 0.256)
		(layer "F.Cu")
		(net 1)
	)
	(segment
		(start 156.285001 125.685001)
		(end 155.650001 125.050001)
		(width 0.256)
		(layer "F.Cu")
		(net 1)
	)
	(segment
		(start 257.45 79.65)
		(end 258.235 79.65)
		(width 0.256)
		(layer "F.Cu")
		(net 1)
	)
	(segment
		(start 166.445001 118.065001)
		(end 167.080001 117.430001)
		(width 0.256)
		(layer "F.Cu")
		(net 1)
	)
	(segment
		(start 193.075 140.925)
		(end 193.075 141.025)
		(width 0.182)
		(layer "F.Cu")
		(net 1)
	)
	(segment
		(start 233.5 149.6)
		(end 233.5 150.6)
		(width 0.201)
		(layer "F.Cu")
		(net 1)
	)
	(segment
		(start 155.015001 119.335001)
		(end 154.380001 119.970001)
		(width 0.256)
		(layer "F.Cu")
		(net 1)
	)
	(segment
		(start 161.365001 83.775001)
		(end 162.000001 84.410001)
		(width 0.256)
		(layer "F.Cu")
		(net 1)
	)
	(segment
		(start 157.555001 109.175001)
		(end 156.920001 109.810001)
		(width 0.256)
		(layer "F.Cu")
		(net 1)
	)
	(segment
		(start 165.175001 116.795001)
		(end 164.540001 117.430001)
		(width 0.256)
		(layer "F.Cu")
		(net 1)
	)
	(segment
		(start 170.255001 91.395001)
		(end 169.620001 92.030001)
		(width 0.256)
		(layer "F.Cu")
		(net 1)
	)
	(segment
		(start 226.97235 122.22765)
		(end 226.97235 121.83)
		(width 0.4)
		(layer "F.Cu")
		(net 1)
	)
	(segment
		(start 161.365001 125.685001)
		(end 160.730001 125.050001)
		(width 0.256)
		(layer "F.Cu")
		(net 1)
	)
	(segment
		(start 247.15 126.75)
		(end 247.3 126.6)
		(width 0.201)
		(layer "F.Cu")
		(net 1)
	)
	(segment
		(start 156.2 144.18)
		(end 156.2 143.78)
		(width 0.4)
		(layer "F.Cu")
		(net 1)
	)
	(segment
		(start 171.6 148.4)
		(end 172 148.4)
		(width 0.4)
		(layer "F.Cu")
		(net 1)
	)
	(segment
		(start 222.4543 160.0775)
		(end 223.4225 160.0775)
		(width 0.201)
		(layer "F.Cu")
		(net 1)
	)
	(segment
		(start 245.3 128.9)
		(end 245.7 128.9)
		(width 0.201)
		(layer "F.Cu")
		(net 1)
	)
	(segment
		(start 167.715001 85.045001)
		(end 168.350001 84.410001)
		(width 0.256)
		(layer "F.Cu")
		(net 1)
	)
	(segment
		(start 156.285001 121.875001)
		(end 155.650001 122.510001)
		(width 0.256)
		(layer "F.Cu")
		(net 1)
	)
	(segment
		(start 167.080001 119.970001)
		(end 166.445001 119.335001)
		(width 0.256)
		(layer "F.Cu")
		(net 1)
	)
	(segment
		(start 239.55 130.175)
		(end 239.3 130.425)
		(width 0.256)
		(layer "F.Cu")
		(net 1)
	)
	(segment
		(start 156.285001 95.205001)
		(end 156.285001 95.200001)
		(width 0.201)
		(layer "F.Cu")
		(net 1)
	)
	(segment
		(start 191.5 144.5)
		(end 191.58 144.58)
		(width 0.4)
		(layer "F.Cu")
		(net 1)
	)
	(segment
		(start 257.7 71.05)
		(end 257.7 71.025)
		(width 0.1)
		(layer "F.Cu")
		(net 1)
	)
	(segment
		(start 166.445001 124.415001)
		(end 165.810001 125.050001)
		(width 0.256)
		(layer "F.Cu")
		(net 1)
	)
	(segment
		(start 202.65 87.2)
		(end 202.65 87.825)
		(width 0.182)
		(layer "F.Cu")
		(net 1)
	)
	(segment
		(start 167.715001 121.875001)
		(end 167.080001 122.510001)
		(width 0.256)
		(layer "F.Cu")
		(net 1)
	)
	(segment
		(start 167.715003 81.235003)
		(end 168.985001 82.505001)
		(width 0.256)
		(layer "F.Cu")
		(net 1)
	)
	(segment
		(start 164.540001 97.110001)
		(end 165.175001 96.475001)
		(width 0.201)
		(layer "F.Cu")
		(net 1)
	)
	(segment
		(start 157.555001 85.045001)
		(end 156.920001 84.410001)
		(width 0.201)
		(layer "F.Cu")
		(net 1)
	)
	(segment
		(start 172 148.4)
		(end 172.4 148.8)
		(width 0.4)
		(layer "F.Cu")
		(net 1)
	)
	(segment
		(start 248.65 131.9625)
		(end 248.65 135.65)
		(width 0.201)
		(layer "F.Cu")
		(net 1)
	)
	(segment
		(start 248.65 131.15)
		(end 249.065 130.735)
		(width 0.201)
		(layer "F.Cu")
		(net 1)
	)
	(segment
		(start 153.745001 100.285001)
		(end 154.380001 99.650001)
		(width 0.201)
		(layer "F.Cu")
		(net 1)
	)
	(segment
		(start 162.635001 120.605001)
		(end 163.270001 119.970001)
		(width 0.256)
		(layer "F.Cu")
		(net 1)
	)
	(segment
		(start 239.85 137.075)
		(end 239.6 137.325)
		(width 0.256)
		(layer "F.Cu")
		(net 1)
	)
	(segment
		(start 163.905001 88.855001)
		(end 164.540001 89.490001)
		(width 0.256)
		(layer "F.Cu")
		(net 1)
	)
	(segment
		(start 156.285001 95.205001)
		(end 156.920001 94.570001)
		(width 0.201)
		(layer "F.Cu")
		(net 1)
	)
	(segment
		(start 156.285001 91.395001)
		(end 155.650001 92.030001)
		(width 0.201)
		(layer "F.Cu")
		(net 1)
	)
	(segment
		(start 230.5 150.55)
		(end 229.45 150.55)
		(width 0.182)
		(layer "F.Cu")
		(net 1)
	)
	(segment
		(start 157.555001 130.765001)
		(end 158.190001 130.130001)
		(width 0.256)
		(layer "F.Cu")
		(net 1)
	)
	(segment
		(start 219.485 155.585)
		(end 219.5 155.6)
		(width 0.256)
		(layer "F.Cu")
		(net 1)
	)
	(segment
		(start 226.075 122.65)
		(end 226.55 122.65)
		(width 0.4)
		(layer "F.Cu")
		(net 1)
	)
	(segment
		(start 205.4955 116.5)
		(end 205.5 116.5)
		(width 0.1)
		(layer "F.Cu")
		(net 1)
	)
	(segment
		(start 203.5 130.5)
		(end 204 131)
		(width 0.4)
		(layer "F.Cu")
		(net 1)
	)
	(segment
		(start 219.685 140.975)
		(end 220.385 140.275)
		(width 0.256)
		(layer "F.Cu")
		(net 1)
	)
	(segment
		(start 167.080001 104.730001)
		(end 167.715001 105.365001)
		(width 0.201)
		(layer "F.Cu")
		(net 1)
	)
	(segment
		(start 157.555001 86.315001)
		(end 156.920001 86.950001)
		(width 0.201)
		(layer "F.Cu")
		(net 1)
	)
	(segment
		(start 165.175001 91.395001)
		(end 164.540001 92.030001)
		(width 0.201)
		(layer "F.Cu")
		(net 1)
	)
	(segment
		(start 167.715001 90.125001)
		(end 168.350001 89.490001)
		(width 0.256)
		(layer "F.Cu")
		(net 1)
	)
	(segment
		(start 190.189 176.15)
		(end 190.85 176.15)
		(width 0.182)
		(layer "F.Cu")
		(net 1)
	)
	(segment
		(start 195.600001 164.115001)
		(end 196.585 165.1)
		(width 0.177)
		(layer "F.Cu")
		(net 1)
	)
	(segment
		(start 160.095001 86.315001)
		(end 159.460001 86.950001)
		(width 0.201)
		(layer "F.Cu")
		(net 1)
	)
	(segment
		(start 166.445001 128.225001)
		(end 167.080001 127.590001)
		(width 0.256)
		(layer "F.Cu")
		(net 1)
	)
	(segment
		(start 153.745001 130.765001)
		(end 154.380001 130.130001)
		(width 0.256)
		(layer "F.Cu")
		(net 1)
	)
	(segment
		(start 165.175001 90.125001)
		(end 165.810001 89.490001)
		(width 0.201)
		(layer "F.Cu")
		(net 1)
	)
	(segment
		(start 229.4 151.235)
		(end 228.735 151.9)
		(width 0.182)
		(layer "F.Cu")
		(net 1)
	)
	(segment
		(start 228.815 137.315)
		(end 229.325 137.825)
		(width 0.256)
		(layer "F.Cu")
		(net 1)
	)
	(segment
		(start 195.5 129.5)
		(end 195 129)
		(width 0.4)
		(layer "F.Cu")
		(net 1)
	)
	(segment
		(start 155.015001 83.775001)
		(end 155.650001 84.410001)
		(width 0.256)
		(layer "F.Cu")
		(net 1)
	)
	(segment
		(start 167.715001 101.555001)
		(end 168.350001 102.190001)
		(width 0.201)
		(layer "F.Cu")
		(net 1)
	)
	(segment
		(start 158.825001 91.395001)
		(end 159.460001 92.030001)
		(width 0.256)
		(layer "F.Cu")
		(net 1)
	)
	(segment
		(start 165.175001 90.125001)
		(end 164.540001 89.490001)
		(width 0.201)
		(layer "F.Cu")
		(net 1)
	)
	(segment
		(start 254.5605 138.3195)
		(end 254.945 137.935)
		(width 0.198)
		(layer "F.Cu")
		(net 1)
	)
	(segment
		(start 168.985001 97.745001)
		(end 168.350001 97.110001)
		(width 0.256)
		(layer "F.Cu")
		(net 1)
	)
	(segment
		(start 220.935 92.715)
		(end 220.95 92.7)
		(width 0.201)
		(layer "F.Cu")
		(net 1)
	)
	(segment
		(start 161.365001 102.825001)
		(end 162.000001 102.190001)
		(width 0.201)
		(layer "F.Cu")
		(net 1)
	)
	(segment
		(start 166.445001 104.095001)
		(end 167.080001 104.730001)
		(width 0.256)
		(layer "F.Cu")
		(net 1)
	)
	(segment
		(start 158.825001 83.775001)
		(end 158.190001 84.410001)
		(width 0.201)
		(layer "F.Cu")
		(net 1)
	)
	(segment
		(start 155.015001 102.825001)
		(end 155.650001 102.190001)
		(width 0.201)
		(layer "F.Cu")
		(net 1)
	)
	(segment
		(start 246.65 127.775)
		(end 246.65 128.9)
		(width 0.201)
		(layer "F.Cu")
		(net 1)
	)
	(segment
		(start 170.255001 130.765001)
		(end 170.890001 130.130001)
		(width 0.256)
		(layer "F.Cu")
		(net 1)
	)
	(segment
		(start 155.015001 114.255001)
		(end 154.380001 114.890001)
		(width 0.256)
		(layer "F.Cu")
		(net 1)
	)
	(segment
		(start 155.650001 86.950001)
		(end 156.285001 87.585001)
		(width 0.201)
		(layer "F.Cu")
		(net 1)
	)
	(segment
		(start 223.5375 160.7125)
		(end 223.55 160.7)
		(width 0.201)
		(layer "F.Cu")
		(net 1)
	)
	(segment
		(start 222.4543 160.7125)
		(end 223.5375 160.7125)
		(width 0.201)
		(layer "F.Cu")
		(net 1)
	)
	(segment
		(start 167.715001 105.365001)
		(end 168.350001 104.730001)
		(width 0.201)
		(layer "F.Cu")
		(net 1)
	)
	(segment
		(start 229.3 140.05)
		(end 228.94 140.05)
		(width 0.256)
		(layer "F.Cu")
		(net 1)
	)
	(segment
		(start 166.445001 87.585001)
		(end 165.810001 86.950001)
		(width 0.256)
		(layer "F.Cu")
		(net 1)
	)
	(segment
		(start 257.45 84.45)
		(end 258.235 84.45)
		(width 0.256)
		(layer "F.Cu")
		(net 1)
	)
	(segment
		(start 192.35 167.75)
		(end 192.625 167.75)
		(width 0.182)
		(layer "F.Cu")
		(net 1)
	)
	(segment
		(start 211.345 79.73)
		(end 211.667 79.408)
		(width 0.182)
		(layer "F.Cu")
		(net 1)
	)
	(segment
		(start 257.45 86.85)
		(end 258.235 86.85)
		(width 0.256)
		(layer "F.Cu")
		(net 1)
	)
	(segment
		(start 258.235 86.85)
		(end 258.4 86.685)
		(width 0.256)
		(layer "F.Cu")
		(net 1)
	)
	(segment
		(start 232.8 144.9)
		(end 232.6 145.1)
		(width 0.4)
		(layer "F.Cu")
		(net 1)
	)
	(segment
		(start 197.671102 131.328898)
		(end 197.500001 131.500001)
		(width 0.1)
		(layer "F.Cu")
		(net 1)
	)
	(segment
		(start 223.475 92.725)
		(end 223.45 92.7)
		(width 0.201)
		(layer "F.Cu")
		(net 1)
	)
	(segment
		(start 188.1 168.5)
		(end 188.1 167.8)
		(width 0.4)
		(layer "F.Cu")
		(net 1)
	)
	(segment
		(start 163.905001 96.475001)
		(end 163.270001 97.110001)
		(width 0.201)
		(layer "F.Cu")
		(net 1)
	)
	(segment
		(start 158.190001 81.862689)
		(end 157.555001 81.227689)
		(width 0.201)
		(layer "F.Cu")
		(net 1)
	)
	(segment
		(start 233.5995 134.3485)
		(end 232.3085 134.3485)
		(width 0.182)
		(layer "F.Cu")
		(net 1)
	)
	(segment
		(start 205.091252 100.028748)
		(end 204.92 100.2)
		(width 0.182)
		(layer "F.Cu")
		(net 1)
	)
	(segment
		(start 177.18 75.67)
		(end 177.18 73.62)
		(width 0.4)
		(layer "F.Cu")
		(net 1)
	)
	(segment
		(start 157.555001 124.415001)
		(end 158.190001 125.050001)
		(width 0.256)
		(layer "F.Cu")
		(net 1)
	)
	(segment
		(start 252.7 71.85)
		(end 252.7 71.05)
		(width 0.4)
		(layer "F.Cu")
		(net 1)
	)
	(segment
		(start 165.175001 130.765001)
		(end 165.810001 130.130001)
		(width 0.256)
		(layer "F.Cu")
		(net 1)
	)
	(segment
		(start 157.555001 120.605001)
		(end 156.920001 119.970001)
		(width 0.256)
		(layer "F.Cu")
		(net 1)
	)
	(segment
		(start 155.015001 124.415001)
		(end 155.650001 125.050001)
		(width 0.256)
		(layer "F.Cu")
		(net 1)
	)
	(segment
		(start 206.5 139.5)
		(end 207 140)
		(width 0.4)
		(layer "F.Cu")
		(net 1)
	)
	(segment
		(start 163.9 141.05)
		(end 163.9 140.3)
		(width 0.4)
		(layer "F.Cu")
		(net 1)
	)
	(segment
		(start 232.3085 134.3485)
		(end 232.2995 134.3395)
		(width 0.182)
		(layer "F.Cu")
		(net 1)
	)
	(segment
		(start 167.78 164.65)
		(end 166.98 164.65)
		(width 0.4)
		(layer "F.Cu")
		(net 1)
	)
	(segment
		(start 257.45 96.45)
		(end 258.235 96.45)
		(width 0.256)
		(layer "F.Cu")
		(net 1)
	)
	(segment
		(start 160.095001 97.745001)
		(end 159.460001 97.110001)
		(width 0.256)
		(layer "F.Cu")
		(net 1)
	)
	(segment
		(start 177.18 71.57)
		(end 177.18 73.62)
		(width 0.4)
		(layer "F.Cu")
		(net 1)
	)
	(segment
		(start 242.6 117.885)
		(end 241.765 117.885)
		(width 0.4)
		(layer "F.Cu")
		(net 1)
	)
	(segment
		(start 193.3 125.7)
		(end 193.3 126.3)
		(width 0.4)
		(layer "F.Cu")
		(net 1)
	)
	(segment
		(start 220.55 145.7)
		(end 220.4 145.85)
		(width 0.256)
		(layer "F.Cu")
		(net 1)
	)
	(segment
		(start 258.4 144.25)
		(end 258.4 143.35)
		(width 0.4)
		(layer "F.Cu")
		(net 1)
	)
	(segment
		(start 268.875 83.2)
		(end 268.9 83.175)
		(width 0.1)
		(layer "F.Cu")
		(net 1)
	)
	(segment
		(start 168.985001 93.935001)
		(end 169.620001 94.570001)
		(width 0.201)
		(layer "F.Cu")
		(net 1)
	)
	(segment
		(start 152.5 146.65)
		(end 152.5 146.675)
		(width 0.201)
		(layer "F.Cu")
		(net 1)
	)
	(segment
		(start 212.5 117.5)
		(end 213 117)
		(width 0.4)
		(layer "F.Cu")
		(net 1)
	)
	(segment
		(start 202.5 126.5)
		(end 203 126)
		(width 0.4)
		(layer "F.Cu")
		(net 1)
	)
	(segment
		(start 214.875 155.175)
		(end 214.88 155.18)
		(width 0.4)
		(layer "F.Cu")
		(net 1)
	)
	(segment
		(start 246.15 138.15)
		(end 248.4 135.9)
		(width 0.201)
		(layer "F.Cu")
		(net 1)
	)
	(segment
		(start 244.675 150.075)
		(end 244.6 150)
		(width 0.256)
		(layer "F.Cu")
		(net 1)
	)
	(segment
		(start 165.175001 96.475001)
		(end 165.810001 97.110001)
		(width 0.256)
		(layer "F.Cu")
		(net 1)
	)
	(segment
		(start 168.985001 87.585001)
		(end 168.350001 86.950001)
		(width 0.256)
		(layer "F.Cu")
		(net 1)
	)
	(segment
		(start 248.675 142.075)
		(end 248.7 142.1)
		(width 0.201)
		(layer "F.Cu")
		(net 1)
	)
	(segment
		(start 252.7 76.15)
		(end 252.7 71.85)
		(width 0.4)
		(layer "F.Cu")
		(net 1)
	)
	(segment
		(start 203.5 140.5)
		(end 204 141)
		(width 0.4)
		(layer "F.Cu")
		(net 1)
	)
	(segment
		(start 162.635001 97.745001)
		(end 163.270001 97.110001)
		(width 0.256)
		(layer "F.Cu")
		(net 1)
	)
	(segment
		(start 190.5 141.5)
		(end 190 142)
		(width 0.4)
		(layer "F.Cu")
		(net 1)
	)
	(segment
		(start 162.635001 81.235001)
		(end 162.000001 81.870001)
		(width 0.201)
		(layer "F.Cu")
		(net 1)
	)
	(segment
		(start 168.350001 117.430001)
		(end 167.715001 116.795001)
		(width 0.256)
		(layer "F.Cu")
		(net 1)
	)
	(segment
		(start 247 128.9)
		(end 246.65 128.9)
		(width 0.201)
		(layer "F.Cu")
		(net 1)
	)
	(segment
		(start 160.095001 128.225001)
		(end 159.460001 127.590001)
		(width 0.256)
		(layer "F.Cu")
		(net 1)
	)
	(segment
		(start 201.206252 98.9)
		(end 201.206252 99.876252)
		(width 0.4)
		(layer "F.Cu")
		(net 1)
	)
	(segment
		(start 170.255001 95.205001)
		(end 169.620001 94.570001)
		(width 0.256)
		(layer "F.Cu")
		(net 1)
	)
	(segment
		(start 194.5 130.5)
		(end 194 131)
		(width 0.4)
		(layer "F.Cu")
		(net 1)
	)
	(segment
		(start 167.21 139.99)
		(end 167.2 140)
		(width 0.4)
		(layer "F.Cu")
		(net 1)
	)
	(segment
		(start 245.15 149.125)
		(end 245.15 150.075)
		(width 0.256)
		(layer "F.Cu")
		(net 1)
	)
	(segment
		(start 190.85 175.2)
		(end 191.325 175.675)
		(width 0.182)
		(layer "F.Cu")
		(net 1)
	)
	(segment
		(start 228.57 115.055)
		(end 230.475 113.15)
		(width 0.4)
		(layer "F.Cu")
		(net 1)
	)
	(segment
		(start 219.685 140.975)
		(end 219.685 139.975)
		(width 0.256)
		(layer "F.Cu")
		(net 1)
	)
	(segment
		(start 201.5 124.5)
		(end 202 124)
		(width 0.4)
		(layer "F.Cu")
		(net 1)
	)
	(segment
		(start 163.905001 126.955001)
		(end 163.270001 127.590001)
		(width 0.256)
		(layer "F.Cu")
		(net 1)
	)
	(segment
		(start 257.45 94.05)
		(end 258.235 94.05)
		(width 0.256)
		(layer "F.Cu")
		(net 1)
	)
	(segment
		(start 155.015001 109.175001)
		(end 155.650001 109.810001)
		(width 0.256)
		(layer "F.Cu")
		(net 1)
	)
	(segment
		(start 201.5 129.5)
		(end 202 129)
		(width 0.4)
		(layer "F.Cu")
		(net 1)
	)
	(segment
		(start 156.285001 102.825001)
		(end 155.650001 102.190001)
		(width 0.256)
		(layer "F.Cu")
		(net 1)
	)
	(segment
		(start 210.5 141.5)
		(end 211 142)
		(width 0.4)
		(layer "F.Cu")
		(net 1)
	)
	(segment
		(start 191.55 108)
		(end 191.3 108.25)
		(width 0.182)
		(layer "F.Cu")
		(net 1)
	)
	(segment
		(start 162.635001 109.175001)
		(end 162.000001 109.810001)
		(width 0.256)
		(layer "F.Cu")
		(net 1)
	)
	(segment
		(start 173.2 148)
		(end 173.6 147.6)
		(width 0.4)
		(layer "F.Cu")
		(net 1)
	)
	(segment
		(start 222.4 150.3)
		(end 222.4 149.487636)
		(width 0.201)
		(layer "F.Cu")
		(net 1)
	)
	(segment
		(start 166.445001 87.585001)
		(end 167.080001 86.950001)
		(width 0.256)
		(layer "F.Cu")
		(net 1)
	)
	(segment
		(start 169.599998 148.400004)
		(end 170 148)
		(width 0.4)
		(layer "F.Cu")
		(net 1)
	)
	(segment
		(start 253.385 96)
		(end 253.385 98.31)
		(width 0.182)
		(layer "F.Cu")
		(net 1)
	)
	(segment
		(start 160.095001 116.795001)
		(end 159.460001 117.430001)
		(width 0.256)
		(layer "F.Cu")
		(net 1)
	)
	(segment
		(start 160.095001 90.125001)
		(end 160.730001 89.490001)
		(width 0.256)
		(layer "F.Cu")
		(net 1)
	)
	(segment
		(start 224.745 92.795)
		(end 224.7 92.75)
		(width 0.201)
		(layer "F.Cu")
		(net 1)
	)
	(segment
		(start 166.445001 129.495001)
		(end 165.810001 130.130001)
		(width 0.256)
		(layer "F.Cu")
		(net 1)
	)
	(segment
		(start 167.715001 116.795001)
		(end 167.080001 117.430001)
		(width 0.256)
		(layer "F.Cu")
		(net 1)
	)
	(segment
		(start 166.445001 107.905001)
		(end 165.810001 107.270001)
		(width 0.256)
		(layer "F.Cu")
		(net 1)
	)
	(segment
		(start 193.5 121.5)
		(end 193.29 121.71)
		(width 0.4)
		(layer "F.Cu")
		(net 1)
	)
	(segment
		(start 229.3 148.7)
		(end 229.3 148.015)
		(width 0.182)
		(layer "F.Cu")
		(net 1)
	)
	(segment
		(start 160.095001 97.745001)
		(end 160.730001 97.110001)
		(width 0.256)
		(layer "F.Cu")
		(net 1)
	)
	(segment
		(start 253.575 98.5)
		(end 254.3 98.5)
		(width 0.182)
		(layer "F.Cu")
		(net 1)
	)
	(segment
		(start 166 148.8)
		(end 166.025 148.825)
		(width 0.1)
		(layer "F.Cu")
		(net 1)
	)
	(segment
		(start 166.445001 93.935001)
		(end 165.810001 94.570001)
		(width 0.256)
		(layer "F.Cu")
		(net 1)
	)
	(segment
		(start 170.255001 81.235002)
		(end 168.985001 82.505001)
		(width 0.256)
		(layer "F.Cu")
		(net 1)
	)
	(segment
		(start 214.88 155.18)
		(end 214.88 155.185)
		(width 0.4)
		(layer "F.Cu")
		(net 1)
	)
	(segment
		(start 157.555001 105.365001)
		(end 158.190001 104.730001)
		(width 0.256)
		(layer "F.Cu")
		(net 1)
	)
	(segment
		(start 167.715001 125.685001)
		(end 167.080001 125.050001)
		(width 0.256)
		(layer "F.Cu")
		(net 1)
	)
	(segment
		(start 163.905001 82.505001)
		(end 163.270001 81.870001)
		(width 0.256)
		(layer "F.Cu")
		(net 1)
	)
	(segment
		(start 195.85 103.7088)
		(end 195.212 103.0708)
		(width 0.182)
		(layer "F.Cu")
		(net 1)
	)
	(segment
		(start 259.115 129.7)
		(end 259.115 128.5)
		(width 0.201)
		(layer "F.Cu")
		(net 1)
	)
	(segment
		(start 193.000001 71.870001)
		(end 193 72)
		(width 0.1)
		(layer "F.Cu")
		(net 1)
	)
	(segment
		(start 240.75 147.89)
		(end 240.75 147.2)
		(width 0.4)
		(layer "F.Cu")
		(net 1)
	)
	(segment
		(start 233.5 150.6)
		(end 233.2 150.9)
		(width 0.201)
		(layer "F.Cu")
		(net 1)
	)
	(segment
		(start 157.1 147.9)
		(end 157 147.8)
		(width 0.4)
		(layer "F.Cu")
		(net 1)
	)
	(segment
		(start 198.5 132.5)
		(end 198 133)
		(width 0.4)
		(layer "F.Cu")
		(net 1)
	)
	(segment
		(start 160.7875 173.9625)
		(end 160.7875 174.825)
		(width 0.182)
		(layer "F.Cu")
		(net 1)
	)
	(segment
		(start 202.5 130.5)
		(end 203 131)
		(width 0.4)
		(layer "F.Cu")
		(net 1)
	)
	(segment
		(start 192.35 168.7)
		(end 192.625 168.7)
		(width 0.182)
		(layer "F.Cu")
		(net 1)
	)
	(segment
		(start 203.735 101.875)
		(end 204.57 102.71)
		(width 0.4)
		(layer "F.Cu")
		(net 1)
	)
	(segment
		(start 191.815 176.165)
		(end 191.325 175.675)
		(width 0.182)
		(layer "F.Cu")
		(net 1)
	)
	(segment
		(start 226 131.2)
		(end 225.985 131.185)
		(width 0.256)
		(layer "F.Cu")
		(net 1)
	)
	(segment
		(start 236.41 116.525)
		(end 236.4 116.525)
		(width 0.4)
		(layer "F.Cu")
		(net 1)
	)
	(segment
		(start 156.920001 81.870001)
		(end 157.555001 81.235001)
		(width 0.201)
		(layer "F.Cu")
		(net 1)
	)
	(segment
		(start 173.2 142.175)
		(end 173.225 142.15)
		(width 0.4)
		(layer "F.Cu")
		(net 1)
	)
	(segment
		(start 191.05 183.749999)
		(end 191.525 183.274999)
		(width 0.182)
		(layer "F.Cu")
		(net 1)
	)
	(segment
		(start 241.16 86.2225)
		(end 241.2775 86.2225)
		(width 0.256)
		(layer "F.Cu")
		(net 1)
	)
	(segment
		(start 154.385001 112.350001)
		(end 154.380001 112.350001)
		(width 0.201)
		(layer "F.Cu")
		(net 1)
	)
	(segment
		(start 243.4 132.325)
		(end 243.325 132.4)
		(width 0.201)
		(layer "F.Cu")
		(net 1)
	)
	(segment
		(start 162.635001 116.795001)
		(end 162.000001 117.430001)
		(width 0.256)
		(layer "F.Cu")
		(net 1)
	)
	(segment
		(start 195.291252 91.55)
		(end 194.591252 91.55)
		(width 0.182)
		(layer "F.Cu")
		(net 1)
	)
	(segment
		(start 225.7 152.6)
		(end 226.2 152.6)
		(width 0.256)
		(layer "F.Cu")
		(net 1)
	)
	(segment
		(start 167.715001 91.395001)
		(end 167.080001 92.030001)
		(width 0.256)
		(layer "F.Cu")
		(net 1)
	)
	(segment
		(start 161.365001 121.875001)
		(end 160.730001 122.510001)
		(width 0.256)
		(layer "F.Cu")
		(net 1)
	)
	(segment
		(start 168.215 151.2)
		(end 168.215 151.61)
		(width 0.4)
		(layer "F.Cu")
		(net 1)
	)
	(segment
		(start 204.2 90.422851)
		(end 204.2 89.6124)
		(width 0.182)
		(layer "F.Cu")
		(net 1)
	)
	(segment
		(start 155.645001 117.435001)
		(end 155.015001 118.065001)
		(width 0.256)
		(layer "F.Cu")
		(net 1)
	)
	(segment
		(start 211.5 144.5)
		(end 212 145)
		(width 0.4)
		(layer "F.Cu")
		(net 1)
	)
	(segment
		(start 193.5 119.5)
		(end 193.29 119.71)
		(width 0.4)
		(layer "F.Cu")
		(net 1)
	)
	(segment
		(start 241.255 93.345)
		(end 241.3 93.3)
		(width 0.256)
		(layer "F.Cu")
		(net 1)
	)
	(segment
		(start 201.101 76.383)
		(end 201.101 72.083)
		(width 0.4)
		(layer "F.Cu")
		(net 1)
	)
	(segment
		(start 229.25 148.75)
		(end 229.3 148.7)
		(width 0.182)
		(layer "F.Cu")
		(net 1)
	)
	(segment
		(start 208.05 79.74)
		(end 208.05 79.853)
		(width 0.182)
		(layer "F.Cu")
		(net 1)
	)
	(segment
		(start 168.985001 128.225001)
		(end 169.620001 127.590001)
		(width 0.256)
		(layer "F.Cu")
		(net 1)
	)
	(segment
		(start 241.255 94.51)
		(end 241.255 93.345)
		(width 0.256)
		(layer "F.Cu")
		(net 1)
	)
	(segment
		(start 163.905001 87.585001)
		(end 163.270001 86.950001)
		(width 0.256)
		(layer "F.Cu")
		(net 1)
	)
	(segment
		(start 226.2 152.6)
		(end 226.4 152.8)
		(width 0.256)
		(layer "F.Cu")
		(net 1)
	)
	(segment
		(start 200.291252 99.9)
		(end 200.241252 99.85)
		(width 0.4)
		(layer "F.Cu")
		(net 1)
	)
	(segment
		(start 157.555001 112.985001)
		(end 158.190001 112.350001)
		(width 0.256)
		(layer "F.Cu")
		(net 1)
	)
	(segment
		(start 241.2775 86.2225)
		(end 241.6 85.9)
		(width 0.256)
		(layer "F.Cu")
		(net 1)
	)
	(segment
		(start 259.715 101.25)
		(end 260.485 101.25)
		(width 0.182)
		(layer "F.Cu")
		(net 1)
	)
	(segment
		(start 165.810001 112.350001)
		(end 165.175001 111.715001)
		(width 0.201)
		(layer "F.Cu")
		(net 1)
	)
	(segment
		(start 258.4 145.2)
		(end 258.4 144.25)
		(width 0.4)
		(layer "F.Cu")
		(net 1)
	)
	(segment
		(start 168.350001 119.970001)
		(end 167.715001 120.605001)
		(width 0.256)
		(layer "F.Cu")
		(net 1)
	)
	(segment
		(start 191.115001 152.584999)
		(end 191.115001 151.685)
		(width 0.4)
		(layer "F.Cu")
		(net 1)
	)
	(segment
		(start 193.3 118.3)
		(end 193.3 117.7)
		(width 0.4)
		(layer "F.Cu")
		(net 1)
	)
	(segment
		(start 223.785 154.485)
		(end 223.7 154.4)
		(width 0.256)
		(layer "F.Cu")
		(net 1)
	)
	(segment
		(start 160.095001 101.555001)
		(end 160.730001 102.190001)
		(width 0.256)
		(layer "F.Cu")
		(net 1)
	)
	(segment
		(start 167.715001 111.715001)
		(end 168.350001 112.350001)
		(width 0.201)
		(layer "F.Cu")
		(net 1)
	)
	(segment
		(start 168.350001 127.590001)
		(end 167.715001 126.955001)
		(width 0.256)
		(layer "F.Cu")
		(net 1)
	)
	(segment
		(start 156.920001 117.430001)
		(end 156.285001 118.065001)
		(width 0.256)
		(layer "F.Cu")
		(net 1)
	)
	(segment
		(start 258.4 125.7)
		(end 258.4 125.9)
		(width 0.201)
		(layer "F.Cu")
		(net 1)
	)
	(segment
		(start 254.545 138.3195)
		(end 254.5605 138.3195)
		(width 0.198)
		(layer "F.Cu")
		(net 1)
	)
	(segment
		(start 162.2 150.7)
		(end 162.25 150.75)
		(width 0.4)
		(layer "F.Cu")
		(net 1)
	)
	(segment
		(start 207.5 122.5)
		(end 208 122)
		(width 0.4)
		(layer "F.Cu")
		(net 1)
	)
	(segment
		(start 258.6 125.5)
		(end 258.4 125.7)
		(width 0.201)
		(layer "F.Cu")
		(net 1)
	)
	(segment
		(start 154.1 139.3)
		(end 154.2 139.2)
		(width 0.4)
		(layer "F.Cu")
		(net 1)
	)
	(segment
		(start 189.5 138.5)
		(end 189 139)
		(width 0.4)
		(layer "F.Cu")
		(net 1)
	)
	(segment
		(start 155.015001 123.145001)
		(end 155.650001 122.510001)
		(width 0.256)
		(layer "F.Cu")
		(net 1)
	)
	(segment
		(start 258.36 119.913)
		(end 258.36 119.88)
		(width 0.114)
		(layer "F.Cu")
		(net 1)
	)
	(segment
		(start 168.985001 99.015001)
		(end 168.350001 99.650001)
		(width 0.256)
		(layer "F.Cu")
		(net 1)
	)
	(segment
		(start 232.365 95.765)
		(end 232.4 95.8)
		(width 0.256)
		(layer "F.Cu")
		(net 1)
	)
	(segment
		(start 193.5 129.5)
		(end 194 130)
		(width 0.4)
		(layer "F.Cu")
		(net 1)
	)
	(segment
		(start 162.635001 86.315001)
		(end 162.000001 86.950001)
		(width 0.256)
		(layer "F.Cu")
		(net 1)
	)
	(segment
		(start 166.445001 88.855001)
		(end 165.810001 89.490001)
		(width 0.256)
		(layer "F.Cu")
		(net 1)
	)
	(segment
		(start 190.814999 152.885001)
		(end 191.115001 152.584999)
		(width 0.4)
		(layer "F.Cu")
		(net 1)
	)
	(segment
		(start 193.29 122.29)
		(end 193.5 122.5)
		(width 0.4)
		(layer "F.Cu")
		(net 1)
	)
	(segment
		(start 173.999999 141.834316)
		(end 174 142.4)
		(width 0.4)
		(layer "F.Cu")
		(net 1)
	)
	(segment
		(start 166.445001 124.415001)
		(end 167.080001 125.050001)
		(width 0.256)
		(layer "F.Cu")
		(net 1)
	)
	(segment
		(start 167.715001 110.445001)
		(end 168.350001 109.810001)
		(width 0.201)
		(layer "F.Cu")
		(net 1)
	)
	(segment
		(start 229.7005 142.75)
		(end 229.425 143.0255)
		(width 0.256)
		(layer "F.Cu")
		(net 1)
	)
	(segment
		(start 231.4 138.5)
		(end 231.4 137.815)
		(width 0.182)
		(layer "F.Cu")
		(net 1)
	)
	(segment
		(start 196.5 126.5)
		(end 196 126)
		(width 0.4)
		(layer "F.Cu")
		(net 1)
	)
	(segment
		(start 193.5 115.5)
		(end 193.29 115.71)
		(width 0.4)
		(layer "F.Cu")
		(net 1)
	)
	(segment
		(start 155.015001 97.745001)
		(end 155.650001 97.110001)
		(width 0.256)
		(layer "F.Cu")
		(net 1)
	)
	(segment
		(start 160.730001 130.130001)
		(end 161.365001 129.495001)
		(width 0.256)
		(layer "F.Cu")
		(net 1)
	)
	(segment
		(start 268.8 87.8)
		(end 268.775 87.775)
		(width 0.1)
		(layer "F.Cu")
		(net 1)
	)
	(segment
		(start 153.8 146.165)
		(end 153.76 146.165)
		(width 0.201)
		(layer "F.Cu")
		(net 1)
	)
	(segment
		(start 205.5 126.5)
		(end 206 126)
		(width 0.4)
		(layer "F.Cu")
		(net 1)
	)
	(segment
		(start 257.45 142.4)
		(end 255.95 142.4)
		(width 0.4)
		(layer "F.Cu")
		(net 1)
	)
	(segment
		(start 244.735 113.15)
		(end 244.575 113.15)
		(width 0.1)
		(layer "F.Cu")
		(net 1)
	)
	(segment
		(start 260.485 101.25)
		(end 261.2 101.25)
		(width 0.182)
		(layer "F.Cu")
		(net 1)
	)
	(segment
		(start 185.000001 71.870001)
		(end 185 72)
		(width 0.1)
		(layer "F.Cu")
		(net 1)
	)
	(segment
		(start 255.925 142.375)
		(end 255.475 142.375)
		(width 0.4)
		(layer "F.Cu")
		(net 1)
	)
	(segment
		(start 171.599999 141.834316)
		(end 171.6 142.4)
		(width 0.4)
		(layer "F.Cu")
		(net 1)
	)
	(segment
		(start 167.715001 115.525001)
		(end 167.080001 114.890001)
		(width 0.256)
		(layer "F.Cu")
		(net 1)
	)
	(segment
		(start 193.5 128.5)
		(end 194 128)
		(width 0.4)
		(layer "F.Cu")
		(net 1)
	)
	(segment
		(start 155.015001 88.855001)
		(end 154.380001 89.490001)
		(width 0.201)
		(layer "F.Cu")
		(net 1)
	)
	(segment
		(start 166.445001 82.505001)
		(end 165.810001 81.870001)
		(width 0.256)
		(layer "F.Cu")
		(net 1)
	)
	(segment
		(start 159.460001 117.430001)
		(end 158.825001 118.065001)
		(width 0.256)
		(layer "F.Cu")
		(net 1)
	)
	(segment
		(start 193.5 122.5)
		(end 194 123)
		(width 0.4)
		(layer "F.Cu")
		(net 1)
	)
	(segment
		(start 206.5 119.5)
		(end 207 119)
		(width 0.4)
		(layer "F.Cu")
		(net 1)
	)
	(segment
		(start 212.5 137.5)
		(end 213 138)
		(width 0.4)
		(layer "F.Cu")
		(net 1)
	)
	(segment
		(start 157.555001 120.605001)
		(end 158.190001 119.970001)
		(width 0.256)
		(layer "F.Cu")
		(net 1)
	)
	(segment
		(start 167.6 142.4)
		(end 167.6 142.35)
		(width 0.1)
		(layer "F.Cu")
		(net 1)
	)
	(segment
		(start 195.5 136.5)
		(end 195 137)
		(width 0.4)
		(layer "F.Cu")
		(net 1)
	)
	(segment
		(start 225.75 159.8)
		(end 226.5 159.8)
		(width 0.201)
		(layer "F.Cu")
		(net 1)
	)
	(segment
		(start 232.3 126.075)
		(end 233.05 126.075)
		(width 0.4)
		(layer "F.Cu")
		(net 1)
	)
	(segment
		(start 166.445001 129.495001)
		(end 167.080001 130.130001)
		(width 0.256)
		(layer "F.Cu")
		(net 1)
	)
	(segment
		(start 239.5 143.2)
		(end 239.5 144.075)
		(width 0.256)
		(layer "F.Cu")
		(net 1)
	)
	(segment
		(start 192.625 168.7)
		(end 193.1 168.225)
		(width 0.182)
		(layer "F.Cu")
		(net 1)
	)
	(segment
		(start 194.591252 97.823748)
		(end 195.34 97.075)
		(width 0.182)
		(layer "F.Cu")
		(net 1)
	)
	(segment
		(start 153.585 139.2)
		(end 154.585 139.2)
		(width 0.4)
		(layer "F.Cu")
		(net 1)
	)
	(segment
		(start 244.6 127.8)
		(end 245.125 127.8)
		(width 0.201)
		(layer "F.Cu")
		(net 1)
	)
	(segment
		(start 161.365001 87.585001)
		(end 162.000001 86.950001)
		(width 0.201)
		(layer "F.Cu")
		(net 1)
	)
	(segment
		(start 245.13 142.1)
		(end 245.115 142.085)
		(width 0.201)
		(layer "F.Cu")
		(net 1)
	)
	(segment
		(start 166.445001 109.175001)
		(end 167.080001 109.810001)
		(width 0.201)
		(layer "F.Cu")
		(net 1)
	)
	(segment
		(start 223.475 94.51)
		(end 223.475 92.725)
		(width 0.201)
		(layer "F.Cu")
		(net 1)
	)
	(segment
		(start 156.285001 99.015001)
		(end 156.920001 99.650001)
		(width 0.256)
		(layer "F.Cu")
		(net 1)
	)
	(segment
		(start 155.015001 82.505001)
		(end 154.380001 81.870001)
		(width 0.201)
		(layer "F.Cu")
		(net 1)
	)
	(segment
		(start 232.3 131.875)
		(end 232.3 130.315)
		(width 0.4)
		(layer "F.Cu")
		(net 1)
	)
	(segment
		(start 162.635001 93.935001)
		(end 162.000001 94.570001)
		(width 0.256)
		(layer "F.Cu")
		(net 1)
	)
	(segment
		(start 201.206252 101.9)
		(end 201.206252 100.9)
		(width 0.4)
		(layer "F.Cu")
		(net 1)
	)
	(segment
		(start 226.55 122.65)
		(end 226.97235 122.22765)
		(width 0.4)
		(layer "F.Cu")
		(net 1)
	)
	(segment
		(start 167.6 142.35)
		(end 167.55 142.3)
		(width 0.1)
		(layer "F.Cu")
		(net 1)
	)
	(segment
		(start 160.095001 93.935001)
		(end 160.730001 94.570001)
		(width 0.201)
		(layer "F.Cu")
		(net 1)
	)
	(segment
		(start 198.35 87.2)
		(end 198.35 87.84)
		(width 0.182)
		(layer "F.Cu")
		(net 1)
	)
	(segment
		(start 210.5 131.5)
		(end 211 132)
		(width 0.4)
		(layer "F.Cu")
		(net 1)
	)
	(segment
		(start 194.445001 86.145001)
		(end 195 86.7)
		(width 0.201)
		(layer "F.Cu")
		(net 1)
	)
	(segment
		(start 255.2515 135.2495)
		(end 255.2515 135.2415)
		(width 0.198)
		(layer "F.Cu")
		(net 1)
	)
	(segment
		(start 221.715 155.585)
		(end 221.7 155.6)
		(width 0.256)
		(layer "F.Cu")
		(net 1)
	)
	(segment
		(start 262.7 123.8)
		(end 262.6 123.9)
		(width 0.201)
		(layer "F.Cu")
		(net 1)
	)
	(segment
		(start 163.905001 82.505001)
		(end 164.540001 81.870001)
		(width 0.201)
		(layer "F.Cu")
		(net 1)
	)
	(segment
		(start 195.325 108.75)
		(end 194.575 108)
		(width 0.182)
		(layer "F.Cu")
		(net 1)
	)
	(segment
		(start 183.000001 71.870001)
		(end 183 72)
		(width 0.1)
		(layer "F.Cu")
		(net 1)
	)
	(segment
		(start 221.015 145.7)
		(end 220.55 145.7)
		(width 0.256)
		(layer "F.Cu")
		(net 1)
	)
	(segment
		(start 199.5 133.5)
		(end 199 134)
		(width 0.4)
		(layer "F.Cu")
		(net 1)
	)
	(segment
		(start 168.985001 102.825001)
		(end 168.350001 102.190001)
		(width 0.256)
		(layer "F.Cu")
		(net 1)
	)
	(segment
		(start 220.35 137.675)
		(end 220.2 137.825)
		(width 0.256)
		(layer "F.Cu")
		(net 1)
	)
	(segment
		(start 231.35 138.45)
		(end 231.4 138.5)
		(width 0.182)
		(layer "F.Cu")
		(net 1)
	)
	(segment
		(start 163.905001 96.475001)
		(end 164.540001 97.110001)
		(width 0.256)
		(layer "F.Cu")
		(net 1)
	)
	(segment
		(start 220.4 146.2)
		(end 220.4 146.55)
		(width 0.256)
		(layer "F.Cu")
		(net 1)
	)
	(segment
		(start 239.5 144.075)
		(end 239.25 144.325)
		(width 0.256)
		(layer "F.Cu")
		(net 1)
	)
	(segment
		(start 168.985001 97.745001)
		(end 169.620001 97.110001)
		(width 0.201)
		(layer "F.Cu")
		(net 1)
	)
	(segment
		(start 243.3 136.95)
		(end 243.05 137.2)
		(width 0.201)
		(layer "F.Cu")
		(net 1)
	)
	(segment
		(start 194.591252 97.85)
		(end 194.591252 97.823748)
		(width 0.182)
		(layer "F.Cu")
		(net 1)
	)
	(segment
		(start 189.24 146.59)
		(end 189.5 146.85)
		(width 0.114)
		(layer "F.Cu")
		(net 1)
	)
	(segment
		(start 222.205 92.705)
		(end 222.2 92.7)
		(width 0.201)
		(layer "F.Cu")
		(net 1)
	)
	(segment
		(start 193.5 127.5)
		(end 194 128)
		(width 0.4)
		(layer "F.Cu")
		(net 1)
	)
	(segment
		(start 153.745001 81.235001)
		(end 154.380001 81.870001)
		(width 0.256)
		(layer "F.Cu")
		(net 1)
	)
	(segment
		(start 263.65 133.75)
		(end 263.7 133.7)
		(width 0.201)
		(layer "F.Cu")
		(net 1)
	)
	(segment
		(start 155.015001 129.495001)
		(end 155.650001 130.130001)
		(width 0.256)
		(layer "F.Cu")
		(net 1)
	)
	(segment
		(start 155.015001 109.175001)
		(end 154.380001 109.810001)
		(width 0.256)
		(layer "F.Cu")
		(net 1)
	)
	(segment
		(start 194.5 132.5)
		(end 194 133)
		(width 0.4)
		(layer "F.Cu")
		(net 1)
	)
	(segment
		(start 166.445001 107.905001)
		(end 167.080001 107.270001)
		(width 0.201)
		(layer "F.Cu")
		(net 1)
	)
	(segment
		(start 214.805 163.15)
		(end 215.35 163.15)
		(width 0.201)
		(layer "F.Cu")
		(net 1)
	)
	(segment
		(start 160.095001 85.045001)
		(end 159.460001 84.410001)
		(width 0.201)
		(layer "F.Cu")
		(net 1)
	)
	(segment
		(start 255.3 98.9)
		(end 254.9 98.5)
		(width 0.182)
		(layer "F.Cu")
		(net 1)
	)
	(segment
		(start 263.61 130.2)
		(end 262.8 130.2)
		(width 0.201)
		(layer "F.Cu")
		(net 1)
	)
	(segment
		(start 240.6 132.7)
		(end 240.6 133.1)
		(width 0.182)
		(layer "F.Cu")
		(net 1)
	)
	(segment
		(start 207.891252 96.55)
		(end 207.891252 95.6225)
		(width 0.182)
		(layer "F.Cu")
		(net 1)
	)
	(segment
		(start 232.3 126.075)
		(end 232.3 124.515)
		(width 0.4)
		(layer "F.Cu")
		(net 1)
	)
	(segment
		(start 165.175001 128.225001)
		(end 164.540001 127.590001)
		(width 0.256)
		(layer "F.Cu")
		(net 1)
	)
	(segment
		(start 256.845 133.75)
		(end 256.83 133.735)
		(width 0.198)
		(layer "F.Cu")
		(net 1)
	)
	(segment
		(start 160.730001 109.810001)
		(end 160.095001 109.175001)
		(width 0.201)
		(layer "F.Cu")
		(net 1)
	)
	(segment
		(start 258.235 82.05)
		(end 258.4 81.885)
		(width 0.256)
		(layer "F.Cu")
		(net 1)
	)
	(segment
		(start 196.5 139.5)
		(end 196 140)
		(width 0.4)
		(layer "F.Cu")
		(net 1)
	)
	(segment
		(start 199.5 127.5)
		(end 199 127)
		(width 0.4)
		(layer "F.Cu")
		(net 1)
	)
	(segment
		(start 168.985001 107.905001)
		(end 169.620001 107.270001)
		(width 0.201)
		(layer "F.Cu")
		(net 1)
	)
	(segment
		(start 227 140.275)
		(end 228.715 140.275)
		(width 0.256)
		(layer "F.Cu")
		(net 1)
	)
	(segment
		(start 210.75 79.73)
		(end 211.345 79.73)
		(width 0.182)
		(layer "F.Cu")
		(net 1)
	)
	(segment
		(start 167.715001 85.045001)
		(end 167.080001 84.410001)
		(width 0.201)
		(layer "F.Cu")
		(net 1)
	)
	(segment
		(start 267.35 137.8)
		(end 268.1 138.55)
		(width 0.182)
		(layer "F.Cu")
		(net 1)
	)
	(segment
		(start 250.5 101.1)
		(end 250.6 101.1)
		(width 0.4)
		(layer "F.Cu")
		(net 1)
	)
	(segment
		(start 156.285001 106.635001)
		(end 155.650001 107.270001)
		(width 0.256)
		(layer "F.Cu")
		(net 1)
	)
	(segment
		(start 208.5 115.5)
		(end 209 115)
		(width 0.4)
		(layer "F.Cu")
		(net 1)
	)
	(segment
		(start 156.285001 118.065001)
		(end 156.285001 118.070001)
		(width 0.256)
		(layer "F.Cu")
		(net 1)
	)
	(segment
		(start 155.015001 128.225001)
		(end 154.380001 127.590001)
		(width 0.256)
		(layer "F.Cu")
		(net 1)
	)
	(segment
		(start 157.555001 101.555001)
		(end 158.190001 102.190001)
		(width 0.256)
		(layer "F.Cu")
		(net 1)
	)
	(segment
		(start 158.7 143.3)
		(end 158.9 143.1)
		(width 0.4)
		(layer "F.Cu")
		(net 1)
	)
	(segment
		(start 170.255001 116.795001)
		(end 169.620001 117.430001)
		(width 0.256)
		(layer "F.Cu")
		(net 1)
	)
	(segment
		(start 177.7375 173.9625)
		(end 177.7375 174.85)
		(width 0.182)
		(layer "F.Cu")
		(net 1)
	)
	(segment
		(start 165.175001 86.315001)
		(end 164.540001 86.950001)
		(width 0.256)
		(layer "F.Cu")
		(net 1)
	)
	(segment
		(start 167.715001 121.875001)
		(end 168.350001 122.510001)
		(width 0.256)
		(layer "F.Cu")
		(net 1)
	)
	(segment
		(start 189.000001 71.870001)
		(end 189 72)
		(width 0.1)
		(layer "F.Cu")
		(net 1)
	)
	(segment
		(start 157.555001 93.935001)
		(end 158.190001 94.570001)
		(width 0.201)
		(layer "F.Cu")
		(net 1)
	)
	(segment
		(start 258.4 143.35)
		(end 257.45 142.4)
		(width 0.4)
		(layer "F.Cu")
		(net 1)
	)
	(segment
		(start 231.3 159.8)
		(end 230.7 160.4)
		(width 0.201)
		(layer "F.Cu")
		(net 1)
	)
	(segment
		(start 197.8 109.5)
		(end 196.075 109.5)
		(width 0.182)
		(layer "F.Cu")
		(net 1)
	)
	(segment
		(start 196.5 132.5)
		(end 196 133)
		(width 0.4)
		(layer "F.Cu")
		(net 1)
	)
	(segment
		(start 195.000001 71.870001)
		(end 195 72)
		(width 0.1)
		(layer "F.Cu")
		(net 1)
	)
	(segment
		(start 157.555001 81.235001)
		(end 157.555001 81.227689)
		(width 0.256)
		(layer "F.Cu")
		(net 1)
	)
	(segment
		(start 189.5 148.15)
		(end 189.5 146.85)
		(width 0.4)
		(layer "F.Cu")
		(net 1)
	)
	(segment
		(start 167.715001 115.525001)
		(end 168.350001 114.890001)
		(width 0.256)
		(layer "F.Cu")
		(net 1)
	)
	(segment
		(start 163.905001 111.715001)
		(end 163.270001 112.350001)
		(width 0.201)
		(layer "F.Cu")
		(net 1)
	)
	(segment
		(start 157.555001 93.935001)
		(end 156.920001 94.570001)
		(width 0.256)
		(layer "F.Cu")
		(net 1)
	)
	(segment
		(start 258.235 91.65)
		(end 258.4 91.485)
		(width 0.256)
		(layer "F.Cu")
		(net 1)
	)
	(segment
		(start 174.77 188.63)
		(end 174.76 188.64)
		(width 0.4)
		(layer "F.Cu")
		(net 1)
	)
	(segment
		(start 231.45 140.25)
		(end 231.4 140.3)
		(width 0.182)
		(layer "F.Cu")
		(net 1)
	)
	(segment
		(start 190.4 152.885001)
		(end 190.814999 152.885001)
		(width 0.4)
		(layer "F.Cu")
		(net 1)
	)
	(segment
		(start 240.75 146.35)
		(end 240.75 147.2)
		(width 0.4)
		(layer "F.Cu")
		(net 1)
	)
	(segment
		(start 259.115 125.5)
		(end 258.6 125.5)
		(width 0.201)
		(layer "F.Cu")
		(net 1)
	)
	(segment
		(start 255.475 142.375)
		(end 254.85 141.75)
		(width 0.4)
		(layer "F.Cu")
		(net 1)
	)
	(segment
		(start 256.945 140.32)
		(end 256.82 140.32)
		(width 0.201)
		(layer "F.Cu")
		(net 1)
	)
	(segment
		(start 153.745001 121.875001)
		(end 154.380001 122.510001)
		(width 0.256)
		(layer "F.Cu")
		(net 1)
	)
	(segment
		(start 209.78 157.56)
		(end 209.365 157.56)
		(width 0.4)
		(layer "F.Cu")
		(net 1)
	)
	(segment
		(start 214.5 123.5)
		(end 215 123)
		(width 0.4)
		(layer "F.Cu")
		(net 1)
	)
	(segment
		(start 153.745001 110.445001)
		(end 154.380001 109.810001)
		(width 0.201)
		(layer "F.Cu")
		(net 1)
	)
	(segment
		(start 171.6 148.4)
		(end 171.6 148)
		(width 0.4)
		(layer "F.Cu")
		(net 1)
	)
	(segment
		(start 196.2 185.8)
		(end 196.3 185.8)
		(width 0.1)
		(layer "F.Cu")
		(net 1)
	)
	(segment
		(start 197.5 133.5)
		(end 197 134)
		(width 0.4)
		(layer "F.Cu")
		(net 1)
	)
	(segment
		(start 160.7875 174.825)
		(end 160.8125 174.85)
		(width 0.182)
		(layer "F.Cu")
		(net 1)
	)
	(segment
		(start 194.5 128.5)
		(end 194 128)
		(width 0.4)
		(layer "F.Cu")
		(net 1)
	)
	(segment
		(start 247.15 127.775)
		(end 247.15 126.75)
		(width 0.201)
		(layer "F.Cu")
		(net 1)
	)
	(segment
		(start 222.11 86.2225)
		(end 222.11 84.74)
		(width 0.201)
		(layer "F.Cu")
		(net 1)
	)
	(segment
		(start 199.5 118.5)
		(end 199 118)
		(width 0.4)
		(layer "F.Cu")
		(net 1)
	)
	(segment
		(start 153.745001 105.365001)
		(end 154.380001 104.730001)
		(width 0.201)
		(layer "F.Cu")
		(net 1)
	)
	(segment
		(start 203.75 87.2)
		(end 203.75 87.825)
		(width 0.182)
		(layer "F.Cu")
		(net 1)
	)
	(segment
		(start 193.5 132.5)
		(end 193 133)
		(width 0.4)
		(layer "F.Cu")
		(net 1)
	)
	(segment
		(start 200.4 107.2)
		(end 200.4 106.2)
		(width 0.182)
		(layer "F.Cu")
		(net 1)
	)
	(segment
		(start 207.891252 95.6225)
		(end 207.891252 95.541252)
		(width 0.182)
		(layer "F.Cu")
		(net 1)
	)
	(segment
		(start 200.4 105.8837)
		(end 200.0255 105.5092)
		(width 0.182)
		(layer "F.Cu")
		(net 1)
	)
	(segment
		(start 168.985001 114.255001)
		(end 168.350001 114.890001)
		(width 0.256)
		(layer "F.Cu")
		(net 1)
	)
	(segment
		(start 161.365001 82.505001)
		(end 160.730001 81.870001)
		(width 0.256)
		(layer "F.Cu")
		(net 1)
	)
	(segment
		(start 258.235 96.45)
		(end 258.4 96.285)
		(width 0.256)
		(layer "F.Cu")
		(net 1)
	)
	(segment
		(start 255.95 142.4)
		(end 255.925 142.375)
		(width 0.4)
		(layer "F.Cu")
		(net 1)
	)
	(segment
		(start 220.55 146.7)
		(end 220.4 146.55)
		(width 0.256)
		(layer "F.Cu")
		(net 1)
	)
	(segment
		(start 240.85 140)
		(end 241.05 140.2)
		(width 0.182)
		(layer "F.Cu")
		(net 1)
	)
	(segment
		(start 212.5 127.5)
		(end 213 127)
		(width 0.4)
		(layer "F.Cu")
		(net 1)
	)
	(segment
		(start 211.5 124.5)
		(end 212 124)
		(width 0.4)
		(layer "F.Cu")
		(net 1)
	)
	(segment
		(start 252.8 101.3)
		(end 252.85 101.3)
		(width 0.4)
		(layer "F.Cu")
		(net 1)
	)
	(segment
		(start 243.525 132.325)
		(end 243.4 132.325)
		(width 0.201)
		(layer "F.Cu")
		(net 1)
	)
	(segment
		(start 246.15 139.8375)
		(end 246.15 138.15)
		(width 0.201)
		(layer "F.Cu")
		(net 1)
	)
	(segment
		(start 177.7375 174.85)
		(end 177.75 174.8625)
		(width 0.182)
		(layer "F.Cu")
		(net 1)
	)
	(segment
		(start 213.5 120.5)
		(end 214 120)
		(width 0.4)
		(layer "F.Cu")
		(net 1)
	)
	(segment
		(start 165.175001 115.525001)
		(end 165.810001 114.890001)
		(width 0.256)
		(layer "F.Cu")
		(net 1)
	)
	(segment
		(start 245.125 127.8)
		(end 245.15 127.775)
		(width 0.201)
		(layer "F.Cu")
		(net 1)
	)
	(segment
		(start 250.4 101)
		(end 250.4 99.985)
		(width 0.4)
		(layer "F.Cu")
		(net 1)
	)
	(segment
		(start 227.15 162.18)
		(end 228.4 163.43)
		(width 0.201)
		(layer "F.Cu")
		(net 1)
	)
	(segment
		(start 186.25 175.65)
		(end 186.3 175.6)
		(width 0.1)
		(layer "F.Cu")
		(net 1)
	)
	(segment
		(start 167.715003 81.235003)
		(end 168.350003 81.870003)
		(width 0.256)
		(layer "F.Cu")
		(net 1)
	)
	(segment
		(start 193.5 123.5)
		(end 194 123)
		(width 0.4)
		(layer "F.Cu")
		(net 1)
	)
	(segment
		(start 196.075 109.5)
		(end 195.325 108.75)
		(width 0.182)
		(layer "F.Cu")
		(net 1)
	)
	(segment
		(start 221.9 165.7)
		(end 221.285 165.7)
		(width 0.201)
		(layer "F.Cu")
		(net 1)
	)
	(segment
		(start 194.5 102.435)
		(end 194.5762 102.435)
		(width 0.182)
		(layer "F.Cu")
		(net 1)
	)
	(segment
		(start 205.5 136.5)
		(end 206 137)
		(width 0.4)
		(layer "F.Cu")
		(net 1)
	)
	(segment
		(start 193.7 168.715)
		(end 193.59 168.715)
		(width 0.182)
		(layer "F.Cu")
		(net 1)
	)
	(segment
		(start 204.5 123.5)
		(end 205 123)
		(width 0.4)
		(layer "F.Cu")
		(net 1)
	)
	(segment
		(start 168.985001 114.255001)
		(end 169.620001 114.890001)
		(width 0.256)
		(layer "F.Cu")
		(net 1)
	)
	(segment
		(start 197.09 93.1)
		(end 198.022851 93.1)
		(width 0.4)
		(layer "F.Cu")
		(net 1)
	)
	(via
		(at 193.91 146.85)
		(size 0.45)
		(drill 0.2)
		(layers "F.Cu" "B.Cu")
		(net 1)
	)
	(via
		(at 198 126)
		(size 0.45)
		(drill 0.2)
		(layers "F.Cu" "B.Cu")
		(net 1)
	)
	(via
		(at 158.190001 130.130001)
		(size 0.45)
		(drill 0.2)
		(layers "F.Cu" "B.Cu")
		(net 1)
	)
	(via
		(at 264.75 83.3)
		(size 0.45)
		(drill 0.2)
		(layers "F.Cu" "B.Cu")
		(net 1)
	)
	(via
		(at 262.7 130.1)
		(size 0.45)
		(drill 0.2)
		(layers "F.Cu" "B.Cu")
		(net 1)
	)
	(via
		(at 166.275 142.225)
		(size 0.45)
		(drill 0.2)
		(layers "F.Cu" "B.Cu")
		(net 1)
	)
	(via
		(at 186.500001 123.500001)
		(size 0.45)
		(drill 0.2)
		(layers "F.Cu" "B.Cu")
		(net 1)
	)
	(via
		(at 163.270001 127.590001)
		(size 0.45)
		(drill 0.2)
		(layers "F.Cu" "B.Cu")
		(net 1)
	)
	(via
		(at 165.810001 102.190001)
		(size 0.45)
		(drill 0.2)
		(layers "F.Cu" "B.Cu")
		(net 1)
	)
	(via
		(at 193.075 141.025)
		(size 0.45)
		(drill 0.2)
		(layers "F.Cu" "B.Cu")
		(net 1)
	)
	(via
		(at 163.270001 86.950001)
		(size 0.45)
		(drill 0.2)
		(layers "F.Cu" "B.Cu")
		(net 1)
	)
	(via
		(at 234.7995 132.76)
		(size 0.45)
		(drill 0.2)
		(layers "F.Cu" "B.Cu")
		(net 1)
	)
	(via
		(at 207.6 95.25)
		(size 0.45)
		(drill 0.2)
		(layers "F.Cu" "B.Cu")
		(net 1)
	)
	(via
		(at 220.95 92.7)
		(size 0.45)
		(drill 0.2)
		(layers "F.Cu" "B.Cu")
		(net 1)
	)
	(via
		(at 158.190001 104.730001)
		(size 0.45)
		(drill 0.2)
		(layers "F.Cu" "B.Cu")
		(net 1)
	)
	(via
		(at 177.15 169.6125)
		(size 0.45)
		(drill 0.2)
		(layers "F.Cu" "B.Cu")
		(net 1)
	)
	(via
		(at 199 134)
		(size 0.45)
		(drill 0.2)
		(layers "F.Cu" "B.Cu")
		(net 1)
	)
	(via
		(at 244.575 113.15)
		(size 0.45)
		(drill 0.2)
		(layers "F.Cu" "B.Cu")
		(net 1)
	)
	(via
		(at 175.6 164)
		(size 0.45)
		(drill 0.2)
		(layers "F.Cu" "B.Cu")
		(net 1)
	)
	(via
		(at 156.920001 102.190001)
		(size 0.45)
		(drill 0.2)
		(layers "F.Cu" "B.Cu")
		(net 1)
	)
	(via
		(at 171.975 109.225)
		(size 0.45)
		(drill 0.2)
		(layers "F.Cu" "B.Cu")
		(net 1)
	)
	(via
		(at 220.4 153.9)
		(size 0.45)
		(drill 0.2)
		(layers "F.Cu" "B.Cu")
		(net 1)
	)
	(via
		(at 197.24 162.03)
		(size 0.45)
		(drill 0.2)
		(layers "F.Cu" "B.Cu")
		(free yes)
		(net 1)
	)
	(via
		(at 193.025 175.2)
		(size 0.45)
		(drill 0.2)
		(layers "F.Cu" "B.Cu")
		(net 1)
	)
	(via
		(at 191.25 159.5)
		(size 0.45)
		(drill 0.2)
		(layers "F.Cu" "B.Cu")
		(free yes)
		(net 1)
	)
	(via
		(at 154.380001 92.030001)
		(size 0.45)
		(drill 0.2)
		(layers "F.Cu" "B.Cu")
		(net 1)
	)
	(via
		(at 252.85 101.3)
		(size 0.45)
		(drill 0.2)
		(layers "F.Cu" "B.Cu")
		(net 1)
	)
	(via
		(at 176.64 170.26)
		(size 0.45)
		(drill 0.2)
		(layers "F.Cu" "B.Cu")
		(net 1)
	)
	(via
		(at 214 120)
		(size 0.45)
		(drill 0.2)
		(layers "F.Cu" "B.Cu")
		(net 1)
	)
	(via
		(at 231.4 140.3)
		(size 0.45)
		(drill 0.2)
		(layers "F.Cu" "B.Cu")
		(net 1)
	)
	(via
		(at 180 167.4)
		(size 0.45)
		(drill 0.2)
		(layers "F.Cu" "B.Cu")
		(net 1)
	)
	(via
		(at 185.4 91.8)
		(size 0.45)
		(drill 0.2)
		(layers "F.Cu" "B.Cu")
		(net 1)
	)
	(via
		(at 245.115 142.085)
		(size 0.45)
		(drill 0.2)
		(layers "F.Cu" "B.Cu")
		(net 1)
	)
	(via
		(at 210.25 174.9)
		(size 0.45)
		(drill 0.2)
		(layers "F.Cu" "B.Cu")
		(net 1)
	)
	(via
		(at 198 148.4)
		(size 0.45)
		(drill 0.2)
		(layers "F.Cu" "B.Cu")
		(net 1)
	)
	(via
		(at 164.540001 127.590001)
		(size 0.45)
		(drill 0.2)
		(layers "F.Cu" "B.Cu")
		(net 1)
	)
	(via
		(at 167.080001 130.130001)
		(size 0.45)
		(drill 0.2)
		(layers "F.Cu" "B.Cu")
		(net 1)
	)
	(via
		(at 207.65 92.65)
		(size 0.45)
		(drill 0.2)
		(layers "F.Cu" "B.Cu")
		(net 1)
	)
	(via
		(at 202.65 87.2)
		(size 0.45)
		(drill 0.2)
		(layers "F.Cu" "B.Cu")
		(net 1)
	)
	(via
		(at 158.190001 84.410001)
		(size 0.45)
		(drill 0.2)
		(layers "F.Cu" "B.Cu")
		(net 1)
	)
	(via
		(at 192.5 126.5)
		(size 0.45)
		(drill 0.2)
		(layers "F.Cu" "B.Cu")
		(net 1)
	)
	(via
		(at 169.620001 119.970001)
		(size 0.45)
		(drill 0.2)
		(layers "F.Cu" "B.Cu")
		(net 1)
	)
	(via
		(at 194.587566 95.649783)
		(size 0.45)
		(drill 0.2)
		(layers "F.Cu" "B.Cu")
		(net 1)
	)
	(via
		(at 183.77 183.54)
		(size 0.45)
		(drill 0.2)
		(layers "F.Cu" "B.Cu")
		(net 1)
	)
	(via
		(at 158.190001 89.490001)
		(size 0.45)
		(drill 0.2)
		(layers "F.Cu" "B.Cu")
		(net 1)
	)
	(via
		(at 264.915 173)
		(size 0.45)
		(drill 0.2)
		(layers "F.Cu" "B.Cu")
		(net 1)
	)
	(via
		(at 154.380001 86.950001)
		(size 0.45)
		(drill 0.2)
		(layers "F.Cu" "B.Cu")
		(net 1)
	)
	(via
		(at 169.620001 86.950001)
		(size 0.45)
		(drill 0.2)
		(layers "F.Cu" "B.Cu")
		(net 1)
	)
	(via
		(at 175.05 170.8375)
		(size 0.45)
		(drill 0.2)
		(layers "F.Cu" "B.Cu")
		(net 1)
	)
	(via
		(at 158.190001 86.950001)
		(size 0.45)
		(drill 0.2)
		(layers "F.Cu" "B.Cu")
		(net 1)
	)
	(via
		(at 171.175237 99.129265)
		(size 0.45)
		(drill 0.2)
		(layers "F.Cu" "B.Cu")
		(net 1)
	)
	(via
		(at 185.4 89.4)
		(size 0.45)
		(drill 0.2)
		(layers "F.Cu" "B.Cu")
		(net 1)
	)
	(via
		(at 253.75 111.25)
		(size 0.45)
		(drill 0.2)
		(layers "F.Cu" "B.Cu")
		(net 1)
	)
	(via
		(at 223.55 161.45)
		(size 0.45)
		(drill 0.2)
		(layers "F.Cu" "B.Cu")
		(net 1)
	)
	(via
		(at 186.425 107.425)
		(size 0.45)
		(drill 0.2)
		(layers "F.Cu" "B.Cu")
		(net 1)
	)
	(via
		(at 214 130)
		(size 0.45)
		(drill 0.2)
		(layers "F.Cu" "B.Cu")
		(net 1)
	)
	(via
		(at 155.650001 122.510001)
		(size 0.45)
		(drill 0.2)
		(layers "F.Cu" "B.Cu")
		(net 1)
	)
	(via
		(at 165.810001 127.590001)
		(size 0.45)
		(drill 0.2)
		(layers "F.Cu" "B.Cu")
		(net 1)
	)
	(via
		(at 190.668043 88.900153)
		(size 0.45)
		(drill 0.2)
		(layers "F.Cu" "B.Cu")
		(net 1)
	)
	(via
		(at 208.2 150.4)
		(size 0.45)
		(drill 0.2)
		(layers "F.Cu" "B.Cu")
		(net 1)
	)
	(via
		(at 166.025 148.825)
		(size 0.45)
		(drill 0.2)
		(layers "F.Cu" "B.Cu")
		(net 1)
	)
	(via
		(at 217.29 129.15)
		(size 0.45)
		(drill 0.2)
		(layers "F.Cu" "B.Cu")
		(net 1)
	)
	(via
		(at 150.76 120.6)
		(size 0.45)
		(drill 0.2)
		(layers "F.Cu" "B.Cu")
		(net 1)
	)
	(via
		(at 169.620001 125.050001)
		(size 0.45)
		(drill 0.2)
		(layers "F.Cu" "B.Cu")
		(net 1)
	)
	(via
		(at 214 141)
		(size 0.45)
		(drill 0.2)
		(layers "F.Cu" "B.Cu")
		(net 1)
	)
	(via
		(at 176.165001 84.950001)
		(size 0.45)
		(drill 0.2)
		(layers "F.Cu" "B.Cu")
		(net 1)
	)
	(via
		(at 254.075 131.075)
		(size 0.45)
		(drill 0.2)
		(layers "F.Cu" "B.Cu")
		(net 1)
	)
	(via
		(at 269.3 90.63)
		(size 0.45)
		(drill 0.2)
		(layers "F.Cu" "B.Cu")
		(net 1)
	)
	(via
		(at 154.380001 89.490001)
		(size 0.45)
		(drill 0.2)
		(layers "F.Cu" "B.Cu")
		(net 1)
	)
	(via
		(at 174.650001 85.800001)
		(size 0.45)
		(drill 0.2)
		(layers "F.Cu" "B.Cu")
		(net 1)
	)
	(via
		(at 172.2 168)
		(size 0.45)
		(drill 0.2)
		(layers "F.Cu" "B.Cu")
		(net 1)
	)
	(via
		(at 186.500001 115.500001)
		(size 0.45)
		(drill 0.2)
		(layers "F.Cu" "B.Cu")
		(net 1)
	)
	(via
		(at 167.080001 81.870001)
		(size 0.45)
		(drill 0.2)
		(layers "F.Cu" "B.Cu")
		(net 1)
	)
	(via
		(at 184.285001 80.222501)
		(size 0.45)
		(drill 0.2)
		(layers "F.Cu" "B.Cu")
		(net 1)
	)
	(via
		(at 159.460001 122.510001)
		(size 0.45)
		(drill 0.2)
		(layers "F.Cu" "B.Cu")
		(net 1)
	)
	(via
		(at 193.99 145.22)
		(size 0.45)
		(drill 0.2)
		(layers "F.Cu" "B.Cu")
		(net 1)
	)
	(via
		(at 168.350001 109.810001)
		(size 0.45)
		(drill 0.2)
		(layers "F.Cu" "B.Cu")
		(net 1)
	)
	(via
		(at 164.85 187.55)
		(size 0.45)
		(drill 0.2)
		(layers "F.Cu" "B.Cu")
		(net 1)
	)
	(via
		(at 165.810001 81.870001)
		(size 0.45)
		(drill 0.2)
		(layers "F.Cu" "B.Cu")
		(net 1)
	)
	(via
		(at 230.61 70.73)
		(size 0.45)
		(drill 0.2)
		(layers "F.Cu" "B.Cu")
		(net 1)
	)
	(via
		(at 160.730001 122.510001)
		(size 0.45)
		(drill 0.2)
		(layers "F.Cu" "B.Cu")
		(net 1)
	)
	(via
		(at 150.72 125.64)
		(size 0.45)
		(drill 0.2)
		(layers "F.Cu" "B.Cu")
		(net 1)
	)
	(via
		(at 252 160)
		(size 0.45)
		(drill 0.2)
		(layers "F.Cu" "B.Cu")
		(net 1)
	)
	(via
		(at 168.350001 130.130001)
		(size 0.45)
		(drill 0.2)
		(layers "F.Cu" "B.Cu")
		(net 1)
	)
	(via
		(at 154.1 141.5)
		(size 0.45)
		(drill 0.2)
		(layers "F.Cu" "B.Cu")
		(net 1)
	)
	(via
		(at 156.920001 117.430001)
		(size 0.45)
		(drill 0.2)
		(layers "F.Cu" "B.Cu")
		(net 1)
	)
	(via
		(at 176.87 101.32)
		(size 0.45)
		(drill 0.2)
		(layers "F.Cu" "B.Cu")
		(net 1)
	)
	(via
		(at 254.8 167.285)
		(size 0.45)
		(drill 0.2)
		(layers "F.Cu" "B.Cu")
		(net 1)
	)
	(via
		(at 159.460001 97.110001)
		(size 0.45)
		(drill 0.2)
		(layers "F.Cu" "B.Cu")
		(net 1)
	)
	(via
		(at 188.500001 120.500001)
		(size 0.45)
		(drill 0.2)
		(layers "F.Cu" "B.Cu")
		(net 1)
	)
	(via
		(at 262.6 146)
		(size 0.45)
		(drill 0.2)
		(layers "F.Cu" "B.Cu")
		(net 1)
	)
	(via
		(at 268.1 138.55)
		(size 0.45)
		(drill 0.2)
		(layers "F.Cu" "B.Cu")
		(net 1)
	)
	(via
		(at 188.500001 118.500001)
		(size 0.45)
		(drill 0.2)
		(layers "F.Cu" "B.Cu")
		(net 1)
	)
	(via
		(at 191.58 145.18)
		(size 0.45)
		(drill 0.2)
		(layers "F.Cu" "B.Cu")
		(net 1)
	)
	(via
		(at 214.8 159.975)
		(size 0.45)
		(drill 0.2)
		(layers "F.Cu" "B.Cu")
		(net 1)
	)
	(via
		(at 197 143)
		(size 0.45)
		(drill 0.2)
		(layers "F.Cu" "B.Cu")
		(net 1)
	)
	(via
		(at 213 117)
		(size 0.45)
		(drill 0.2)
		(layers "F.Cu" "B.Cu")
		(net 1)
	)
	(via
		(at 194 133)
		(size 0.45)
		(drill 0.2)
		(layers "F.Cu" "B.Cu")
		(net 1)
	)
	(via
		(at 217.8 136.2)
		(size 0.45)
		(drill 0.2)
		(layers "F.Cu" "B.Cu")
		(net 1)
	)
	(via
		(at 159.8 143.1)
		(size 0.45)
		(drill 0.2)
		(layers "F.Cu" "B.Cu")
		(net 1)
	)
	(via
		(at 150.75 155.1)
		(size 0.45)
		(drill 0.2)
		(layers "F.Cu" "B.Cu")
		(net 1)
	)
	(via
		(at 228.1 164.6005)
		(size 0.45)
		(drill 0.2)
		(layers "F.Cu" "B.Cu")
		(net 1)
	)
	(via
		(at 189.5 135.5)
		(size 0.45)
		(drill 0.2)
		(layers "F.Cu" "B.Cu")
		(net 1)
	)
	(via
		(at 163.270001 81.870001)
		(size 0.45)
		(drill 0.2)
		(layers "F.Cu" "B.Cu")
		(net 1)
	)
	(via
		(at 191.725 104.9)
		(size 0.45)
		(drill 0.2)
		(layers "F.Cu" "B.Cu")
		(net 1)
	)
	(via
		(at 160.730001 104.730001)
		(size 0.45)
		(drill 0.2)
		(layers "F.Cu" "B.Cu")
		(net 1)
	)
	(via
		(at 261.25 101.3)
		(size 0.45)
		(drill 0.2)
		(layers "F.Cu" "B.Cu")
		(net 1)
	)
	(via
		(at 258.4 91.485)
		(size 0.45)
		(drill 0.2)
		(layers "F.Cu" "B.Cu")
		(net 1)
	)
	(via
		(at 162.000001 114.890001)
		(size 0.45)
		(drill 0.2)
		(layers "F.Cu" "B.Cu")
		(net 1)
	)
	(via
		(at 254.5 140.1)
		(size 0.45)
		(drill 0.2)
		(layers "F.Cu" "B.Cu")
		(net 1)
	)
	(via
		(at 159.460001 107.270001)
		(size 0.45)
		(drill 0.2)
		(layers "F.Cu" "B.Cu")
		(net 1)
	)
	(via
		(at 206 137)
		(size 0.45)
		(drill 0.2)
		(layers "F.Cu" "B.Cu")
		(net 1)
	)
	(via
		(at 170.53 189.3)
		(size 0.45)
		(drill 0.2)
		(layers "F.Cu" "B.Cu")
		(free yes)
		(net 1)
	)
	(via
		(at 165.810001 104.730001)
		(size 0.45)
		(drill 0.2)
		(layers "F.Cu" "B.Cu")
		(net 1)
	)
	(via
		(at 200 140)
		(size 0.45)
		(drill 0.2)
		(layers "F.Cu" "B.Cu")
		(net 1)
	)
	(via
		(at 191.525 183.274999)
		(size 0.45)
		(drill 0.2)
		(layers "F.Cu" "B.Cu")
		(net 1)
	)
	(via
		(at 176.1 170.8375)
		(size 0.45)
		(drill 0.2)
		(layers "F.Cu" "B.Cu")
		(net 1)
	)
	(via
		(at 220.64 70.77)
		(size 0.45)
		(drill 0.2)
		(layers "F.Cu" "B.Cu")
		(net 1)
	)
	(via
		(at 194.4 160.9)
		(size 0.45)
		(drill 0.2)
		(layers "F.Cu" "B.Cu")
		(free yes)
		(net 1)
	)
	(via
		(at 174.5 172.9625)
		(size 0.45)
		(drill 0.2)
		(layers "F.Cu" "B.Cu")
		(net 1)
	)
	(via
		(at 239.25 145.075)
		(size 0.45)
		(drill 0.2)
		(layers "F.Cu" "B.Cu")
		(net 1)
	)
	(via
		(at 206.230739 93.345017)
		(size 0.45)
		(drill 0.2)
		(layers "F.Cu" "B.Cu")
		(free yes)
		(net 1)
	)
	(via
		(at 164.325 149)
		(size 0.45)
		(drill 0.2)
		(layers "F.Cu" "B.Cu")
		(net 1)
	)
	(via
		(at 168.350001 112.350001)
		(size 0.45)
		(drill 0.2)
		(layers "F.Cu" "B.Cu")
		(net 1)
	)
	(via
		(at 159.460001 94.570001)
		(size 0.45)
		(drill 0.2)
		(layers "F.Cu" "B.Cu")
		(net 1)
	)
	(via
		(at 261.535 139.935)
		(size 0.45)
		(drill 0.2)
		(layers "F.Cu" "B.Cu")
		(net 1)
	)
	(via
		(at 169.25 168)
		(size 0.45)
		(drill 0.2)
		(layers "F.Cu" "B.Cu")
		(net 1)
	)
	(via
		(at 197.25 157.45)
		(size 0.45)
		(drill 0.2)
		(layers "F.Cu" "B.Cu")
		(free yes)
		(net 1)
	)
	(via
		(at 172.2 168.6)
		(size 0.45)
		(drill 0.2)
		(layers "F.Cu" "B.Cu")
		(net 1)
	)
	(via
		(at 193.4 160.9)
		(size 0.45)
		(drill 0.2)
		(layers "F.Cu" "B.Cu")
		(free yes)
		(net 1)
	)
	(via
		(at 264.75 92.5)
		(size 0.45)
		(drill 0.2)
		(layers "F.Cu" "B.Cu")
		(net 1)
	)
	(via
		(at 167.080001 127.590001)
		(size 0.45)
		(drill 0.2)
		(layers "F.Cu" "B.Cu")
		(net 1)
	)
	(via
		(at 173.225 142.15)
		(size 0.45)
		(drill 0.2)
		(layers "F.Cu" "B.Cu")
		(net 1)
	)
	(via
		(at 167.080001 125.050001)
		(size 0.45)
		(drill 0.2)
		(layers "F.Cu" "B.Cu")
		(net 1)
	)
	(via
		(at 260.42 189.17)
		(size 0.45)
		(drill 0.2)
		(layers "F.Cu" "B.Cu")
		(net 1)
	)
	(via
		(at 210.25 170.88)
		(size 0.45)
		(drill 0.2)
		(layers "F.Cu" "B.Cu")
		(net 1)
	)
	(via
		(at 197 122)
		(size 0.45)
		(drill 0.2)
		(layers "F.Cu" "B.Cu")
		(net 1)
	)
	(via
		(at 195.212 103.0708)
		(size 0.45)
		(drill 0.2)
		(layers "F.Cu" "B.Cu")
		(net 1)
	)
	(via
		(at 157 147.8)
		(size 0.45)
		(drill 0.2)
		(layers "F.Cu" "B.Cu")
		(net 1)
	)
	(via
		(at 160.730001 130.130001)
		(size 0.45)
		(drill 0.2)
		(layers "F.Cu" "B.Cu")
		(net 1)
	)
	(via
		(at 223.6 153.2)
		(size 0.45)
		(drill 0.2)
		(layers "F.Cu" "B.Cu")
		(free yes)
		(net 1)
	)
	(via
		(at 180 168.6)
		(size 0.45)
		(drill 0.2)
		(layers "F.Cu" "B.Cu")
		(net 1)
	)
	(via
		(at 211.125 158.75)
		(size 0.45)
		(drill 0.2)
		(layers "F.Cu" "B.Cu")
		(net 1)
	)
	(via
		(at 150.73 95.67)
		(size 0.45)
		(drill 0.2)
		(layers "F.Cu" "B.Cu")
		(net 1)
	)
	(via
		(at 154.380001 94.570001)
		(size 0.45)
		(drill 0.2)
		(layers "F.Cu" "B.Cu")
		(net 1)
	)
	(via
		(at 196.57 109.67)
		(size 0.45)
		(drill 0.2)
		(layers "F.Cu" "B.Cu")
		(net 1)
	)
	(via
		(at 167.080001 94.570001)
		(size 0.45)
		(drill 0.2)
		(layers "F.Cu" "B.Cu")
		(net 1)
	)
	(via
		(at 198 129)
		(size 0.45)
		(drill 0.2)
		(layers "F.Cu" "B.Cu")
		(net 1)
	)
	(via
		(at 150.67 130.59)
		(size 0.45)
		(drill 0.2)
		(layers "F.Cu" "B.Cu")
		(net 1)
	)
	(via
		(at 155.6 149)
		(size 0.45)
		(drill 0.2)
		(layers "F.Cu" "B.Cu")
		(net 1)
	)
	(via
		(at 176.8 164)
		(size 0.45)
		(drill 0.2)
		(layers "F.Cu" "B.Cu")
		(net 1)
	)
	(via
		(at 155.650001 114.890001)
		(size 0.45)
		(drill 0.2)
		(layers "F.Cu" "B.Cu")
		(net 1)
	)
	(via
		(at 166.31 166.66)
		(size 0.45)
		(drill 0.2)
		(layers "F.Cu" "B.Cu")
		(net 1)
	)
	(via
		(at 269.3 110.54)
		(size 0.45)
		(drill 0.2)
		(layers "F.Cu" "B.Cu")
		(net 1)
	)
	(via
		(at 194.591252 91.55)
		(size 0.45)
		(drill 0.2)
		(layers "F.Cu" "B.Cu")
		(net 1)
	)
	(via
		(at 154.6 157.7)
		(size 0.45)
		(drill 0.2)
		(layers "F.Cu" "B.Cu")
		(free yes)
		(net 1)
	)
	(via
		(at 164.540001 84.410001)
		(size 0.45)
		(drill 0.2)
		(layers "F.Cu" "B.Cu")
		(net 1)
	)
	(via
		(at 175.8 166.5)
		(size 0.45)
		(drill 0.2)
		(layers "F.Cu" "B.Cu")
		(net 1)
	)
	(via
		(at 198.35 87.2)
		(size 0.45)
		(drill 0.2)
		(layers "F.Cu" "B.Cu")
		(net 1)
	)
	(via
		(at 255.3 98.9)
		(size 0.45)
		(drill 0.2)
		(layers "F.Cu" "B.Cu")
		(net 1)
	)
	(via
		(at 212 145)
		(size 0.45)
		(drill 0.2)
		(layers "F.Cu" "B.Cu")
		(net 1)
	)
	(via
		(at 201 121)
		(size 0.45)
		(drill 0.2)
		(layers "F.Cu" "B.Cu")
		(net 1)
	)
	(via
		(at 211 132)
		(size 0.45)
		(drill 0.2)
		(layers "F.Cu" "B.Cu")
		(net 1)
	)
	(via
		(at 239.6 138.075)
		(size 0.45)
		(drill 0.2)
		(layers "F.Cu" "B.Cu")
		(net 1)
	)
	(via
		(at 195.715 84.2875)
		(size 0.45)
		(drill 0.2)
		(layers "F.Cu" "B.Cu")
		(net 1)
	)
	(via
		(at 258.3 124.35)
		(size 0.45)
		(drill 0.2)
		(layers "F.Cu" "B.Cu")
		(net 1)
	)
	(via
		(at 255.1 107.7)
		(size 0.45)
		(drill 0.2)
		(layers "F.Cu" "B.Cu")
		(free yes)
		(net 1)
	)
	(via
		(at 165.810001 89.490001)
		(size 0.45)
		(drill 0.2)
		(layers "F.Cu" "B.Cu")
		(net 1)
	)
	(via
		(at 155.8 153.8)
		(size 0.45)
		(drill 0.2)
		(layers "F.Cu" "B.Cu")
		(free yes)
		(net 1)
	)
	(via
		(at 154.1 140.45)
		(size 0.45)
		(drill 0.2)
		(layers "F.Cu" "B.Cu")
		(net 1)
	)
	(via
		(at 169.599998 148.400004)
		(size 0.45)
		(drill 0.2)
		(layers "F.Cu" "B.Cu")
		(net 1)
	)
	(via
		(at 256.4 139.9)
		(size 0.45)
		(drill 0.2)
		(layers "F.Cu" "B.Cu")
		(net 1)
	)
	(via
		(at 190.5 159.5)
		(size 0.45)
		(drill 0.2)
		(layers "F.Cu" "B.Cu")
		(free yes)
		(net 1)
	)
	(via
		(at 262.8 142.8)
		(size 0.45)
		(drill 0.2)
		(layers "F.Cu" "B.Cu")
		(net 1)
	)
	(via
		(at 164.15 183.65)
		(size 0.45)
		(drill 0.2)
		(layers "F.Cu" "B.Cu")
		(net 1)
	)
	(via
		(at 215.59 189.25)
		(size 0.45)
		(drill 0.2)
		(layers "F.Cu" "B.Cu")
		(net 1)
	)
	(via
		(at 159.1625 172)
		(size 0.45)
		(drill 0.2)
		(layers "F.Cu" "B.Cu")
		(net 1)
	)
	(via
		(at 258.4 93.885)
		(size 0.45)
		(drill 0.2)
		(layers "F.Cu" "B.Cu")
		(net 1)
	)
	(via
		(at 192.5 120.5)
		(size 0.45)
		(drill 0.2)
		(layers "F.Cu" "B.Cu")
		(net 1)
	)
	(via
		(at 201.65 87.2)
		(size 0.45)
		(drill 0.2)
		(layers "F.Cu" "B.Cu")
		(net 1)
	)
	(via
		(at 160.730001 86.950001)
		(size 0.45)
		(drill 0.2)
		(layers "F.Cu" "B.Cu")
		(net 1)
	)
	(via
		(at 150.84 115.58)
		(size 0.45)
		(drill 0.2)
		(layers "F.Cu" "B.Cu")
		(net 1)
	)
	(via
		(at 226.2 146.5)
		(size 0.45)
		(drill 0.2)
		(layers "F.Cu" "B.Cu")
		(net 1)
	)
	(via
		(at 203 138)
		(size 0.45)
		(drill 0.2)
		(layers "F.Cu" "B.Cu")
		(net 1)
	)
	(via
		(at 226.5 161.49)
		(size 0.45)
		(drill 0.2)
		(layers "F.Cu" "B.Cu")
		(net 1)
	)
	(via
		(at 160.2125 172)
		(size 0.45)
		(drill 0.2)
		(layers "F.Cu" "B.Cu")
		(net 1)
	)
	(via
		(at 164.540001 92.030001)
		(size 0.45)
		(drill 0.2)
		(layers "F.Cu" "B.Cu")
		(net 1)
	)
	(via
		(at 210.6 189.36)
		(size 0.45)
		(drill 0.2)
		(layers "F.Cu" "B.Cu")
		(net 1)
	)
	(via
		(at 150.67 85.59)
		(size 0.45)
		(drill 0.2)
		(layers "F.Cu" "B.Cu")
		(net 1)
	)
	(via
		(at 205.95 103.7)
		(size 0.45)
		(drill 0.2)
		(layers "F.Cu" "B.Cu")
		(net 1)
	)
	(via
		(at 188.25 159.25)
		(size 0.45)
		(drill 0.2)
		(layers "F.Cu" "B.Cu")
		(free yes)
		(net 1)
	)
	(via
		(at 186.500001 135.500001)
		(size 0.45)
		(drill 0.2)
		(layers "F.Cu" "B.Cu")
		(net 1)
	)
	(via
		(at 200.316752 101.9)
		(size 0.45)
		(drill 0.2)
		(layers "F.Cu" "B.Cu")
		(net 1)
	)
	(via
		(at 202 150.5)
		(size 0.45)
		(drill 0.2)
		(layers "F.Cu" "B.Cu")
		(net 1)
	)
	(via
		(at 196.525 166.8)
		(size 0.45)
		(drill 0.2)
		(layers "F.Cu" "B.Cu")
		(net 1)
	)
	(via
		(at 213 127)
		(size 0.45)
		(drill 0.2)
		(layers "F.Cu" "B.Cu")
		(net 1)
	)
	(via
		(at 187.43 187.5)
		(size 0.45)
		(drill 0.2)
		(layers "F.Cu" "B.Cu")
		(net 1)
	)
	(via
		(at 232.4 95.8)
		(size 0.45)
		(drill 0.2)
		(layers "F.Cu" "B.Cu")
		(net 1)
	)
	(via
		(at 209 115)
		(size 0.45)
		(drill 0.2)
		(layers "F.Cu" "B.Cu")
		(net 1)
	)
	(via
		(at 169.25 163.98)
		(size 0.45)
		(drill 0.2)
		(layers "F.Cu" "B.Cu")
		(net 1)
	)
	(via
		(at 239.6 137.325)
		(size 0.45)
		(drill 0.2)
		(layers "F.Cu" "B.Cu")
		(net 1)
	)
	(via
		(at 210 139)
		(size 0.45)
		(drill 0.2)
		(layers "F.Cu" "B.Cu")
		(net 1)
	)
	(via
		(at 158.1125 170.825)
		(size 0.45)
		(drill 0.2)
		(layers "F.Cu" "B.Cu")
		(net 1)
	)
	(via
		(at 185.4 94.4)
		(size 0.45)
		(drill 0.2)
		(layers "F.Cu" "B.Cu")
		(net 1)
	)
	(via
		(at 223.55 160.7)
		(size 0.45)
		(drill 0.2)
		(layers "F.Cu" "B.Cu")
		(net 1)
	)
	(via
		(at 156.920001 86.950001)
		(size 0.45)
		(drill 0.2)
		(layers "F.Cu" "B.Cu")
		(net 1)
	)
	(via
		(at 189.925 90.6)
		(size 0.45)
		(drill 0.2)
		(layers "F.Cu" "B.Cu")
		(net 1)
	)
	(via
		(at 169.620001 81.870001)
		(size 0.45)
		(drill 0.2)
		(layers "F.Cu" "B.Cu")
		(net 1)
	)
	(via
		(at 238.05 132.7)
		(size 0.45)
		(drill 0.2)
		(layers "F.Cu" "B.Cu")
		(net 1)
	)
	(via
		(at 155.75 177.75)
		(size 0.45)
		(drill 0.2)
		(layers "F.Cu" "B.Cu")
		(free yes)
		(net 1)
	)
	(via
		(at 171.599999 141.834316)
		(size 0.45)
		(drill 0.2)
		(layers "F.Cu" "B.Cu")
		(net 1)
	)
	(via
		(at 194 130)
		(size 0.45)
		(drill 0.2)
		(layers "F.Cu" "B.Cu")
		(net 1)
	)
	(via
		(at 197 129)
		(size 0.45)
		(drill 0.2)
		(layers "F.Cu" "B.Cu")
		(net 1)
	)
	(via
		(at 166.31 163.98)
		(size 0.45)
		(drill 0.2)
		(layers "F.Cu" "B.Cu")
		(net 1)
	)
	(via
		(at 258.175 167.285)
		(size 0.45)
		(drill 0.2)
		(layers "F.Cu" "B.Cu")
		(net 1)
	)
	(via
		(at 172.2 166.8)
		(size 0.45)
		(drill 0.2)
		(layers "F.Cu" "B.Cu")
		(net 1)
	)
	(via
		(at 269.33 184.22)
		(size 0.45)
		(drill 0.2)
		(layers "F.Cu" "B.Cu")
		(net 1)
	)
	(via
		(at 214.875 155.175)
		(size 0.45)
		(drill 0.2)
		(layers "F.Cu" "B.Cu")
		(net 1)
	)
	(via
		(at 159.69 171.42)
		(size 0.45)
		(drill 0.2)
		(layers "F.Cu" "B.Cu")
		(net 1)
	)
	(via
		(at 172.050001 119.374399)
		(size 0.45)
		(drill 0.2)
		(layers "F.Cu" "B.Cu")
		(net 1)
	)
	(via
		(at 167.080001 97.110001)
		(size 0.45)
		(drill 0.2)
		(layers "F.Cu" "B.Cu")
		(net 1)
	)
	(via
		(at 150.67 105.59)
		(size 0.45)
		(drill 0.2)
		(layers "F.Cu" "B.Cu")
		(net 1)
	)
	(via
		(at 226.5 159.8)
		(size 0.45)
		(drill 0.2)
		(layers "F.Cu" "B.Cu")
		(net 1)
	)
	(via
		(at 154.7 155.7)
		(size 0.45)
		(drill 0.2)
		(layers "F.Cu" "B.Cu")
		(free yes)
		(net 1)
	)
	(via
		(at 248.25 118.925)
		(size 0.45)
		(drill 0.2)
		(layers "F.Cu" "B.Cu")
		(net 1)
	)
	(via
		(at 154.380001 119.970001)
		(size 0.45)
		(drill 0.2)
		(layers "F.Cu" "B.Cu")
		(net 1)
	)
	(via
		(at 174.76 188.64)
		(size 0.45)
		(drill 0.2)
		(layers "F.Cu" "B.Cu")
		(net 1)
	)
	(via
		(at 154.2 139.2)
		(size 0.45)
		(drill 0.2)
		(layers "F.Cu" "B.Cu")
		(net 1)
	)
	(via
		(at 168.125 151.7)
		(size 0.45)
		(drill 0.2)
		(layers "F.Cu" "B.Cu")
		(net 1)
	)
	(via
		(at 155.2 168.6)
		(size 0.45)
		(drill 0.2)
		(layers "F.Cu" "B.Cu")
		(free yes)
		(net 1)
	)
	(via
		(at 254.7 71.05)
		(size 0.45)
		(drill 0.2)
		(layers "F.Cu" "B.Cu")
		(net 1)
	)
	(via
		(at 155.650001 97.110001)
		(size 0.45)
		(drill 0.2)
		(layers "F.Cu" "B.Cu")
		(net 1)
	)
	(via
		(at 168.350001 117.430001)
		(size 0.45)
		(drill 0.2)
		(layers "F.Cu" "B.Cu")
		(net 1)
	)
	(via
		(at 196.05 109.24)
		(size 0.45)
		(drill 0.2)
		(layers "F.Cu" "B.Cu")
		(net 1)
	)
	(via
		(at 198 136)
		(size 0.45)
		(drill 0.2)
		(layers "F.Cu" "B.Cu")
		(net 1)
	)
	(via
		(at 172.25 178)
		(size 0.45)
		(drill 0.2)
		(layers "F.Cu" "B.Cu")
		(free yes)
		(net 1)
	)
	(via
		(at 205 123)
		(size 0.45)
		(drill 0.2)
		(layers "F.Cu" "B.Cu")
		(net 1)
	)
	(via
		(at 190.5 123.5)
		(size 0.45)
		(drill 0.2)
		(layers "F.Cu" "B.Cu")
		(net 1)
	)
	(via
		(at 158.7 154.7)
		(size 0.45)
		(drill 0.2)
		(layers "F.Cu" "B.Cu")
		(free yes)
		(net 1)
	)
	(via
		(at 188.500001 124.500001)
		(size 0.45)
		(drill 0.2)
		(layers "F.Cu" "B.Cu")
		(net 1)
	)
	(via
		(at 208.679 80.482)
		(size 0.45)
		(drill 0.2)
		(layers "F.Cu" "B.Cu")
		(net 1)
	)
	(via
		(at 195.6 189.36)
		(size 0.45)
		(drill 0.2)
		(layers "F.Cu" "B.Cu")
		(net 1)
	)
	(via
		(at 204.57 102.71)
		(size 0.45)
		(drill 0.2)
		(layers "F.Cu" "B.Cu")
		(net 1)
	)
	(via
		(at 168.350001 89.490001)
		(size 0.45)
		(drill 0.2)
		(layers "F.Cu" "B.Cu")
		(net 1)
	)
	(via
		(at 206.205577 95.848218)
		(size 0.45)
		(drill 0.2)
		(layers "F.Cu" "B.Cu")
		(free yes)
		(net 1)
	)
	(via
		(at 187.25 159.25)
		(size 0.45)
		(drill 0.2)
		(layers "F.Cu" "B.Cu")
		(free yes)
		(net 1)
	)
	(via
		(at 269.37 130.57)
		(size 0.45)
		(drill 0.2)
		(layers "F.Cu" "B.Cu")
		(net 1)
	)
	(via
		(at 169.620001 114.890001)
		(size 0.45)
		(drill 0.2)
		(layers "F.Cu" "B.Cu")
		(net 1)
	)
	(via
		(at 165.810001 109.810001)
		(size 0.45)
		(drill 0.2)
		(layers "F.Cu" "B.Cu")
		(net 1)
	)
	(via
		(at 239.3 131.175)
		(size 0.45)
		(drill 0.2)
		(layers "F.Cu" "B.Cu")
		(net 1)
	)
	(via
		(at 195 137)
		(size 0.45)
		(drill 0.2)
		(layers "F.Cu" "B.Cu")
		(net 1)
	)
	(via
		(at 198 150.4)
		(size 0.45)
		(drill 0.2)
		(layers "F.Cu" "B.Cu")
		(net 1)
	)
	(via
		(at 168.350001 125.050001)
		(size 0.45)
		(drill 0.2)
		(layers "F.Cu" "B.Cu")
		(net 1)
	)
	(via
		(at 171.225 115.375)
		(size 0.45)
		(drill 0.2)
		(layers "F.Cu" "B.Cu")
		(net 1)
	)
	(via
		(at 150.67 110.59)
		(size 0.45)
		(drill 0.2)
		(layers "F.Cu" "B.Cu")
		(net 1)
	)
	(via
		(at 177.475001 84.950001)
		(size 0.45)
		(drill 0.2)
		(layers "F.Cu" "B.Cu")
		(net 1)
	)
	(via
		(at 154.380001 107.270001)
		(size 0.45)
		(drill 0.2)
		(layers "F.Cu" "B.Cu")
		(net 1)
	)
	(via
		(at 208 133)
		(size 0.45)
		(drill 0.2)
		(layers "F.Cu" "B.Cu")
		(net 1)
	)
	(via
		(at 215.95 160.7)
		(size 0.45)
		(drill 0.2)
		(layers "F.Cu" "B.Cu")
		(net 1)
	)
	(via
		(at 230.6 189.36)
		(size 0.45)
		(drill 0.2)
		(layers "F.Cu" "B.Cu")
		(net 1)
	)
	(via
		(at 213.19 173.56)
		(size 0.45)
		(drill 0.2)
		(layers "F.Cu" "B.Cu")
		(net 1)
	)
	(via
		(at 185.500001 127.500001)
		(size 0.45)
		(drill 0.2)
		(layers "F.Cu" "B.Cu")
		(net 1)
	)
	(via
		(at 195.987196 164.436005)
		(size 0.45)
		(drill 0.2)
		(layers "F.Cu" "B.Cu")
		(net 1)
	)
	(via
		(at 162.000001 86.950001)
		(size 0.45)
		(drill 0.2)
		(layers "F.Cu" "B.Cu")
		(net 1)
	)
	(via
		(at 223.7 154.4)
		(size 0.45)
		(drill 0.2)
		(layers "F.Cu" "B.Cu")
		(net 1)
	)
	(via
		(at 183 72)
		(size 0.45)
		(drill 0.2)
		(layers "F.Cu" "B.Cu")
		(net 1)
	)
	(via
		(at 159.460001 114.890001)
		(size 0.45)
		(drill 0.2)
		(layers "F.Cu" "B.Cu")
		(net 1)
	)
	(via
		(at 196 140)
		(size 0.45)
		(drill 0.2)
		(layers "F.Cu" "B.Cu")
		(net 1)
	)
	(via
		(at 269.31 189.24)
		(size 0.45)
		(drill 0.2)
		(layers "F.Cu" "B.Cu")
		(net 1)
	)
	(via
		(at 165.810001 125.050001)
		(size 0.45)
		(drill 0.2)
		(layers "F.Cu" "B.Cu")
		(net 1)
	)
	(via
		(at 159.460001 125.050001)
		(size 0.45)
		(drill 0.2)
		(layers "F.Cu" "B.Cu")
		(net 1)
	)
	(via
		(at 222.386864 149.4745)
		(size 0.45)
		(drill 0.2)
		(layers "F.Cu" "B.Cu")
		(net 1)
	)
	(via
		(at 170.52 70.74)
		(size 0.45)
		(drill 0.2)
		(layers "F.Cu" "B.Cu")
		(net 1)
	)
	(via
		(at 192.44 101.59)
		(size 0.45)
		(drill 0.2)
		(layers "F.Cu" "B.Cu")
		(net 1)
	)
	(via
		(at 160.730001 94.570001)
		(size 0.45)
		(drill 0.2)
		(layers "F.Cu" "B.Cu")
		(net 1)
	)
	(via
		(at 153 154.6)
		(size 0.45)
		(drill 0.2)
		(layers "F.Cu" "B.Cu")
		(net 1)
	)
	(via
		(at 241.6 85.9)
		(size 0.45)
		(drill 0.2)
		(layers "F.Cu" "B.Cu")
		(net 1)
	)
	(via
		(at 194.9 167.1)
		(size 0.45)
		(drill 0.2)
		(layers "F.Cu" "B.Cu")
		(net 1)
	)
	(via
		(at 198 149.4)
		(size 0.45)
		(drill 0.2)
		(layers "F.Cu" "B.Cu")
		(net 1)
	)
	(via
		(at 160.730001 102.190001)
		(size 0.45)
		(drill 0.2)
		(layers "F.Cu" "B.Cu")
		(net 1)
	)
	(via
		(at 247.6 116.4)
		(size 0.45)
		(drill 0.2)
		(layers "F.Cu" "B.Cu")
		(net 1)
	)
	(via
		(at 252.6 108.2)
		(size 0.45)
		(drill 0.2)
		(layers "F.Cu" "B.Cu")
		(free yes)
		(net 1)
	)
	(via
		(at 201.101 72.083)
		(size 0.45)
		(drill 0.2)
		(layers "F.Cu" "B.Cu")
		(net 1)
	)
	(via
		(at 193 134)
		(size 0.45)
		(drill 0.2)
		(layers "F.Cu" "B.Cu")
		(net 1)
	)
	(via
		(at 154.380001 127.590001)
		(size 0.45)
		(drill 0.2)
		(layers "F.Cu" "B.Cu")
		(net 1)
	)
	(via
		(at 175.700001 132.275191)
		(size 0.45)
		(drill 0.2)
		(layers "F.Cu" "B.Cu")
		(net 1)
	)
	(via
		(at 169.620001 97.110001)
		(size 0.45)
		(drill 0.2)
		(layers "F.Cu" "B.Cu")
		(net 1)
	)
	(via
		(at 155.6 150.8)
		(size 0.45)
		(drill 0.2)
		(layers "F.Cu" "B.Cu")
		(net 1)
	)
	(via
		(at 158.190001 81.862689)
		(size 0.45)
		(drill 0.2)
		(layers "F.Cu" "B.Cu")
		(net 1)
	)
	(via
		(at 163.270001 104.730001)
		(size 0.45)
		(drill 0.2)
		(layers "F.Cu" "B.Cu")
		(net 1)
	)
	(via
		(at 190.5 129.5)
		(size 0.45)
		(drill 0.2)
		(layers "F.Cu" "B.Cu")
		(net 1)
	)
	(via
		(at 240.6 132.7)
		(size 0.45)
		(drill 0.2)
		(layers "F.Cu" "B.Cu")
		(net 1)
	)
	(via
		(at 165.810001 94.570001)
		(size 0.45)
		(drill 0.2)
		(layers "F.Cu" "B.Cu")
		(net 1)
	)
	(via
		(at 167.080001 86.950001)
		(size 0.45)
		(drill 0.2)
		(layers "F.Cu" "B.Cu")
		(net 1)
	)
	(via
		(at 195 72)
		(size 0.45)
		(drill 0.2)
		(layers "F.Cu" "B.Cu")
		(net 1)
	)
	(via
		(at 232.3 87.4)
		(size 0.45)
		(drill 0.2)
		(layers "F.Cu" "B.Cu")
		(net 1)
	)
	(via
		(at 172.595501 87.389501)
		(size 0.45)
		(drill 0.2)
		(layers "F.Cu" "B.Cu")
		(net 1)
	)
	(via
		(at 201 131)
		(size 0.45)
		(drill 0.2)
		(layers "F.Cu" "B.Cu")
		(net 1)
	)
	(via
		(at 268.1 134.65)
		(size 0.45)
		(drill 0.2)
		(layers "F.Cu" "B.Cu")
		(net 1)
	)
	(via
		(at 159.8 163.2)
		(size 0.45)
		(drill 0.2)
		(layers "F.Cu" "B.Cu")
		(net 1)
	)
	(via
		(at 171.175237 100.170736)
		(size 0.45)
		(drill 0.2)
		(layers "F.Cu" "B.Cu")
		(net 1)
	)
	(via
		(at 194.9 160.9)
		(size 0.45)
		(drill 0.2)
		(layers "F.Cu" "B.Cu")
		(free yes)
		(net 1)
	)
	(via
		(at 159.1625 169.6)
		(size 0.45)
		(drill 0.2)
		(layers "F.Cu" "B.Cu")
		(net 1)
	)
	(via
		(at 162.8 185.2)
		(size 0.45)
		(drill 0.2)
		(layers "F.Cu" "B.Cu")
		(net 1)
	)
	(via
		(at 186.500001 119.500001)
		(size 0.45)
		(drill 0.2)
		(layers "F.Cu" "B.Cu")
		(net 1)
	)
	(via
		(at 214.85 161.65)
		(size 0.45)
		(drill 0.2)
		(layers "F.Cu" "B.Cu")
		(net 1)
	)
	(via
		(at 187 143)
		(size 0.45)
		(drill 0.2)
		(layers "F.Cu" "B.Cu")
		(net 1)
	)
	(via
		(at 169.25 162.64)
		(size 0.45)
		(drill 0.2)
		(layers "F.Cu" "B.Cu")
		(net 1)
	)
	(via
		(at 215 134)
		(size 0.45)
		(drill 0.2)
		(layers "F.Cu" "B.Cu")
		(net 1)
	)
	(via
		(at 168.350001 114.890001)
		(size 0.45)
		(drill 0.2)
		(layers "F.Cu" "B.Cu")
		(net 1)
	)
	(via
		(at 163.3 138.3)
		(size 0.45)
		(drill 0.2)
		(layers "F.Cu" "B.Cu")
		(net 1)
	)
	(via
		(at 180 166.8)
		(size 0.45)
		(drill 0.2)
		(layers "F.Cu" "B.Cu")
		(net 1)
	)
	(via
		(at 190.5 135.5)
		(size 0.45)
		(drill 0.2)
		(layers "F.Cu" "B.Cu")
		(net 1)
	)
	(via
		(at 175.428711 84.285141)
		(size 0.45)
		(drill 0.2)
		(layers "F.Cu" "B.Cu")
		(net 1)
	)
	(via
		(at 158.190001 97.110001)
		(size 0.45)
		(drill 0.2)
		(layers "F.Cu" "B.Cu")
		(net 1)
	)
	(via
		(at 267 127.2)
		(size 0.45)
		(drill 0.2)
		(layers "F.Cu" "B.Cu")
		(net 1)
	)
	(via
		(at 166.31 165.32)
		(size 0.45)
		(drill 0.2)
		(layers "F.Cu" "B.Cu")
		(net 1)
	)
	(via
		(at 169.6 143.6)
		(size 0.45)
		(drill 0.2)
		(layers "F.Cu" "B.Cu")
		(net 1)
	)
	(via
		(at 208 122)
		(size 0.45)
		(drill 0.2)
		(layers "F.Cu" "B.Cu")
		(net 1)
	)
	(via
		(at 156.920001 99.650001)
		(size 0.45)
		(drill 0.2)
		(layers "F.Cu" "B.Cu")
		(net 1)
	)
	(via
		(at 218.7 139.225)
		(size 0.45)
		(drill 0.2)
		(layers "F.Cu" "B.Cu")
		(net 1)
	)
	(via
		(at 202 127)
		(size 0.45)
		(drill 0.2)
		(layers "F.Cu" "B.Cu")
		(net 1)
	)
	(via
		(at 165.52 70.74)
		(size 0.45)
		(drill 0.2)
		(layers "F.Cu" "B.Cu")
		(net 1)
	)
	(via
		(at 185.500001 125.500001)
		(size 0.45)
		(drill 0.2)
		(layers "F.Cu" "B.Cu")
		(net 1)
	)
	(via
		(at 202 148.3)
		(size 0.45)
		(drill 0.2)
		(layers "F.Cu" "B.Cu")
		(net 1)
	)
	(via
		(at 167.2 149.2)
		(size 0.45)
		(drill 0.2)
		(layers "F.Cu" "B.Cu")
		(net 1)
	)
	(via
		(at 177.450001 107.570001)
		(size 0.45)
		(drill 0.2)
		(layers "F.Cu" "B.Cu")
		(net 1)
	)
	(via
		(at 203 131)
		(size 0.45)
		(drill 0.2)
		(layers "F.Cu" "B.Cu")
		(net 1)
	)
	(via
		(at 187 163)
		(size 0.45)
		(drill 0.2)
		(layers "F.Cu" "B.Cu")
		(free yes)
		(net 1)
	)
	(via
		(at 195 134)
		(size 0.45)
		(drill 0.2)
		(layers "F.Cu" "B.Cu")
		(net 1)
	)
	(via
		(at 186.500001 127.500001)
		(size 0.45)
		(drill 0.2)
		(layers "F.Cu" "B.Cu")
		(net 1)
	)
	(via
		(at 174.77 183.54)
		(size 0.45)
		(drill 0.2)
		(layers "F.Cu" "B.Cu")
		(net 1)
	)
	(via
		(at 168.350001 86.950001)
		(size 0.45)
		(drill 0.2)
		(layers "F.Cu" "B.Cu")
		(net 1)
	)
	(via
		(at 258.4 89.085)
		(size 0.45)
		(drill 0.2)
		(layers "F.Cu" "B.Cu")
		(net 1)
	)
	(via
		(at 259.7 71.05)
		(size 0.45)
		(drill 0.2)
		(layers "F.Cu" "B.Cu")
		(net 1)
	)
	(via
		(at 188.500001 126.500001)
		(size 0.45)
		(drill 0.2)
		(layers "F.Cu" "B.Cu")
		(net 1)
	)
	(via
		(at 194.591252 97.85)
		(size 0.45)
		(drill 0.2)
		(layers "F.Cu" "B.Cu")
		(net 1)
	)
	(via
		(at 165.810001 122.510001)
		(size 0.45)
		(drill 0.2)
		(layers "F.Cu" "B.Cu")
		(net 1)
	)
	(via
		(at 155.650001 109.810001)
		(size 0.45)
		(drill 0.2)
		(layers "F.Cu" "B.Cu")
		(net 1)
	)
	(via
		(at 222.2 92.7)
		(size 0.45)
		(drill 0.2)
		(layers "F.Cu" "B.Cu")
		(net 1)
	)
	(via
		(at 167.080001 84.410001)
		(size 0.45)
		(drill 0.2)
		(layers "F.Cu" "B.Cu")
		(net 1)
	)
	(via
		(at 176.1 172.0125)
		(size 0.45)
		(drill 0.2)
		(layers "F.Cu" "B.Cu")
		(net 1)
	)
	(via
		(at 239.3 130.425)
		(size 0.45)
		(drill 0.2)
		(layers "F.Cu" "B.Cu")
		(net 1)
	)
	(via
		(at 171.85 120.725)
		(size 0.45)
		(drill 0.2)
		(layers "F.Cu" "B.Cu")
		(net 1)
	)
	(via
		(at 191 165)
		(size 0.45)
		(drill 0.2)
		(layers "F.Cu" "B.Cu")
		(free yes)
		(net 1)
	)
	(via
		(at 176.190001 107.580001)
		(size 0.45)
		(drill 0.2)
		(layers "F.Cu" "B.Cu")
		(net 1)
	)
	(via
		(at 258.7 71.05)
		(size 0.45)
		(drill 0.2)
		(layers "F.Cu" "B.Cu")
		(net 1)
	)
	(via
		(at 163 168.6)
		(size 0.45)
		(drill 0.2)
		(layers "F.Cu" "B.Cu")
		(net 1)
	)
	(via
		(at 164.540001 81.870001)
		(size 0.45)
		(drill 0.2)
		(layers "F.Cu" "B.Cu")
		(net 1)
	)
	(via
		(at 190.5 114)
		(size 0.45)
		(drill 0.2)
		(layers "F.Cu" "B.Cu")
		(net 1)
	)
	(via
		(at 177.18 73.62)
		(size 0.45)
		(drill 0.2)
		(layers "F.Cu" "B.Cu")
		(net 1)
	)
	(via
		(at 223.55 159.95)
		(size 0.45)
		(drill 0.2)
		(layers "F.Cu" "B.Cu")
		(net 1)
	)
	(via
		(at 268.85 92.4)
		(size 0.45)
		(drill 0.2)
		(layers "F.Cu" "B.Cu")
		(net 1)
	)
	(via
		(at 192.5 137.5)
		(size 0.45)
		(drill 0.2)
		(layers "F.Cu" "B.Cu")
		(net 1)
	)
	(via
		(at 155 158.1)
		(size 0.45)
		(drill 0.2)
		(layers "F.Cu" "B.Cu")
		(free yes)
		(net 1)
	)
	(via
		(at 188.500001 132.500001)
		(size 0.45)
		(drill 0.2)
		(layers "F.Cu" "B.Cu")
		(net 1)
	)
	(via
		(at 156.21 143.77)
		(size 0.45)
		(drill 0.2)
		(layers "F.Cu" "B.Cu")
		(net 1)
	)
	(via
		(at 150.66 180.64)
		(size 0.45)
		(drill 0.2)
		(layers "F.Cu" "B.Cu")
		(net 1)
	)
	(via
		(at 167.080001 109.810001)
		(size 0.45)
		(drill 0.2)
		(layers "F.Cu" "B.Cu")
		(net 1)
	)
	(via
		(at 216.13 172.22)
		(size 0.45)
		(drill 0.2)
		(layers "F.Cu" "B.Cu")
		(net 1)
	)
	(via
		(at 169.620001 102.190001)
		(size 0.45)
		(drill 0.2)
		(layers "F.Cu" "B.Cu")
		(net 1)
	)
	(via
		(at 190.6 189.36)
		(size 0.45)
		(drill 0.2)
		(layers "F.Cu" "B.Cu")
		(net 1)
	)
	(via
		(at 155.650001 99.650001)
		(size 0.45)
		(drill 0.2)
		(layers "F.Cu" "B.Cu")
		(net 1)
	)
	(via
		(at 169.620001 107.270001)
		(size 0.45)
		(drill 0.2)
		(layers "F.Cu" "B.Cu")
		(net 1)
	)
	(via
		(at 194 144)
		(size 0.45)
		(drill 0.2)
		(layers "F.Cu" "B.Cu")
		(net 1)
	)
	(via
		(at 161.768768 128.811232)
		(size 0.45)
		(drill 0.2)
		(layers "F.Cu" "B.Cu")
		(net 1)
	)
	(via
		(at 191.75 153.15)
		(size 0.45)
		(drill 0.2)
		(layers "F.Cu" "B.Cu")
		(net 1)
	)
	(via
		(at 207.600001 146.857)
		(size 0.45)
		(drill 0.2)
		(layers "F.Cu" "B.Cu")
		(net 1)
	)
	(via
		(at 177.75 174.8625)
		(size 0.45)
		(drill 0.2)
		(layers "F.Cu" "B.Cu")
		(net 1)
	)
	(via
		(at 211.667 79.408)
		(size 0.45)
		(drill 0.2)
		(layers "F.Cu" "B.Cu")
		(net 1)
	)
	(via
		(at 269.36 115.63)
		(size 0.45)
		(drill 0.2)
		(layers "F.Cu" "B.Cu")
		(net 1)
	)
	(via
		(at 268.9 83.175)
		(size 0.45)
		(drill 0.2)
		(layers "F.Cu" "B.Cu")
		(net 1)
	)
	(via
		(at 169.620001 127.590001)
		(size 0.45)
		(drill 0.2)
		(layers "F.Cu" "B.Cu")
		(net 1)
	)
	(via
		(at 260.7 71.05)
		(size 0.45)
		(drill 0.2)
		(layers "F.Cu" "B.Cu")
		(net 1)
	)
	(via
		(at 168 149.2)
		(size 0.45)
		(drill 0.2)
		(layers "F.Cu" "B.Cu")
		(net 1)
	)
	(via
		(at 258.474135 104.222827)
		(size 0.45)
		(drill 0.2)
		(layers "F.Cu" "B.Cu")
		(free yes)
		(net 1)
	)
	(via
		(at 194 157.5)
		(size 0.45)
		(drill 0.2)
		(layers "F.Cu" "B.Cu")
		(free yes)
		(net 1)
	)
	(via
		(at 202.101 71.283)
		(size 0.45)
		(drill 0.2)
		(layers "F.Cu" "B.Cu")
		(net 1)
	)
	(via
		(at 165.810001 119.970001)
		(size 0.45)
		(drill 0.2)
		(layers "F.Cu" "B.Cu")
		(net 1)
	)
	(via
		(at 169.620001 104.730001)
		(size 0.45)
		(drill 0.2)
		(layers "F.Cu" "B.Cu")
		(net 1)
	)
	(via
		(at 221.2 150)
		(size 0.45)
		(drill 0.2)
		(layers "F.Cu" "B.Cu")
		(net 1)
	)
	(via
		(at 160.05 166.5)
		(size 0.45)
		(drill 0.2)
		(layers "F.Cu" "B.Cu")
		(net 1)
	)
	(via
		(at 240.9 146.2)
		(size 0.45)
		(drill 0.2)
		(layers "F.Cu" "B.Cu")
		(net 1)
	)
	(via
		(at 215.61 70.7)
		(size 0.45)
		(drill 0.2)
		(layers "F.Cu" "B.Cu")
		(net 1)
	)
	(via
		(at 193.1 168.225)
		(size 0.45)
		(drill 0.2)
		(layers "F.Cu" "B.Cu")
		(net 1)
	)
	(via
		(at 236.4 116.525)
		(size 0.45)
		(drill 0.2)
		(layers "F.Cu" "B.Cu")
		(net 1)
	)
	(via
		(at 172 171.1)
		(size 0.45)
		(drill 0.2)
		(layers "F.Cu" "B.Cu")
		(net 1)
	)
	(via
		(at 169.25 161.3)
		(size 0.45)
		(drill 0.2)
		(layers "F.Cu" "B.Cu")
		(net 1)
	)
	(via
		(at 246.65 128.9)
		(size 0.45)
		(drill 0.2)
		(layers "F.Cu" "B.Cu")
		(net 1)
	)
	(via
		(at 220.6 189.36)
		(size 0.45)
		(drill 0.2)
		(layers "F.Cu" "B.Cu")
		(net 1)
	)
	(via
		(at 165.810001 86.950001)
		(size 0.45)
		(drill 0.2)
		(layers "F.Cu" "B.Cu")
		(net 1)
	)
	(via
		(at 228.9 164.6)
		(size 0.45)
		(drill 0.2)
		(layers "F.Cu" "B.Cu")
		(net 1)
	)
	(via
		(at 159.55 166.5)
		(size 0.45)
		(drill 0.2)
		(layers "F.Cu" "B.Cu")
		(net 1)
	)
	(via
		(at 226.075 122.65)
		(size 0.45)
		(drill 0.2)
		(layers "F.Cu" "B.Cu")
		(net 1)
	)
	(via
		(at 200 145)
		(size 0.45)
		(drill 0.2)
		(layers "F.Cu" "B.Cu")
		(net 1)
	)
	(via
		(at 258.4 128.5)
		(size 0.45)
		(drill 0.2)
		(layers "F.Cu" "B.Cu")
		(net 1)
	)
	(via
		(at 219.07 170.88)
		(size 0.45)
		(drill 0.2)
		(layers "F.Cu" "B.Cu")
		(net 1)
	)
	(via
		(at 150.67 160.59)
		(size 0.45)
		(drill 0.2)
		(layers "F.Cu" "B.Cu")
		(net 1)
	)
	(via
		(at 210 128)
		(size 0.45)
		(drill 0.2)
		(layers "F.Cu" "B.Cu")
		(net 1)
	)
	(via
		(at 207 119)
		(size 0.45)
		(drill 0.2)
		(layers "F.Cu" "B.Cu")
		(net 1)
	)
	(via
		(at 240.85 139.6)
		(size 0.45)
		(drill 0.2)
		(layers "F.Cu" "B.Cu")
		(net 1)
	)
	(via
		(at 199 146.62)
		(size 0.45)
		(drill 0.2)
		(layers "F.Cu" "B.Cu")
		(net 1)
	)
	(via
		(at 158.190001 117.430001)
		(size 0.45)
		(drill 0.2)
		(layers "F.Cu" "B.Cu")
		(net 1)
	)
	(via
		(at 195 129)
		(size 0.45)
		(drill 0.2)
		(layers "F.Cu" "B.Cu")
		(net 1)
	)
	(via
		(at 150.68 75.68)
		(size 0.45)
		(drill 0.2)
		(layers "F.Cu" "B.Cu")
		(net 1)
	)
	(via
		(at 254.545 138.3195)
		(size 0.45)
		(drill 0.2)
		(layers "F.Cu" "B.Cu")
		(net 1)
	)
	(via
		(at 186.503727 117.503727)
		(size 0.45)
		(drill 0.2)
		(layers "F.Cu" "B.Cu")
		(net 1)
	)
	(via
		(at 252.7 71.05)
		(size 0.45)
		(drill 0.2)
		(layers "F.Cu" "B.Cu")
		(net 1)
	)
	(via
		(at 155.650001 102.190001)
		(size 0.45)
		(drill 0.2)
		(layers "F.Cu" "B.Cu")
		(net 1)
	)
	(via
		(at 177 166.5)
		(size 0.45)
		(drill 0.2)
		(layers "F.Cu" "B.Cu")
		(net 1)
	)
	(via
		(at 199.3 102.5)
		(size 0.45)
		(drill 0.2)
		(layers "F.Cu" "B.Cu")
		(net 1)
	)
	(via
		(at 154.380001 109.810001)
		(size 0.45)
		(drill 0.2)
		(layers "F.Cu" "B.Cu")
		(net 1)
	)
	(via
		(at 168.350001 119.970001)
		(size 0.45)
		(drill 0.2)
		(layers "F.Cu" "B.Cu")
		(net 1)
	)
	(via
		(at 165.810001 107.270001)
		(size 0.45)
		(drill 0.2)
		(layers "F.Cu" "B.Cu")
		(net 1)
	)
	(via
		(at 162.000001 81.870001)
		(size 0.45)
		(drill 0.2)
		(layers "F.Cu" "B.Cu")
		(net 1)
	)
	(via
		(at 203 133)
		(size 0.45)
		(drill 0.2)
		(layers "F.Cu" "B.Cu")
		(net 1)
	)
	(via
		(at 154.380001 99.650001)
		(size 0.45)
		(drill 0.2)
		(layers "F.Cu" "B.Cu")
		(net 1)
	)
	(via
		(at 156.920001 119.970001)
		(size 0.45)
		(drill 0.2)
		(layers "F.Cu" "B.Cu")
		(net 1)
	)
	(via
		(at 191.5 134.5)
		(size 0.45)
		(drill 0.2)
		(layers "F.Cu" "B.Cu")
		(net 1)
	)
	(via
		(at 269.35 140.59)
		(size 0.45)
		(drill 0.2)
		(layers "F.Cu" "B.Cu")
		(net 1)
	)
	(via
		(at 162.000001 125.050001)
		(size 0.45)
		(drill 0.2)
		(layers "F.Cu" "B.Cu")
		(net 1)
	)
	(via
		(at 156.920001 94.570001)
		(size 0.45)
		(drill 0.2)
		(layers "F.Cu" "B.Cu")
		(net 1)
	)
	(via
		(at 243.05 137.2)
		(size 0.45)
		(drill 0.2)
		(layers "F.Cu" "B.Cu")
		(net 1)
	)
	(via
		(at 158.190001 119.970001)
		(size 0.45)
		(drill 0.2)
		(layers "F.Cu" "B.Cu")
		(net 1)
	)
	(via
		(at 201 128)
		(size 0.45)
		(drill 0.2)
		(layers "F.Cu" "B.Cu")
		(net 1)
	)
	(via
		(at 203 128)
		(size 0.45)
		(drill 0.2)
		(layers "F.Cu" "B.Cu")
		(net 1)
	)
	(via
		(at 206 130)
		(size 0.45)
		(drill 0.2)
		(layers "F.Cu" "B.Cu")
		(net 1)
	)
	(via
		(at 158.85 166.5)
		(size 0.45)
		(drill 0.2)
		(layers "F.Cu" "B.Cu")
		(net 1)
	)
	(via
		(at 169.620001 94.570001)
		(size 0.45)
		(drill 0.2)
		(layers "F.Cu" "B.Cu")
		(net 1)
	)
	(via
		(at 185.500001 129.500001)
		(size 0.45)
		(drill 0.2)
		(layers "F.Cu" "B.Cu")
		(net 1)
	)
	(via
		(at 226 155.2)
		(size 0.45)
		(drill 0.2)
		(layers "F.Cu" "B.Cu")
		(net 1)
	)
	(via
		(at 244.625 119.375)
		(size 0.45)
		(drill 0.2)
		(layers "F.Cu" "B.Cu")
		(net 1)
	)
	(via
		(at 162.000001 107.270001)
		(size 0.45)
		(drill 0.2)
		(layers "F.Cu" "B.Cu")
		(net 1)
	)
	(via
		(at 164.540001 107.270001)
		(size 0.45)
		(drill 0.2)
		(layers "F.Cu" "B.Cu")
		(net 1)
	)
	(via
		(at 201 133)
		(size 0.45)
		(drill 0.2)
		(layers "F.Cu" "B.Cu")
		(net 1)
	)
	(via
		(at 215 144)
		(size 0.45)
		(drill 0.2)
		(layers "F.Cu" "B.Cu")
		(net 1)
	)
	(via
		(at 150.8 189.2)
		(size 0.45)
		(drill 0.2)
		(layers "F.Cu" "B.Cu")
		(net 1)
	)
	(via
		(at 160.2125 170.825)
		(size 0.45)
		(drill 0.2)
		(layers "F.Cu" "B.Cu")
		(net 1)
	)
	(via
		(at 154.380001 122.510001)
		(size 0.45)
		(drill 0.2)
		(layers "F.Cu" "B.Cu")
		(net 1)
	)
	(via
		(at 233.1 126.025)
		(size 0.45)
		(drill 0.2)
		(layers "F.Cu" "B.Cu")
		(net 1)
	)
	(via
		(at 195 127)
		(size 0.45)
		(drill 0.2)
		(layers "F.Cu" "B.Cu")
		(net 1)
	)
	(via
		(at 269.32 165.59)
		(size 0.45)
		(drill 0.2)
		(layers "F.Cu" "B.Cu")
		(net 1)
	)
	(via
		(at 267.1 124.7)
		(size 0.45)
		(drill 0.2)
		(layers "F.Cu" "B.Cu")
		(net 1)
	)
	(via
		(at 167.080001 89.490001)
		(size 0.45)
		(drill 0.2)
		(layers "F.Cu" "B.Cu")
		(net 1)
	)
	(via
		(at 155.75 178.75)
		(size 0.45)
		(drill 0.2)
		(layers "F.Cu" "B.Cu")
		(free yes)
		(net 1)
	)
	(via
		(at 185.500001 133.500001)
		(size 0.45)
		(drill 0.2)
		(layers "F.Cu" "B.Cu")
		(net 1)
	)
	(via
		(at 200 142.975001)
		(size 0.45)
		(drill 0.2)
		(layers "F.Cu" "B.Cu")
		(net 1)
	)
	(via
		(at 225.6 189.36)
		(size 0.45)
		(drill 0.2)
		(layers "F.Cu" "B.Cu")
		(net 1)
	)
	(via
		(at 163 168)
		(size 0.45)
		(drill 0.2)
		(layers "F.Cu" "B.Cu")
		(net 1)
	)
	(via
		(at 159.1625 170.825)
		(size 0.45)
		(drill 0.2)
		(layers "F.Cu" "B.Cu")
		(net 1)
	)
	(via
		(at 165.810001 112.350001)
		(size 0.45)
		(drill 0.2)
		(layers "F.Cu" "B.Cu")
		(net 1)
	)
	(via
		(at 164.540001 97.110001)
		(size 0.45)
		(drill 0.2)
		(layers "F.Cu" "B.Cu")
		(net 1)
	)
	(via
		(at 192.6 86.6)
		(size 0.45)
		(drill 0.2)
		(layers "F.Cu" "B.Cu")
		(net 1)
	)
	(via
		(at 204 141)
		(size 0.45)
		(drill 0.2)
		(layers "F.Cu" "B.Cu")
		(net 1)
	)
	(via
		(at 155.2 167.4)
		(size 0.45)
		(drill 0.2)
		(layers "F.Cu" "B.Cu")
		(net 1)
	)
	(via
		(at 156.920001 125.050001)
		(size 0.45)
		(drill 0.2)
		(layers "F.Cu" "B.Cu")
		(net 1)
	)
	(via
		(at 188.500001 122.500001)
		(size 0.45)
		(drill 0.2)
		(layers "F.Cu" "B.Cu")
		(net 1)
	)
	(via
		(at 197.09 93.1)
		(size 0.45)
		(drill 0.2)
		(layers "F.Cu" "B.Cu")
		(net 1)
	)
	(via
		(at 160.6 143.1)
		(size 0.45)
		(drill 0.2)
		(layers "F.Cu" "B.Cu")
		(net 1)
	)
	(via
		(at 256.2 105)
		(size 0.45)
		(drill 0.2)
		(layers "F.Cu" "B.Cu")
		(free yes)
		(net 1)
	)
	(via
		(at 176.64 171.44)
		(size 0.45)
		(drill 0.2)
		(layers "F.Cu" "B.Cu")
		(net 1)
	)
	(via
		(at 199 118)
		(size 0.45)
		(drill 0.2)
		(layers "F.Cu" "B.Cu")
		(net 1)
	)
	(via
		(at 219.685 139.975)
		(size 0.45)
		(drill 0.2)
		(layers "F.Cu" "B.Cu")
		(net 1)
	)
	(via
		(at 175.6 175)
		(size 0.45)
		(drill 0.2)
		(layers "F.Cu" "B.Cu")
		(net 1)
	)
	(via
		(at 165.810001 92.030001)
		(size 0.45)
		(drill 0.2)
		(layers "F.Cu" "B.Cu")
		(net 1)
	)
	(via
		(at 178.901092 86.836091)
		(size 0.45)
		(drill 0.2)
		(layers "F.Cu" "B.Cu")
		(net 1)
	)
	(via
		(at 185.500001 135.500001)
		(size 0.45)
		(drill 0.2)
		(layers "F.Cu" "B.Cu")
		(net 1)
	)
	(via
		(at 201 142)
		(size 0.45)
		(drill 0.2)
		(layers "F.Cu" "B.Cu")
		(net 1)
	)
	(via
		(at 200 125)
		(size 0.45)
		(drill 0.2)
		(layers "F.Cu" "B.Cu")
		(net 1)
	)
	(via
		(at 269.24 155.61)
		(size 0.45)
		(drill 0.2)
		(layers "F.Cu" "B.Cu")
		(net 1)
	)
	(via
		(at 184.030001 127.500001)
		(size 0.45)
		(drill 0.2)
		(layers "F.Cu" "B.Cu")
		(net 1)
	)
	(via
		(at 173.75 178.5)
		(size 0.45)
		(drill 0.2)
		(layers "F.Cu" "B.Cu")
		(free yes)
		(net 1)
	)
	(via
		(at 164.540001 104.730001)
		(size 0.45)
		(drill 0.2)
		(layers "F.Cu" "B.Cu")
		(net 1)
	)
	(via
		(at 189 139)
		(size 0.45)
		(drill 0.2)
		(layers "F.Cu" "B.Cu")
		(net 1)
	)
	(via
		(at 213.19 172.22)
		(size 0.45)
		(drill 0.2)
		(layers "F.Cu" "B.Cu")
		(net 1)
	)
	(via
		(at 223.25 130.65)
		(size 0.45)
		(drill 0.2)
		(layers "F.Cu" "B.Cu")
		(net 1)
	)
	(via
		(at 256.85 160)
		(size 0.45)
		(drill 0.2)
		(layers "F.Cu" "B.Cu")
		(net 1)
	)
	(via
		(at 166.31 169.34)
		(size 0.45)
		(drill 0.2)
		(layers "F.Cu" "B.Cu")
		(net 1)
	)
	(via
		(at 185.500001 121.500001)
		(size 0.45)
		(drill 0.2)
		(layers "F.Cu" "B.Cu")
		(net 1)
	)
	(via
		(at 217 124.5)
		(size 0.45)
		(drill 0.2)
		(layers "F.Cu" "B.Cu")
		(net 1)
	)
	(via
		(at 192.5 128.5)
		(size 0.45)
		(drill 0.2)
		(layers "F.Cu" "B.Cu")
		(net 1)
	)
	(via
		(at 176.55 98.625)
		(size 0.45)
		(drill 0.2)
		(layers "F.Cu" "B.Cu")
		(net 1)
	)
	(via
		(at 200.6 189.36)
		(size 0.45)
		(drill 0.2)
		(layers "F.Cu" "B.Cu")
		(net 1)
	)
	(via
		(at 164.540001 114.890001)
		(size 0.45)
		(drill 0.2)
		(layers "F.Cu" "B.Cu")
		(net 1)
	)
	(via
		(at 192.75 159.5)
		(size 0.45)
		(drill 0.2)
		(layers "F.Cu" "B.Cu")
		(free yes)
		(net 1)
	)
	(via
		(at 209 136)
		(size 0.45)
		(drill 0.2)
		(layers "F.Cu" "B.Cu")
		(net 1)
	)
	(via
		(at 174.6 70.74)
		(size 0.45)
		(drill 0.2)
		(layers "F.Cu" "B.Cu")
		(net 1)
	)
	(via
		(at 200 137)
		(size 0.45)
		(drill 0.2)
		(layers "F.Cu" "B.Cu")
		(net 1)
	)
	(via
		(at 253.2 134.351498)
		(size 0.45)
		(drill 0.2)
		(layers "F.Cu" "B.Cu")
		(net 1)
	)
	(via
		(at 155.655001 94.570001)
		(size 0.45)
		(drill 0.2)
		(layers "F.Cu" "B.Cu")
		(net 1)
	)
	(via
		(at 172.75 178.5)
		(size 0.45)
		(drill 0.2)
		(layers "F.Cu" "B.Cu")
		(free yes)
		(net 1)
	)
	(via
		(at 263.7 133.7)
		(size 0.45)
		(drill 0.2)
		(layers "F.Cu" "B.Cu")
		(net 1)
	)
	(via
		(at 154.380001 125.050001)
		(size 0.45)
		(drill 0.2)
		(layers "F.Cu" "B.Cu")
		(net 1)
	)
	(via
		(at 268.85 78.6)
		(size 0.45)
		(drill 0.2)
		(layers "F.Cu" "B.Cu")
		(net 1)
	)
	(via
		(at 204.93 105.03)
		(size 0.45)
		(drill 0.2)
		(layers "F.Cu" "B.Cu")
		(net 1)
	)
	(via
		(at 150.67 90.59)
		(size 0.45)
		(drill 0.2)
		(layers "F.Cu" "B.Cu")
		(net 1)
	)
	(via
		(at 154.380001 130.130001)
		(size 0.45)
		(drill 0.2)
		(layers "F.Cu" "B.Cu")
		(net 1)
	)
	(via
		(at 198 133)
		(size 0.45)
		(drill 0.2)
		(layers "F.Cu" "B.Cu")
		(net 1)
	)
	(via
		(at 259.7 189)
		(size 0.45)
		(drill 0.2)
		(layers "F.Cu" "B.Cu")
		(net 1)
	)
	(via
		(at 188.25 161.25)
		(size 0.45)
		(drill 0.2)
		(layers "F.Cu" "B.Cu")
		(free yes)
		(net 1)
	)
	(via
		(at 208.19 151.9)
		(size 0.45)
		(drill 0.2)
		(layers "F.Cu" "B.Cu")
		(net 1)
	)
	(via
		(at 163.9 141.05)
		(size 0.45)
		(drill 0.2)
		(layers "F.Cu" "B.Cu")
		(net 1)
	)
	(via
		(at 200.61 70.7)
		(size 0.45)
		(drill 0.2)
		(layers "F.Cu" "B.Cu")
		(net 1)
	)
	(via
		(at 234.4 110.35)
		(size 0.45)
		(drill 0.2)
		(layers "F.Cu" "B.Cu")
		(net 1)
	)
	(via
		(at 157.9 154.7)
		(size 0.45)
		(drill 0.2)
		(layers "F.Cu" "B.Cu")
		(free yes)
		(net 1)
	)
	(via
		(at 189.5 146.85)
		(size 0.45)
		(drill 0.2)
		(layers "F.Cu" "B.Cu")
		(free yes)
		(net 1)
	)
	(via
		(at 195.02 108.23)
		(size 0.45)
		(drill 0.2)
		(layers "F.Cu" "B.Cu")
		(net 1)
	)
	(via
		(at 165.810001 130.130001)
		(size 0.45)
		(drill 0.2)
		(layers "F.Cu" "B.Cu")
		(net 1)
	)
	(via
		(at 180.3 171.7)
		(size 0.45)
		(drill 0.2)
		(layers "F.Cu" "B.Cu")
		(net 1)
	)
	(via
		(at 196.5 119.5)
		(size 0.45)
		(drill 0.2)
		(layers "F.Cu" "B.Cu")
		(net 1)
	)
	(via
		(at 269.32 175.59)
		(size 0.45)
		(drill 0.2)
		(layers "F.Cu" "B.Cu")
		(net 1)
	)
	(via
		(at 169.620001 99.650001)
		(size 0.45)
		(drill 0.2)
		(layers "F.Cu" "B.Cu")
		(net 1)
	)
	(via
		(at 264.05 189.19)
		(size 0.45)
		(drill 0.2)
		(layers "F.Cu" "B.Cu")
		(net 1)
	)
	(via
		(at 180.1 70.75)
		(size 0.45)
		(drill 0.2)
		(layers "F.Cu" "B.Cu")
		(free yes)
		(net 1)
	)
	(via
		(at 174.4 147.6)
		(size 0.45)
		(drill 0.2)
		(layers "F.Cu" "B.Cu")
		(net 1)
	)
	(via
		(at 167.6 188.9)
		(size 0.45)
		(drill 0.2)
		(layers "F.Cu" "B.Cu")
		(net 1)
	)
	(via
		(at 193 72)
		(size 0.45)
		(drill 0.2)
		(layers "F.Cu" "B.Cu")
		(net 1)
	)
	(via
		(at 158.190001 99.650001)
		(size 0.45)
		(drill 0.2)
		(layers "F.Cu" "B.Cu")
		(net 1)
	)
	(via
		(at 207.35 102.5)
		(size 0.45)
		(drill 0.2)
		(layers "F.Cu" "B.Cu")
		(net 1)
	)
	(via
		(at 163.270001 130.130001)
		(size 0.45)
		(drill 0.2)
		(layers "F.Cu" "B.Cu")
		(net 1)
	)
	(via
		(at 198.5 115.5)
		(size 0.45)
		(drill 0.2)
		(layers "F.Cu" "B.Cu")
		(net 1)
	)
	(via
		(at 223.45 92.7)
		(size 0.45)
		(drill 0.2)
		(layers "F.Cu" "B.Cu")
		(net 1)
	)
	(via
		(at 187 165)
		(size 0.45)
		(drill 0.2)
		(layers "F.Cu" "B.Cu")
		(free yes)
		(net 1)
	)
	(via
		(at 207.28 94.355601)
		(size 0.45)
		(drill 0.2)
		(layers "F.Cu" "B.Cu")
		(free yes)
		(net 1)
	)
	(via
		(at 204 120)
		(size 0.45)
		(drill 0.2)
		(layers "F.Cu" "B.Cu")
		(net 1)
	)
	(via
		(at 263.4 179.7)
		(size 0.45)
		(drill 0.2)
		(layers "F.Cu" "B.Cu")
		(net 1)
	)
	(via
		(at 190.5 133.5)
		(size 0.45)
		(drill 0.2)
		(layers "F.Cu" "B.Cu")
		(net 1)
	)
	(via
		(at 186 140)
		(size 0.45)
		(drill 0.2)
		(layers "F.Cu" "B.Cu")
		(net 1)
	)
	(via
		(at 188 144)
		(size 0.45)
		(drill 0.2)
		(layers "F.Cu" "B.Cu")
		(net 1)
	)
	(via
		(at 188.500001 116.500001)
		(size 0.45)
		(drill 0.2)
		(layers "F.Cu" "B.Cu")
		(net 1)
	)
	(via
		(at 168.350001 99.650001)
		(size 0.45)
		(drill 0.2)
		(layers "F.Cu" "B.Cu")
		(net 1)
	)
	(via
		(at 229.3 148.7)
		(size 0.45)
		(drill 0.2)
		(layers "F.Cu" "B.Cu")
		(net 1)
	)
	(via
		(at 222.9 154.1)
		(size 0.45)
		(drill 0.2)
		(layers "F.Cu" "B.Cu")
		(free yes)
		(net 1)
	)
	(via
		(at 158.35 166.5)
		(size 0.45)
		(drill 0.2)
		(layers "F.Cu" "B.Cu")
		(net 1)
	)
	(via
		(at 154.7 156.3)
		(size 0.45)
		(drill 0.2)
		(layers "F.Cu" "B.Cu")
		(free yes)
		(net 1)
	)
	(via
		(at 253.7 71.05)
		(size 0.45)
		(drill 0.2)
		(layers "F.Cu" "B.Cu")
		(net 1)
	)
	(via
		(at 174.629738 101.420266)
		(size 0.45)
		(drill 0.2)
		(layers "F.Cu" "B.Cu")
		(net 1)
	)
	(via
		(at 197 130)
		(size 0.45)
		(drill 0.2)
		(layers "F.Cu" "B.Cu")
		(net 1)
	)
	(via
		(at 165.810001 99.650001)
		(size 0.45)
		(drill 0.2)
		(layers "F.Cu" "B.Cu")
		(net 1)
	)
	(via
		(at 211 121)
		(size 0.45)
		(drill 0.2)
		(layers "F.Cu" "B.Cu")
		(net 1)
	)
	(via
		(at 163.270001 97.110001)
		(size 0.45)
		(drill 0.2)
		(layers "F.Cu" "B.Cu")
		(net 1)
	)
	(via
		(at 185.500001 117.500001)
		(size 0.45)
		(drill 0.2)
		(layers "F.Cu" "B.Cu")
		(net 1)
	)
	(via
		(at 258.4 81.885)
		(size 0.45)
		(drill 0.2)
		(layers "F.Cu" "B.Cu")
		(net 1)
	)
	(via
		(at 183.800001 133.500001)
		(size 0.45)
		(drill 0.2)
		(layers "F.Cu" "B.Cu")
		(net 1)
	)
	(via
		(at 203.75 87.2)
		(size 0.45)
		(drill 0.2)
		(layers "F.Cu" "B.Cu")
		(net 1)
	)
	(via
		(at 156.920001 84.410001)
		(size 0.45)
		(drill 0.2)
		(layers "F.Cu" "B.Cu")
		(net 1)
	)
	(via
		(at 192.5 130.5)
		(size 0.45)
		(drill 0.2)
		(layers "F.Cu" "B.Cu")
		(net 1)
	)
	(via
		(at 195 152.75)
		(size 0.45)
		(drill 0.2)
		(layers "F.Cu" "B.Cu")
		(free yes)
		(net 1)
	)
	(via
		(at 188.5 136.5)
		(size 0.45)
		(drill 0.2)
		(layers "F.Cu" "B.Cu")
		(net 1)
	)
	(via
		(at 158.62 171.4)
		(size 0.45)
		(drill 0.2)
		(layers "F.Cu" "B.Cu")
		(net 1)
	)
	(via
		(at 167.4 139.99)
		(size 0.45)
		(drill 0.2)
		(layers "F.Cu" "B.Cu")
		(net 1)
	)
	(via
		(at 222.425 124.425)
		(size 0.45)
		(drill 0.2)
		(layers "F.Cu" "B.Cu")
		(net 1)
	)
	(via
		(at 210 118)
		(size 0.45)
		(drill 0.2)
		(layers "F.Cu" "B.Cu")
		(net 1)
	)
	(via
		(at 248.675 142.075)
		(size 0.45)
		(drill 0.2)
		(layers "F.Cu" "B.Cu")
		(net 1)
	)
	(via
		(at 169.620001 89.490001)
		(size 0.45)
		(drill 0.2)
		(layers "F.Cu" "B.Cu")
		(net 1)
	)
	(via
		(at 232.6 145.1)
		(size 0.45)
		(drill 0.2)
		(layers "F.Cu" "B.Cu")
		(net 1)
	)
	(via
		(at 189.5 115.5)
		(size 0.45)
		(drill 0.2)
		(layers "F.Cu" "B.Cu")
		(net 1)
	)
	(via
		(at 159.72 170.23)
		(size 0.45)
		(drill 0.2)
		(layers "F.Cu" "B.Cu")
		(net 1)
	)
	(via
		(at 156.920001 81.870001)
		(size 0.45)
		(drill 0.2)
		(layers "F.Cu" "B.Cu")
		(net 1)
	)
	(via
		(at 171.018636 120.434019)
		(size 0.45)
		(drill 0.2)
		(layers "F.Cu" "B.Cu")
		(net 1)
	)
	(via
		(at 258.4 79.485)
		(size 0.45)
		(drill 0.2)
		(layers "F.Cu" "B.Cu")
		(net 1)
	)
	(via
		(at 200.0255 105.5092)
		(size 0.45)
		(drill 0.2)
		(layers "F.Cu" "B.Cu")
		(net 1)
	)
	(via
		(at 192.46 95.96)
		(size 0.45)
		(drill 0.2)
		(layers "F.Cu" "B.Cu")
		(net 1)
	)
	(via
		(at 191 72)
		(size 0.45)
		(drill 0.2)
		(layers "F.Cu" "B.Cu")
		(net 1)
	)
	(via
		(at 260.7 127)
		(size 0.45)
		(drill 0.2)
		(layers "F.Cu" "B.Cu")
		(net 1)
	)
	(via
		(at 256.95 101.3)
		(size 0.45)
		(drill 0.2)
		(layers "F.Cu" "B.Cu")
		(net 1)
	)
	(via
		(at 194.63 107.8)
		(size 0.45)
		(drill 0.2)
		(layers "F.Cu" "B.Cu")
		(net 1)
	)
	(via
		(at 196 133)
		(size 0.45)
		(drill 0.2)
		(layers "F.Cu" "B.Cu")
		(net 1)
	)
	(via
		(at 170.875001 132.525001)
		(size 0.45)
		(drill 0.2)
		(layers "F.Cu" "B.Cu")
		(net 1)
	)
	(via
		(at 155.73 70.7)
		(size 0.45)
		(drill 0.2)
		(layers "F.Cu" "B.Cu")
		(net 1)
	)
	(via
		(at 166.31 161.3)
		(size 0.45)
		(drill 0.2)
		(layers "F.Cu" "B.Cu")
		(net 1)
	)
	(via
		(at 158.1125 172)
		(size 0.45)
		(drill 0.2)
		(layers "F.Cu" "B.Cu")
		(net 1)
	)
	(via
		(at 258.62 119.62)
		(size 0.45)
		(drill 0.2)
		(layers "F.Cu" "B.Cu")
		(free yes)
		(net 1)
	)
	(via
		(at 254.93 136.835)
		(size 0.45)
		(drill 0.2)
		(layers "F.Cu" "B.Cu")
		(net 1)
	)
	(via
		(at 158.6 175.3)
		(size 0.45)
		(drill 0.2)
		(layers "F.Cu" "B.Cu")
		(net 1)
	)
	(via
		(at 155.650001 125.050001)
		(size 0.45)
		(drill 0.2)
		(layers "F.Cu" "B.Cu")
		(net 1)
	)
	(via
		(at 233.2 150.9)
		(size 0.45)
		(drill 0.2)
		(layers "F.Cu" "B.Cu")
		(net 1)
	)
	(via
		(at 161 128.8)
		(size 0.45)
		(drill 0.2)
		(layers "F.Cu" "B.Cu")
		(net 1)
	)
	(via
		(at 166.31 159.96)
		(size 0.45)
		(drill 0.2)
		(layers "F.Cu" "B.Cu")
		(net 1)
	)
	(via
		(at 192.5 116.5)
		(size 0.45)
		(drill 0.2)
		(layers "F.Cu" "B.Cu")
		(net 1)
	)
	(via
		(at 154.380001 104.730001)
		(size 0.45)
		(drill 0.2)
		(layers "F.Cu" "B.Cu")
		(net 1)
	)
	(via
		(at 185.500001 131.500001)
		(size 0.45)
		(drill 0.2)
		(layers "F.Cu" "B.Cu")
		(net 1)
	)
	(via
		(at 158.190001 125.050001)
		(size 0.45)
		(drill 0.2)
		(layers "F.Cu" "B.Cu")
		(net 1)
	)
	(via
		(at 169.620001 92.030001)
		(size 0.45)
		(drill 0.2)
		(layers "F.Cu" "B.Cu")
		(net 1)
	)
	(via
		(at 172.2 167.4)
		(size 0.45)
		(drill 0.2)
		(layers "F.Cu" "B.Cu")
		(net 1)
	)
	(via
		(at 220.85 85.475)
		(size 0.45)
		(drill 0.2)
		(layers "F.Cu" "B.Cu")
		(net 1)
	)
	(via
		(at 247.3 126.6)
		(size 0.45)
		(drill 0.2)
		(layers "F.Cu" "B.Cu")
		(net 1)
	)
	(via
		(at 209.120001 146.857)
		(size 0.45)
		(drill 0.2)
		(layers "F.Cu" "B.Cu")
		(net 1)
	)
	(via
		(at 195 130)
		(size 0.45)
		(drill 0.2)
		(layers "F.Cu" "B.Cu")
		(net 1)
	)
	(via
		(at 177.15 172.0125)
		(size 0.45)
		(drill 0.2)
		(layers "F.Cu" "B.Cu")
		(net 1)
	)
	(via
		(at 185.500001 115.500001)
		(size 0.45)
		(drill 0.2)
		(layers "F.Cu" "B.Cu")
		(net 1)
	)
	(via
		(at 159.95 188.95)
		(size 0.45)
		(drill 0.2)
		(layers "F.Cu" "B.Cu")
		(net 1)
	)
	(via
		(at 176.581481 83.115051)
		(size 0.45)
		(drill 0.2)
		(layers "F.Cu" "B.Cu")
		(net 1)
	)
	(via
		(at 169.620001 109.810001)
		(size 0.45)
		(drill 0.2)
		(layers "F.Cu" "B.Cu")
		(net 1)
	)
	(via
		(at 188.25 160.25)
		(size 0.45)
		(drill 0.2)
		(layers "F.Cu" "B.Cu")
		(free yes)
		(net 1)
	)
	(via
		(at 250.625 134.975)
		(size 0.45)
		(drill 0.2)
		(layers "F.Cu" "B.Cu")
		(net 1)
	)
	(via
		(at 200 131)
		(size 0.45)
		(drill 0.2)
		(layers "F.Cu" "B.Cu")
		(net 1)
	)
	(via
		(at 192.47 93.04)
		(size 0.45)
		(drill 0.2)
		(layers "F.Cu" "B.Cu")
		(net 1)
	)
	(via
		(at 205.61 70.7)
		(size 0.45)
		(drill 0.2)
		(layers "F.Cu" "B.Cu")
		(net 1)
	)
	(via
		(at 214.004834 131.025)
		(size 0.45)
		(drill 0.2)
		(layers "F.Cu" "B.Cu")
		(net 1)
	)
	(via
		(at 169.620001 84.410001)
		(size 0.45)
		(drill 0.2)
		(layers "F.Cu" "B.Cu")
		(net 1)
	)
	(via
		(at 172 171.7)
		(size 0.45)
		(drill 0.2)
		(layers "F.Cu" "B.Cu")
		(net 1)
	)
	(via
		(at 160.59 70.66)
		(size 0.45)
		(drill 0.2)
		(layers "F.Cu" "B.Cu")
		(net 1)
	)
	(via
		(at 167.55 142.3)
		(size 0.45)
		(drill 0.2)
		(layers "F.Cu" "B.Cu")
		(net 1)
	)
	(via
		(at 155.6 189.36)
		(size 0.45)
		(drill 0.2)
		(layers "F.Cu" "B.Cu")
		(net 1)
	)
	(via
		(at 254 106.6)
		(size 0.45)
		(drill 0.2)
		(layers "F.Cu" "B.Cu")
		(free yes)
		(net 1)
	)
	(via
		(at 202 145)
		(size 0.45)
		(drill 0.2)
		(layers "F.Cu" "B.Cu")
		(net 1)
	)
	(via
		(at 244.6 150)
		(size 0.45)
		(drill 0.2)
		(layers "F.Cu" "B.Cu")
		(net 1)
	)
	(via
		(at 190.5 131.5)
		(size 0.45)
		(drill 0.2)
		(layers "F.Cu" "B.Cu")
		(net 1)
	)
	(via
		(at 164.540001 86.950001)
		(size 0.45)
		(drill 0.2)
		(layers "F.Cu" "B.Cu")
		(net 1)
	)
	(via
		(at 258.4 96.285)
		(size 0.45)
		(drill 0.2)
		(layers "F.Cu" "B.Cu")
		(net 1)
	)
	(via
		(at 154.380001 117.430001)
		(size 0.45)
		(drill 0.2)
		(layers "F.Cu" "B.Cu")
		(net 1)
	)
	(via
		(at 269.36 120.63)
		(size 0.45)
		(drill 0.2)
		(layers "F.Cu" "B.Cu")
		(net 1)
	)
	(via
		(at 155.650001 117.435001)
		(size 0.45)
		(drill 0.2)
		(layers "F.Cu" "B.Cu")
		(net 1)
	)
	(via
		(at 259.2 76.1)
		(size 0.45)
		(drill 0.2)
		(layers "F.Cu" "B.Cu")
		(net 1)
	)
	(via
		(at 167.080001 114.890001)
		(size 0.45)
		(drill 0.2)
		(layers "F.Cu" "B.Cu")
		(net 1)
	)
	(via
		(at 168.350001 102.190001)
		(size 0.45)
		(drill 0.2)
		(layers "F.Cu" "B.Cu")
		(net 1)
	)
	(via
		(at 182.916916 138.301937)
		(size 0.45)
		(drill 0.2)
		(layers "F.Cu" "B.Cu")
		(net 1)
	)
	(via
		(at 240.425 112.275)
		(size 0.45)
		(drill 0.2)
		(layers "F.Cu" "B.Cu")
		(net 1)
	)
	(via
		(at 189.797196 159.508591)
		(size 0.45)
		(drill 0.2)
		(layers "F.Cu" "B.Cu")
		(free yes)
		(net 1)
	)
	(via
		(at 156.75 178.75)
		(size 0.45)
		(drill 0.2)
		(layers "F.Cu" "B.Cu")
		(free yes)
		(net 1)
	)
	(via
		(at 186.500001 121.500001)
		(size 0.45)
		(drill 0.2)
		(layers "F.Cu" "B.Cu")
		(net 1)
	)
	(via
		(at 154.380001 81.870001)
		(size 0.45)
		(drill 0.2)
		(layers "F.Cu" "B.Cu")
		(net 1)
	)
	(via
		(at 158.190001 102.190001)
		(size 0.45)
		(drill 0.2)
		(layers "F.Cu" "B.Cu")
		(net 1)
	)
	(via
		(at 175.3 166.5)
		(size 0.45)
		(drill 0.2)
		(layers "F.Cu" "B.Cu")
		(net 1)
	)
	(via
		(at 190.5 125.5)
		(size 0.45)
		(drill 0.2)
		(layers "F.Cu" "B.Cu")
		(net 1)
	)
	(via
		(at 195 86.7)
		(size 0.45)
		(drill 0.2)
		(layers "F.Cu" "B.Cu")
		(net 1)
	)
	(via
		(at 169.620001 117.430001)
		(size 0.45)
		(drill 0.2)
		(layers "F.Cu" "B.Cu")
		(net 1)
	)
	(via
		(at 195 116)
		(size 0.45)
		(drill 0.2)
		(layers "F.Cu" "B.Cu")
		(net 1)
	)
	(via
		(at 219.07 173.56)
		(size 0.45)
		(drill 0.2)
		(layers "F.Cu" "B.Cu")
		(net 1)
	)
	(via
		(at 189 159.5)
		(size 0.45)
		(drill 0.2)
		(layers "F.Cu" "B.Cu")
		(free yes)
		(net 1)
	)
	(via
		(at 171.175237 97.630736)
		(size 0.45)
		(drill 0.2)
		(layers "F.Cu" "B.Cu")
		(net 1)
	)
	(via
		(at 193.9 160.9)
		(size 0.45)
		(drill 0.2)
		(layers "F.Cu" "B.Cu")
		(free yes)
		(net 1)
	)
	(via
		(at 150.67 150.59)
		(size 0.45)
		(drill 0.2)
		(layers "F.Cu" "B.Cu")
		(net 1)
	)
	(via
		(at 221.3 165.05)
		(size 0.45)
		(drill 0.2)
		(layers "F.Cu" "B.Cu")
		(net 1)
	)
	(via
		(at 154.385001 112.350001)
		(size 0.45)
		(drill 0.2)
		(layers "F.Cu" "B.Cu")
		(net 1)
	)
	(via
		(at 205 134)
		(size 0.45)
		(drill 0.2)
		(layers "F.Cu" "B.Cu")
		(net 1)
	)
	(via
		(at 199 139)
		(size 0.45)
		(drill 0.2)
		(layers "F.Cu" "B.Cu")
		(net 1)
	)
	(via
		(at 201.0005 119.05)
		(size 0.45)
		(drill 0.2)
		(layers "F.Cu" "B.Cu")
		(net 1)
	)
	(via
		(at 161.4 187.5)
		(size 0.45)
		(drill 0.2)
		(layers "F.Cu" "B.Cu")
		(net 1)
	)
	(via
		(at 163 166.8)
		(size 0.45)
		(drill 0.2)
		(layers "F.Cu" "B.Cu")
		(net 1)
	)
	(via
		(at 183.76 188.64)
		(size 0.45)
		(drill 0.2)
		(layers "F.Cu" "B.Cu")
		(net 1)
	)
	(via
		(at 185.5 98.7)
		(size 0.45)
		(drill 0.2)
		(layers "F.Cu" "B.Cu")
		(net 1)
	)
	(via
		(at 160.2125 169.6)
		(size 0.45)
		(drill 0.2)
		(layers "F.Cu" "B.Cu")
		(net 1)
	)
	(via
		(at 155.6 152.5)
		(size 0.45)
		(drill 0.2)
		(layers "F.Cu" "B.Cu")
		(free yes)
		(net 1)
	)
	(via
		(at 197 127)
		(size 0.45)
		(drill 0.2)
		(layers "F.Cu" "B.Cu")
		(net 1)
	)
	(via
		(at 156.915001 92.030001)
		(size 0.45)
		(drill 0.2)
		(layers "F.Cu" "B.Cu")
		(net 1)
	)
	(via
		(at 207 140)
		(size 0.45)
		(drill 0.2)
		(layers "F.Cu" "B.Cu")
		(net 1)
	)
	(via
		(at 192.55 98.69)
		(size 0.45)
		(drill 0.2)
		(layers "F.Cu" "B.Cu")
		(net 1)
	)
	(via
		(at 220.9 111.55)
		(size 0.45)
		(drill 0.2)
		(layers "F.Cu" "B.Cu")
		(net 1)
	)
	(via
		(at 165.810001 117.430001)
		(size 0.45)
		(drill 0.2)
		(layers "F.Cu" "B.Cu")
		(net 1)
	)
	(via
		(at 186.6 183.7)
		(size 0.45)
		(drill 0.2)
		(layers "F.Cu" "B.Cu")
		(net 1)
	)
	(via
		(at 226 92.75)
		(size 0.45)
		(drill 0.2)
		(layers "F.Cu" "B.Cu")
		(net 1)
	)
	(via
		(at 203 126)
		(size 0.45)
		(drill 0.2)
		(layers "F.Cu" "B.Cu")
		(net 1)
	)
	(via
		(at 157.9 143.1)
		(size 0.45)
		(drill 0.2)
		(layers "F.Cu" "B.Cu")
		(net 1)
	)
	(via
		(at 221.9 165.7)
		(size 0.45)
		(drill 0.2)
		(layers "F.Cu" "B.Cu")
		(net 1)
	)
	(via
		(at 207.2 150.4)
		(size 0.45)
		(drill 0.2)
		(layers "F.Cu" "B.Cu")
		(net 1)
	)
	(via
		(at 199.7 95.95)
		(size 0.45)
		(drill 0.2)
		(layers "F.Cu" "B.Cu")
		(net 1)
	)
	(via
		(at 229.3 140.05)
		(size 0.45)
		(drill 0.2)
		(layers "F.Cu" "B.Cu")
		(net 1)
	)
	(via
		(at 165.810001 97.110001)
		(size 0.45)
		(drill 0.2)
		(layers "F.Cu" "B.Cu")
		(net 1)
	)
	(via
		(at 200 128)
		(size 0.45)
		(drill 0.2)
		(layers "F.Cu" "B.Cu")
		(net 1)
	)
	(via
		(at 269.22 160.65)
		(size 0.45)
		(drill 0.2)
		(layers "F.Cu" "B.Cu")
		(net 1)
	)
	(via
		(at 190.5 121.5)
		(size 0.45)
		(drill 0.2)
		(layers "F.Cu" "B.Cu")
		(net 1)
	)
	(via
		(at 167.080001 117.430001)
		(size 0.45)
		(drill 0.2)
		(layers "F.Cu" "B.Cu")
		(net 1)
	)
	(via
		(at 158.190001 122.510001)
		(size 0.45)
		(drill 0.2)
		(layers "F.Cu" "B.Cu")
		(net 1)
	)
	(via
		(at 192.5 118.5)
		(size 0.45)
		(drill 0.2)
		(layers "F.Cu" "B.Cu")
		(net 1)
	)
	(via
		(at 188.1 167.8)
		(size 0.45)
		(drill 0.2)
		(layers "F.Cu" "B.Cu")
		(net 1)
	)
	(via
		(at 160.8125 174.85)
		(size 0.45)
		(drill 0.2)
		(layers "F.Cu" "B.Cu")
		(net 1)
	)
	(via
		(at 162.000001 117.430001)
		(size 0.45)
		(drill 0.2)
		(layers "F.Cu" "B.Cu")
		(net 1)
	)
	(via
		(at 269.32 70.68)
		(size 0.45)
		(drill 0.2)
		(layers "F.Cu" "B.Cu")
		(net 1)
	)
	(via
		(at 185 72)
		(size 0.45)
		(drill 0.2)
		(layers "F.Cu" "B.Cu")
		(net 1)
	)
	(via
		(at 195.8 185.675)
		(size 0.45)
		(drill 0.2)
		(layers "F.Cu" "B.Cu")
		(net 1)
	)
	(via
		(at 168.350003 81.870003)
		(size 0.45)
		(drill 0.2)
		(layers "F.Cu" "B.Cu")
		(net 1)
	)
	(via
		(at 162.000001 92.030001)
		(size 0.45)
		(drill 0.2)
		(layers "F.Cu" "B.Cu")
		(net 1)
	)
	(via
		(at 155.650001 127.590001)
		(size 0.45)
		(drill 0.2)
		(layers "F.Cu" "B.Cu")
		(net 1)
	)
	(via
		(at 215.4 163.1)
		(size 0.45)
		(drill 0.2)
		(layers "F.Cu" "B.Cu")
		(net 1)
	)
	(via
		(at 173.25 178)
		(size 0.45)
		(drill 0.2)
		(layers "F.Cu" "B.Cu")
		(free yes)
		(net 1)
	)
	(via
		(at 190.5 115.5)
		(size 0.45)
		(drill 0.2)
		(layers "F.Cu" "B.Cu")
		(net 1)
	)
	(via
		(at 167.080001 92.030001)
		(size 0.45)
		(drill 0.2)
		(layers "F.Cu" "B.Cu")
		(net 1)
	)
	(via
		(at 269.1 144.6)
		(size 0.45)
		(drill 0.2)
		(layers "F.Cu" "B.Cu")
		(net 1)
	)
	(via
		(at 165.810001 114.890001)
		(size 0.45)
		(drill 0.2)
		(layers "F.Cu" "B.Cu")
		(net 1)
	)
	(via
		(at 187.75 160.75)
		(size 0.45)
		(drill 0.2)
		(layers "F.Cu" "B.Cu")
		(free yes)
		(net 1)
	)
	(via
		(at 164.540001 117.430001)
		(size 0.45)
		(drill 0.2)
		(layers "F.Cu" "B.Cu")
		(net 1)
	)
	(via
		(at 162.000001 94.570001)
		(size 0.45)
		(drill 0.2)
		(layers "F.Cu" "B.Cu")
		(net 1)
	)
	(via
		(at 231.4 138.5)
		(size 0.45)
		(drill 0.2)
		(layers "F.Cu" "B.Cu")
		(net 1)
	)
	(via
		(at 193.5 131.5)
		(size 0.45)
		(drill 0.2)
		(layers "F.Cu" "B.Cu")
		(net 1)
	)
	(via
		(at 207 129)
		(size 0.45)
		(drill 0.2)
		(layers "F.Cu" "B.Cu")
		(net 1)
	)
	(via
		(at 204.2036 89.6088)
		(size 0.45)
		(drill 0.2)
		(layers "F.Cu" "B.Cu")
		(net 1)
	)
	(via
		(at 189 72)
		(size 0.45)
		(drill 0.2)
		(layers "F.Cu" "B.Cu")
		(net 1)
	)
	(via
		(at 196 131)
		(size 0.45)
		(drill 0.2)
		(layers "F.Cu" "B.Cu")
		(net 1)
	)
	(via
		(at 257.275 108.6)
		(size 0.45)
		(drill 0.2)
		(layers "F.Cu" "B.Cu")
		(net 1)
	)
	(via
		(at 210.25 173.56)
		(size 0.45)
		(drill 0.2)
		(layers "F.Cu" "B.Cu")
		(net 1)
	)
	(via
		(at 202 132)
		(size 0.45)
		(drill 0.2)
		(layers "F.Cu" "B.Cu")
		(net 1)
	)
	(via
		(at 243.6 165)
		(size 0.45)
		(drill 0.2)
		(layers "F.Cu" "B.Cu")
		(net 1)
	)
	(via
		(at 190.5 117.5)
		(size 0.45)
		(drill 0.2)
		(layers "F.Cu" "B.Cu")
		(net 1)
	)
	(via
		(at 200.25 100.55)
		(size 0.45)
		(drill 0.2)
		(layers "F.Cu" "B.Cu")
		(net 1)
	)
	(via
		(at 192.9 160.9)
		(size 0.45)
		(drill 0.2)
		(layers "F.Cu" "B.Cu")
		(free yes)
		(net 1)
	)
	(via
		(at 264.75 87.9)
		(size 0.45)
		(drill 0.2)
		(layers "F.Cu" "B.Cu")
		(net 1)
	)
	(via
		(at 192.5 132.5)
		(size 0.45)
		(drill 0.2)
		(layers "F.Cu" "B.Cu")
		(net 1)
	)
	(via
		(at 199.35 87.2)
		(size 0.45)
		(drill 0.2)
		(layers "F.Cu" "B.Cu")
		(net 1)
	)
	(via
		(at 186.3 175.6)
		(size 0.45)
		(drill 0.2)
		(layers "F.Cu" "B.Cu")
		(net 1)
	)
	(via
		(at 158.190001 127.590001)
		(size 0.45)
		(drill 0.2)
		(layers "F.Cu" "B.Cu")
		(net 1)
	)
	(via
		(at 187 72)
		(size 0.45)
		(drill 0.2)
		(layers "F.Cu" "B.Cu")
		(net 1)
	)
	(via
		(at 185.500001 123.500001)
		(size 0.45)
		(drill 0.2)
		(layers "F.Cu" "B.Cu")
		(net 1)
	)
	(via
		(at 222.5 84.35)
		(size 0.45)
		(drill 0.2)
		(layers "F.Cu" "B.Cu")
		(net 1)
	)
	(via
		(at 155 171.1)
		(size 0.45)
		(drill 0.2)
		(layers "F.Cu" "B.Cu")
		(net 1)
	)
	(via
		(at 256.7 71.05)
		(size 0.45)
		(drill 0.2)
		(layers "F.Cu" "B.Cu")
		(net 1)
	)
	(via
		(at 191.75 158.25)
		(size 0.45)
		(drill 0.2)
		(layers "F.Cu" "B.Cu")
		(free yes)
		(net 1)
	)
	(via
		(at 156.920001 107.270001)
		(size 0.45)
		(drill 0.2)
		(layers "F.Cu" "B.Cu")
		(net 1)
	)
	(via
		(at 217.95 111.55)
		(size 0.45)
		(drill 0.2)
		(layers "F.Cu" "B.Cu")
		(net 1)
	)
	(via
		(at 204.92 100.2)
		(size 0.45)
		(drill 0.2)
		(layers "F.Cu" "B.Cu")
		(net 1)
	)
	(via
		(at 150.67 136.11)
		(size 0.45)
		(drill 0.2)
		(layers "F.Cu" "B.Cu")
		(net 1)
	)
	(via
		(at 169.25 166.66)
		(size 0.45)
		(drill 0.2)
		(layers "F.Cu" "B.Cu")
		(net 1)
	)
	(via
		(at 202 129)
		(size 0.45)
		(drill 0.2)
		(layers "F.Cu" "B.Cu")
		(net 1)
	)
	(via
		(at 172.25 114.325)
		(size 0.45)
		(drill 0.2)
		(layers "F.Cu" "B.Cu")
		(net 1)
	)
	(via
		(at 159.460001 117.430001)
		(size 0.45)
		(drill 0.2)
		(layers "F.Cu" "B.Cu")
		(net 1)
	)
	(via
		(at 155.650001 92.030001)
		(size 0.45)
		(drill 0.2)
		(layers "F.Cu" "B.Cu")
		(net 1)
	)
	(via
		(at 188.500001 134.500001)
		(size 0.45)
		(drill 0.2)
		(layers "F.Cu" "B.Cu")
		(net 1)
	)
	(via
		(at 154.380001 97.110001)
		(size 0.45)
		(drill 0.2)
		(layers "F.Cu" "B.Cu")
		(net 1)
	)
	(via
		(at 226.4 152.8)
		(size 0.45)
		(drill 0.2)
		(layers "F.Cu" "B.Cu")
		(net 1)
	)
	(via
		(at 202 134)
		(size 0.45)
		(drill 0.2)
		(layers "F.Cu" "B.Cu")
		(net 1)
	)
	(via
		(at 175.05 169.6125)
		(size 0.45)
		(drill 0.2)
		(layers "F.Cu" "B.Cu")
		(net 1)
	)
	(via
		(at 198 128)
		(size 0.45)
		(drill 0.2)
		(layers "F.Cu" "B.Cu")
		(net 1)
	)
	(via
		(at 158.1125 169.6)
		(size 0.45)
		(drill 0.2)
		(layers "F.Cu" "B.Cu")
		(net 1)
	)
	(via
		(at 164.540001 102.190001)
		(size 0.45)
		(drill 0.2)
		(layers "F.Cu" "B.Cu")
		(net 1)
	)
	(via
		(at 187.5 136.5)
		(size 0.45)
		(drill 0.2)
		(layers "F.Cu" "B.Cu")
		(net 1)
	)
	(via
		(at 172.325001 132.525001)
		(size 0.45)
		(drill 0.2)
		(layers "F.Cu" "B.Cu")
		(net 1)
	)
	(via
		(at 207.2 151.9)
		(size 0.45)
		(drill 0.2)
		(layers "F.Cu" "B.Cu")
		(net 1)
	)
	(via
		(at 176.1 169.6125)
		(size 0.45)
		(drill 0.2)
		(layers "F.Cu" "B.Cu")
		(net 1)
	)
	(via
		(at 187.25 161.25)
		(size 0.45)
		(drill 0.2)
		(layers "F.Cu" "B.Cu")
		(free yes)
		(net 1)
	)
	(via
		(at 229.425 143.0255)
		(size 0.45)
		(drill 0.2)
		(layers "F.Cu" "B.Cu")
		(net 1)
	)
	(via
		(at 255.2515 135.2495)
		(size 0.45)
		(drill 0.2)
		(layers "F.Cu" "B.Cu")
		(net 1)
	)
	(via
		(at 163.3 169.9)
		(size 0.45)
		(drill 0.2)
		(layers "F.Cu" "B.Cu")
		(net 1)
	)
	(via
		(at 156.920001 109.810001)
		(size 0.45)
		(drill 0.2)
		(layers "F.Cu" "B.Cu")
		(net 1)
	)
	(via
		(at 194 156.25)
		(size 0.45)
		(drill 0.2)
		(layers "F.Cu" "B.Cu")
		(free yes)
		(net 1)
	)
	(via
		(at 205 144)
		(size 0.45)
		(drill 0.2)
		(layers "F.Cu" "B.Cu")
		(net 1)
	)
	(via
		(at 160.730001 112.350001)
		(size 0.45)
		(drill 0.2)
		(layers "F.Cu" "B.Cu")
		(net 1)
	)
	(via
		(at 262.6 123.9)
		(size 0.45)
		(drill 0.2)
		(layers "F.Cu" "B.Cu")
		(net 1)
	)
	(via
		(at 200 135)
		(size 0.45)
		(drill 0.2)
		(layers "F.Cu" "B.Cu")
		(net 1)
	)
	(via
		(at 239.25 144.325)
		(size 0.45)
		(drill 0.2)
		(layers "F.Cu" "B.Cu")
		(net 1)
	)
	(via
		(at 202.699685 92.712282)
		(size 0.45)
		(drill 0.2)
		(layers "F.Cu" "B.Cu")
		(net 1)
	)
	(via
		(at 200 123)
		(size 0.45)
		(drill 0.2)
		(layers "F.Cu" "B.Cu")
		(net 1)
	)
	(via
		(at 160.730001 119.970001)
		(size 0.45)
		(drill 0.2)
		(layers "F.Cu" "B.Cu")
		(net 1)
	)
	(via
		(at 169.25 159.96)
		(size 0.45)
		(drill 0.2)
		(layers "F.Cu" "B.Cu")
		(net 1)
	)
	(via
		(at 150.66 184.44)
		(size 0.45)
		(drill 0.2)
		(layers "F.Cu" "B.Cu")
		(net 1)
	)
	(via
		(at 195.4 175.2)
		(size 0.45)
		(drill 0.2)
		(layers "F.Cu" "B.Cu")
		(net 1)
	)
	(via
		(at 223.3 149.8)
		(size 0.45)
		(drill 0.2)
		(layers "F.Cu" "B.Cu")
		(net 1)
	)
	(via
		(at 219.5 155.6)
		(size 0.45)
		(drill 0.2)
		(layers "F.Cu" "B.Cu")
		(net 1)
	)
	(via
		(at 158.65 170.2)
		(size 0.45)
		(drill 0.2)
		(layers "F.Cu" "B.Cu")
		(net 1)
	)
	(via
		(at 158.190001 94.570001)
		(size 0.45)
		(drill 0.2)
		(layers "F.Cu" "B.Cu")
		(net 1)
	)
	(via
		(at 155.650001 86.950001)
		(size 0.45)
		(drill 0.2)
		(layers "F.Cu" "B.Cu")
		(net 1)
	)
	(via
		(at 171.175237 101.669265)
		(size 0.45)
		(drill 0.2)
		(layers "F.Cu" "B.Cu")
		(net 1)
	)
	(via
		(at 212 135)
		(size 0.45)
		(drill 0.2)
		(layers "F.Cu" "B.Cu")
		(net 1)
	)
	(via
		(at 167.080001 99.650001)
		(size 0.45)
		(drill 0.2)
		(layers "F.Cu" "B.Cu")
		(net 1)
	)
	(via
		(at 154.380001 84.410001)
		(size 0.45)
		(drill 0.2)
		(layers "F.Cu" "B.Cu")
		(net 1)
	)
	(via
		(at 195 152)
		(size 0.45)
		(drill 0.2)
		(layers "F.Cu" "B.Cu")
		(free yes)
		(net 1)
	)
	(via
		(at 216.13 174.9)
		(size 0.45)
		(drill 0.2)
		(layers "F.Cu" "B.Cu")
		(net 1)
	)
	(via
		(at 201 126)
		(size 0.45)
		(drill 0.2)
		(layers "F.Cu" "B.Cu")
		(net 1)
	)
	(via
		(at 154.380001 102.190001)
		(size 0.45)
		(drill 0.2)
		(layers "F.Cu" "B.Cu")
		(net 1)
	)
	(via
		(at 205.6 189.36)
		(size 0.45)
		(drill 0.2)
		(layers "F.Cu" "B.Cu")
		(net 1)
	)
	(via
		(at 245.61 70.7)
		(size 0.45)
		(drill 0.2)
		(layers "F.Cu" "B.Cu")
		(net 1)
	)
	(via
		(at 154.6 153.7)
		(size 0.45)
		(drill 0.2)
		(layers "F.Cu" "B.Cu")
		(free yes)
		(net 1)
	)
	(via
		(at 171.6 148.4)
		(size 0.45)
		(drill 0.2)
		(layers "F.Cu" "B.Cu")
		(net 1)
	)
	(via
		(at 156.920001 127.590001)
		(size 0.45)
		(drill 0.2)
		(layers "F.Cu" "B.Cu")
		(net 1)
	)
	(via
		(at 196.075 175.2)
		(size 0.45)
		(drill 0.2)
		(layers "F.Cu" "B.Cu")
		(net 1)
	)
	(via
		(at 195 132)
		(size 0.45)
		(drill 0.2)
		(layers "F.Cu" "B.Cu")
		(net 1)
	)
	(via
		(at 172.595501 85.929501)
		(size 0.45)
		(drill 0.2)
		(layers "F.Cu" "B.Cu")
		(net 1)
	)
	(via
		(at 196.475 185.675)
		(size 0.45)
		(drill 0.2)
		(layers "F.Cu" "B.Cu")
		(net 1)
	)
	(via
		(at 258.4 86.685)
		(size 0.45)
		(drill 0.2)
		(layers "F.Cu" "B.Cu")
		(net 1)
	)
	(via
		(at 196 128)
		(size 0.45)
		(drill 0.2)
		(layers "F.Cu" "B.Cu")
		(net 1)
	)
	(via
		(at 186.500001 129.500001)
		(size 0.45)
		(drill 0.2)
		(layers "F.Cu" "B.Cu")
		(net 1)
	)
	(via
		(at 168.350001 122.510001)
		(size 0.45)
		(drill 0.2)
		(layers "F.Cu" "B.Cu")
		(net 1)
	)
	(via
		(at 161.3 154.4)
		(size 0.45)
		(drill 0.2)
		(layers "F.Cu" "B.Cu")
		(free yes)
		(net 1)
	)
	(via
		(at 194.591252 93.55)
		(size 0.45)
		(drill 0.2)
		(layers "F.Cu" "B.Cu")
		(net 1)
	)
	(via
		(at 167.080001 104.730001)
		(size 0.45)
		(drill 0.2)
		(layers "F.Cu" "B.Cu")
		(net 1)
	)
	(via
		(at 216.13 173.56)
		(size 0.45)
		(drill 0.2)
		(layers "F.Cu" "B.Cu")
		(net 1)
	)
	(via
		(at 174.675191 133.300001)
		(size 0.45)
		(drill 0.2)
		(layers "F.Cu" "B.Cu")
		(net 1)
	)
	(via
		(at 202 124)
		(size 0.45)
		(drill 0.2)
		(layers "F.Cu" "B.Cu")
		(net 1)
	)
	(via
		(at 192 159.5)
		(size 0.45)
		(drill 0.2)
		(layers "F.Cu" "B.Cu")
		(free yes)
		(net 1)
	)
	(via
		(at 219.07 172.22)
		(size 0.45)
		(drill 0.2)
		(layers "F.Cu" "B.Cu")
		(net 1)
	)
	(via
		(at 177.15 170.8375)
		(size 0.45)
		(drill 0.2)
		(layers "F.Cu" "B.Cu")
		(net 1)
	)
	(via
		(at 186.7 181.85)
		(size 0.45)
		(drill 0.2)
		(layers "F.Cu" "B.Cu")
		(net 1)
	)
	(via
		(at 164.540001 99.650001)
		(size 0.45)
		(drill 0.2)
		(layers "F.Cu" "B.Cu")
		(net 1)
	)
	(via
		(at 269.32 125.61)
		(size 0.45)
		(drill 0.2)
		(layers "F.Cu" "B.Cu")
		(net 1)
	)
	(via
		(at 212 124)
		(size 0.45)
		(drill 0.2)
		(layers "F.Cu" "B.Cu")
		(net 1)
	)
	(via
		(at 188.500001 130.500001)
		(size 0.45)
		(drill 0.2)
		(layers "F.Cu" "B.Cu")
		(net 1)
	)
	(via
		(at 268.775 87.775)
		(size 0.45)
		(drill 0.2)
		(layers "F.Cu" "B.Cu")
		(net 1)
	)
	(via
		(at 235.43 121.5)
		(size 0.45)
		(drill 0.2)
		(layers "F.Cu" "B.Cu")
		(net 1)
	)
	(via
		(at 190 73.075)
		(size 0.45)
		(drill 0.2)
		(layers "F.Cu" "B.Cu")
		(net 1)
	)
	(via
		(at 235.61 70.7)
		(size 0.45)
		(drill 0.2)
		(layers "F.Cu" "B.Cu")
		(net 1)
	)
	(via
		(at 243.525 132.325)
		(size 0.45)
		(drill 0.2)
		(layers "F.Cu" "B.Cu")
		(net 1)
	)
	(via
		(at 192.45 90.01)
		(size 0.45)
		(drill 0.2)
		(layers "F.Cu" "B.Cu")
		(net 1)
	)
	(via
		(at 164.540001 112.350001)
		(size 0.45)
		(drill 0.2)
		(layers "F.Cu" "B.Cu")
		(net 1)
	)
	(via
		(at 163.270001 92.030001)
		(size 0.45)
		(drill 0.2)
		(layers "F.Cu" "B.Cu")
		(net 1)
	)
	(via
		(at 155.8 156.3)
		(size 0.45)
		(drill 0.2)
		(layers "F.Cu" "B.Cu")
		(free yes)
		(net 1)
	)
	(via
		(at 235.45 114.7)
		(size 0.45)
		(drill 0.2)
		(layers "F.Cu" "B.Cu")
		(net 1)
	)
	(via
		(at 262.5 150.1)
		(size 0.45)
		(drill 0.2)
		(layers "F.Cu" "B.Cu")
		(net 1)
	)
	(via
		(at 180.2 169.8)
		(size 0.45)
		(drill 0.2)
		(layers "F.Cu" "B.Cu")
		(net 1)
	)
	(via
		(at 160.2 143.75)
		(size 0.45)
		(drill 0.2)
		(layers "F.Cu" "B.Cu")
		(net 1)
	)
	(via
		(at 153.7 146.225)
		(size 0.45)
		(drill 0.2)
		(layers "F.Cu" "B.Cu")
		(net 1)
	)
	(via
		(at 154.380001 114.890001)
		(size 0.45)
		(drill 0.2)
		(layers "F.Cu" "B.Cu")
		(net 1)
	)
	(via
		(at 240.61 70.7)
		(size 0.45)
		(drill 0.2)
		(layers "F.Cu" "B.Cu")
		(net 1)
	)
	(via
		(at 203 117)
		(size 0.45)
		(drill 0.2)
		(layers "F.Cu" "B.Cu")
		(net 1)
	)
	(via
		(at 213.19 170.88)
		(size 0.45)
		(drill 0.2)
		(layers "F.Cu" "B.Cu")
		(net 1)
	)
	(via
		(at 209 125)
		(size 0.45)
		(drill 0.2)
		(layers "F.Cu" "B.Cu")
		(net 1)
	)
	(via
		(at 210.25 172.22)
		(size 0.45)
		(drill 0.2)
		(layers "F.Cu" "B.Cu")
		(net 1)
	)
	(via
		(at 216.13 170.88)
		(size 0.45)
		(drill 0.2)
		(layers "F.Cu" "B.Cu")
		(net 1)
	)
	(via
		(at 191.325 175.675)
		(size 0.45)
		(drill 0.2)
		(layers "F.Cu" "B.Cu")
		(net 1)
	)
	(via
		(at 257.3 106.1)
		(size 0.45)
		(drill 0.2)
		(layers "F.Cu" "B.Cu")
		(free yes)
		(net 1)
	)
	(via
		(at 162.000001 104.730001)
		(size 0.45)
		(drill 0.2)
		(layers "F.Cu" "B.Cu")
		(net 1)
	)
	(via
		(at 152.5 146.675)
		(size 0.45)
		(drill 0.2)
		(layers "F.Cu" "B.Cu")
		(net 1)
	)
	(via
		(at 193.7 175.2)
		(size 0.45)
		(drill 0.2)
		(layers "F.Cu" "B.Cu")
		(net 1)
	)
	(via
		(at 168.350001 84.410001)
		(size 0.45)
		(drill 0.2)
		(layers "F.Cu" "B.Cu")
		(net 1)
	)
	(via
		(at 198 125)
		(size 0.45)
		(drill 0.2)
		(layers "F.Cu" "B.Cu")
		(net 1)
	)
	(via
		(at 259.7 184.5)
		(size 0.45)
		(drill 0.2)
		(layers "F.Cu" "B.Cu")
		(net 1)
	)
	(via
		(at 217.6 118.1)
		(size 0.45)
		(drill 0.2)
		(layers "F.Cu" "B.Cu")
		(net 1)
	)
	(via
		(at 229.325 137.825)
		(size 0.45)
		(drill 0.2)
		(layers "F.Cu" "B.Cu")
		(net 1)
	)
	(via
		(at 194 131)
		(size 0.45)
		(drill 0.2)
		(layers "F.Cu" "B.Cu")
		(net 1)
	)
	(via
		(at 150.67 145.59)
		(size 0.45)
		(drill 0.2)
		(layers "F.Cu" "B.Cu")
		(net 1)
	)
	(via
		(at 175.56 170.23)
		(size 0.45)
		(drill 0.2)
		(layers "F.Cu" "B.Cu")
		(net 1)
	)
	(via
		(at 164.540001 89.490001)
		(size 0.45)
		(drill 0.2)
		(layers "F.Cu" "B.Cu")
		(net 1)
	)
	(via
		(at 169.620001 130.130001)
		(size 0.45)
		(drill 0.2)
		(layers "F.Cu" "B.Cu")
		(net 1)
	)
	(via
		(at 160.730001 97.110001)
		(size 0.45)
		(drill 0.2)
		(layers "F.Cu" "B.Cu")
		(net 1)
	)
	(via
		(at 269.34 95.73)
		(size 0.45)
		(drill 0.2)
		(layers "F.Cu" "B.Cu")
		(net 1)
	)
	(via
		(at 185.500001 119.500001)
		(size 0.45)
		(drill 0.2)
		(layers "F.Cu" "B.Cu")
		(net 1)
	)
	(via
		(at 250.6 101.1)
		(size 0.45)
		(drill 0.2)
		(layers "F.Cu" "B.Cu")
		(net 1)
	)
	(via
		(at 188.500001 128.500001)
		(size 0.45)
		(drill 0.2)
		(layers "F.Cu" "B.Cu")
		(net 1)
	)
	(via
		(at 264.75 78.7)
		(size 0.45)
		(drill 0.2)
		(layers "F.Cu" "B.Cu")
		(net 1)
	)
	(via
		(at 155 171.7)
		(size 0.45)
		(drill 0.2)
		(layers "F.Cu" "B.Cu")
		(net 1)
	)
	(via
		(at 187.25 160.25)
		(size 0.45)
		(drill 0.2)
		(layers "F.Cu" "B.Cu")
		(free yes)
		(net 1)
	)
	(via
		(at 173.999999 141.834316)
		(size 0.45)
		(drill 0.2)
		(layers "F.Cu" "B.Cu")
		(net 1)
	)
	(via
		(at 150.71 70.67)
		(size 0.45)
		(drill 0.2)
		(layers "F.Cu" "B.Cu")
		(net 1)
	)
	(via
		(at 151.625 156.225)
		(size 0.45)
		(drill 0.2)
		(layers "F.Cu" "B.Cu")
		(net 1)
	)
	(via
		(at 192.5 124.5)
		(size 0.45)
		(drill 0.2)
		(layers "F.Cu" "B.Cu")
		(net 1)
	)
	(via
		(at 160.730001 125.050001)
		(size 0.45)
		(drill 0.2)
		(layers "F.Cu" "B.Cu")
		(net 1)
	)
	(via
		(at 196.75 175.2)
		(size 0.45)
		(drill 0.2)
		(layers "F.Cu" "B.Cu")
		(net 1)
	)
	(via
		(at 170.890001 130.130001)
		(size 0.45)
		(drill 0.2)
		(layers "F.Cu" "B.Cu")
		(net 1)
	)
	(via
		(at 150.66 175.64)
		(size 0.45)
		(drill 0.2)
		(layers "F.Cu" "B.Cu")
		(net 1)
	)
	(via
		(at 159.460001 84.410001)
		(size 0.45)
		(drill 0.2)
		(layers "F.Cu" "B.Cu")
		(net 1)
	)
	(via
		(at 158.9 143.1)
		(size 0.45)
		(drill 0.2)
		(layers "F.Cu" "B.Cu")
		(net 1)
	)
	(via
		(at 163.3 171.8)
		(size 0.45)
		(drill 0.2)
		(layers "F.Cu" "B.Cu")
		(net 1)
	)
	(via
		(at 196 126)
		(size 0.45)
		(drill 0.2)
		(layers "F.Cu" "B.Cu")
		(net 1)
	)
	(via
		(at 162.000001 84.410001)
		(size 0.45)
		(drill 0.2)
		(layers "F.Cu" "B.Cu")
		(net 1)
	)
	(via
		(at 208 130)
		(size 0.45)
		(drill 0.2)
		(layers "F.Cu" "B.Cu")
		(net 1)
	)
	(via
		(at 169.25 165.32)
		(size 0.45)
		(drill 0.2)
		(layers "F.Cu" "B.Cu")
		(net 1)
	)
	(via
		(at 194 123)
		(size 0.45)
		(drill 0.2)
		(layers "F.Cu" "B.Cu")
		(net 1)
	)
	(via
		(at 155.650001 107.270001)
		(size 0.45)
		(drill 0.2)
		(layers "F.Cu" "B.Cu")
		(net 1)
	)
	(via
		(at 160.730001 81.870001)
		(size 0.45)
		(drill 0.2)
		(layers "F.Cu" "B.Cu")
		(net 1)
	)
	(via
		(at 264.33 70.68)
		(size 0.45)
		(drill 0.2)
		(layers "F.Cu" "B.Cu")
		(net 1)
	)
	(via
		(at 155.6 155.7)
		(size 0.45)
		(drill 0.2)
		(layers "F.Cu" "B.Cu")
		(free yes)
		(net 1)
	)
	(via
		(at 205.101 72.083)
		(size 0.45)
		(drill 0.2)
		(layers "F.Cu" "B.Cu")
		(net 1)
	)
	(via
		(at 171.75 112.4)
		(size 0.45)
		(drill 0.2)
		(layers "F.Cu" "B.Cu")
		(net 1)
	)
	(via
		(at 164.540001 122.510001)
		(size 0.45)
		(drill 0.2)
		(layers "F.Cu" "B.Cu")
		(net 1)
	)
	(via
		(at 255.7 71.05)
		(size 0.45)
		(drill 0.2)
		(layers "F.Cu" "B.Cu")
		(net 1)
	)
	(via
		(at 190.5 119.5)
		(size 0.45)
		(drill 0.2)
		(layers "F.Cu" "B.Cu")
		(net 1)
	)
	(via
		(at 190 142)
		(size 0.45)
		(drill 0.2)
		(layers "F.Cu" "B.Cu")
		(net 1)
	)
	(via
		(at 156.920001 97.110001)
		(size 0.45)
		(drill 0.2)
		(layers "F.Cu" "B.Cu")
		(net 1)
	)
	(via
		(at 167.080001 119.970001)
		(size 0.45)
		(drill 0.2)
		(layers "F.Cu" "B.Cu")
		(net 1)
	)
	(via
		(at 164.540001 130.130001)
		(size 0.45)
		(drill 0.2)
		(layers "F.Cu" "B.Cu")
		(net 1)
	)
	(via
		(at 168.350001 127.590001)
		(size 0.45)
		(drill 0.2)
		(layers "F.Cu" "B.Cu")
		(net 1)
	)
	(via
		(at 209.78 157.56)
		(size 0.45)
		(drill 0.2)
		(layers "F.Cu" "B.Cu")
		(net 1)
	)
	(via
		(at 203.101 71.283)
		(size 0.45)
		(drill 0.2)
		(layers "F.Cu" "B.Cu")
		(net 1)
	)
	(via
		(at 194 128)
		(size 0.45)
		(drill 0.2)
		(layers "F.Cu" "B.Cu")
		(net 1)
	)
	(via
		(at 204 131)
		(size 0.45)
		(drill 0.2)
		(layers "F.Cu" "B.Cu")
		(net 1)
	)
	(via
		(at 168.25 177.5)
		(size 0.45)
		(drill 0.2)
		(layers "F.Cu" "B.Cu")
		(free yes)
		(net 1)
	)
	(via
		(at 156.25 178.25)
		(size 0.45)
		(drill 0.2)
		(layers "F.Cu" "B.Cu")
		(free yes)
		(net 1)
	)
	(via
		(at 156.75 177.75)
		(size 0.45)
		(drill 0.2)
		(layers "F.Cu" "B.Cu")
		(free yes)
		(net 1)
	)
	(via
		(at 169.620001 122.510001)
		(size 0.45)
		(drill 0.2)
		(layers "F.Cu" "B.Cu")
		(net 1)
	)
	(via
		(at 180 168)
		(size 0.45)
		(drill 0.2)
		(layers "F.Cu" "B.Cu")
		(free yes)
		(net 1)
	)
	(via
		(at 211 130)
		(size 0.45)
		(drill 0.2)
		(layers "F.Cu" "B.Cu")
		(net 1)
	)
	(via
		(at 187.75 159.75)
		(size 0.45)
		(drill 0.2)
		(layers "F.Cu" "B.Cu")
		(free yes)
		(net 1)
	)
	(via
		(at 206 126)
		(size 0.45)
		(drill 0.2)
		(layers "F.Cu" "B.Cu")
		(net 1)
	)
	(via
		(at 255.2 76.1)
		(size 0.45)
		(drill 0.2)
		(layers "F.Cu" "B.Cu")
		(net 1)
	)
	(via
		(at 185.6 189.36)
		(size 0.45)
		(drill 0.2)
		(layers "F.Cu" "B.Cu")
		(net 1)
	)
	(via
		(at 163.270001 112.350001)
		(size 0.45)
		(drill 0.2)
		(layers "F.Cu" "B.Cu")
		(net 1)
	)
	(via
		(at 159.460001 127.590001)
		(size 0.45)
		(drill 0.2)
		(layers "F.Cu" "B.Cu")
		(net 1)
	)
	(via
		(at 184.030001 131.500001)
		(size 0.45)
		(drill 0.2)
		(layers "F.Cu" "B.Cu")
		(net 1)
	)
	(via
		(at 160.730001 109.810001)
		(size 0.45)
		(drill 0.2)
		(layers "F.Cu" "B.Cu")
		(net 1)
	)
	(via
		(at 206.291252 91.85)
		(size 0.45)
		(drill 0.2)
		(layers "F.Cu" "B.Cu")
		(free yes)
		(net 1)
	)
	(via
		(at 167.080001 107.270001)
		(size 0.45)
		(drill 0.2)
		(layers "F.Cu" "B.Cu")
		(net 1)
	)
	(via
		(at 150.67 165.59)
		(size 0.45)
		(drill 0.2)
		(layers "F.Cu" "B.Cu")
		(net 1)
	)
	(via
		(at 205.4955 116.5)
		(size 0.45)
		(drill 0.2)
		(layers "F.Cu" "B.Cu")
		(net 1)
	)
	(via
		(at 258.4 125.9)
		(size 0.45)
		(drill 0.2)
		(layers "F.Cu" "B.Cu")
		(net 1)
	)
	(via
		(at 225.61 70.7)
		(size 0.45)
		(drill 0.2)
		(layers "F.Cu" "B.Cu")
		(net 1)
	)
	(via
		(at 167.080001 112.350001)
		(size 0.45)
		(drill 0.2)
		(layers "F.Cu" "B.Cu")
		(net 1)
	)
	(via
		(at 191.5 135.5)
		(size 0.45)
		(drill 0.2)
		(layers "F.Cu" "B.Cu")
		(net 1)
	)
	(via
		(at 241.5 118.15)
		(size 0.45)
		(drill 0.2)
		(layers "F.Cu" "B.Cu")
		(net 1)
	)
	(via
		(at 250.61 70.7)
		(size 0.45)
		(drill 0.2)
		(layers "F.Cu" "B.Cu")
		(net 1)
	)
	(via
		(at 195.125 185.675)
		(size 0.45)
		(drill 0.2)
		(layers "F.Cu" "B.Cu")
		(net 1)
	)
	(via
		(at 248.65 131.35)
		(size 0.45)
		(drill 0.2)
		(layers "F.Cu" "B.Cu")
		(net 1)
	)
	(via
		(at 244.6 127.8)
		(size 0.45)
		(drill 0.2)
		(layers "F.Cu" "B.Cu")
		(net 1)
	)
	(via
		(at 178.890217 88.274785)
		(size 0.45)
		(drill 0.2)
		(layers "F.Cu" "B.Cu")
		(net 1)
	)
	(via
		(at 159.460001 92.030001)
		(size 0.45)
		(drill 0.2)
		(layers "F.Cu" "B.Cu")
		(net 1)
	)
	(via
		(at 213.19 174.9)
		(size 0.45)
		(drill 0.2)
		(layers "F.Cu" "B.Cu")
		(net 1)
	)
	(via
		(at 255.025 135.85)
		(size 0.45)
		(drill 0.2)
		(layers "F.Cu" "B.Cu")
		(net 1)
	)
	(via
		(at 225.775 116.75)
		(size 0.45)
		(drill 0.2)
		(layers "F.Cu" "B.Cu")
		(net 1)
	)
	(via
		(at 163.270001 99.650001)
		(size 0.45)
		(drill 0.2)
		(layers "F.Cu" "B.Cu")
		(net 1)
	)
	(via
		(at 230.2 155.5)
		(size 0.45)
		(drill 0.2)
		(layers "F.Cu" "B.Cu")
		(net 1)
	)
	(via
		(at 166.31 168)
		(size 0.45)
		(drill 0.2)
		(layers "F.Cu" "B.Cu")
		(net 1)
	)
	(via
		(at 196.95 86.33)
		(size 0.45)
		(drill 0.2)
		(layers "F.Cu" "B.Cu")
		(net 1)
	)
	(via
		(at 261.7 71.05)
		(size 0.45)
		(drill 0.2)
		(layers "F.Cu" "B.Cu")
		(net 1)
	)
	(via
		(at 158.6 163.2)
		(size 0.45)
		(drill 0.2)
		(layers "F.Cu" "B.Cu")
		(net 1)
	)
	(via
		(at 165.810001 84.410001)
		(size 0.45)
		(drill 0.2)
		(layers "F.Cu" "B.Cu")
		(net 1)
	)
	(via
		(at 197 134)
		(size 0.45)
		(drill 0.2)
		(layers "F.Cu" "B.Cu")
		(net 1)
	)
	(via
		(at 175.05 172.0125)
		(size 0.45)
		(drill 0.2)
		(layers "F.Cu" "B.Cu")
		(net 1)
	)
	(via
		(at 158.190001 112.350001)
		(size 0.45)
		(drill 0.2)
		(layers "F.Cu" "B.Cu")
		(net 1)
	)
	(via
		(at 172 106.675)
		(size 0.45)
		(drill 0.2)
		(layers "F.Cu" "B.Cu")
		(net 1)
	)
	(via
		(at 155.650001 84.410001)
		(size 0.45)
		(drill 0.2)
		(layers "F.Cu" "B.Cu")
		(net 1)
	)
	(via
		(at 163 167.4)
		(size 0.45)
		(drill 0.2)
		(layers "F.Cu" "B.Cu")
		(net 1)
	)
	(via
		(at 171.175237 94.049265)
		(size 0.45)
		(drill 0.2)
		(layers "F.Cu" "B.Cu")
		(net 1)
	)
	(via
		(at 253.7 109.3)
		(size 0.45)
		(drill 0.2)
		(layers "F.Cu" "B.Cu")
		(free yes)
		(net 1)
	)
	(via
		(at 269.36 105.63)
		(size 0.45)
		(drill 0.2)
		(layers "F.Cu" "B.Cu")
		(net 1)
	)
	(via
		(at 199 127)
		(size 0.45)
		(drill 0.2)
		(layers "F.Cu" "B.Cu")
		(net 1)
	)
	(via
		(at 219.07 174.9)
		(size 0.45)
		(drill 0.2)
		(layers "F.Cu" "B.Cu")
		(net 1)
	)
	(via
		(at 192.5 122.5)
		(size 0.45)
		(drill 0.2)
		(layers "F.Cu" "B.Cu")
		(net 1)
	)
	(via
		(at 256.845 134.285)
		(size 0.45)
		(drill 0.2)
		(layers "F.Cu" "B.Cu")
		(net 1)
	)
	(via
		(at 190.49 113.14)
		(size 0.45)
		(drill 0.2)
		(layers "F.Cu" "B.Cu")
		(net 1)
	)
	(via
		(at 192.5 134.48)
		(size 0.45)
		(drill 0.2)
		(layers "F.Cu" "B.Cu")
		(net 1)
	)
	(via
		(at 150.67 100.59)
		(size 0.45)
		(drill 0.2)
		(layers "F.Cu" "B.Cu")
		(net 1)
	)
	(via
		(at 221.9 153.6)
		(size 0.45)
		(drill 0.2)
		(layers "F.Cu" "B.Cu")
		(free yes)
		(net 1)
	)
	(via
		(at 241.3 93.3)
		(size 0.45)
		(drill 0.2)
		(layers "F.Cu" "B.Cu")
		(net 1)
	)
	(via
		(at 183.800001 132.500001)
		(size 0.45)
		(drill 0.2)
		(layers "F.Cu" "B.Cu")
		(net 1)
	)
	(via
		(at 204.101 71.283)
		(size 0.45)
		(drill 0.2)
		(layers "F.Cu" "B.Cu")
		(net 1)
	)
	(via
		(at 186.500001 133.500001)
		(size 0.45)
		(drill 0.2)
		(layers "F.Cu" "B.Cu")
		(net 1)
	)
	(via
		(at 162.000001 109.810001)
		(size 0.45)
		(drill 0.2)
		(layers "F.Cu" "B.Cu")
		(net 1)
	)
	(via
		(at 197 132)
		(size 0.45)
		(drill 0.2)
		(layers "F.Cu" "B.Cu")
		(net 1)
	)
	(via
		(at 169.620001 112.350001)
		(size 0.45)
		(drill 0.2)
		(layers "F.Cu" "B.Cu")
		(net 1)
	)
	(via
		(at 168.350001 104.730001)
		(size 0.45)
		(drill 0.2)
		(layers "F.Cu" "B.Cu")
		(net 1)
	)
	(via
		(at 193 133)
		(size 0.45)
		(drill 0.2)
		(layers "F.Cu" "B.Cu")
		(net 1)
	)
	(via
		(at 155.2 168)
		(size 0.45)
		(drill 0.2)
		(layers "F.Cu" "B.Cu")
		(net 1)
	)
	(via
		(at 160.730001 99.650001)
		(size 0.45)
		(drill 0.2)
		(layers "F.Cu" "B.Cu")
		(net 1)
	)
	(via
		(at 261 123.65)
		(size 0.45)
		(drill 0.2)
		(layers "F.Cu" "B.Cu")
		(net 1)
	)
	(via
		(at 171.770191 104.750001)
		(size 0.45)
		(drill 0.2)
		(layers "F.Cu" "B.Cu")
		(net 1)
	)
	(via
		(at 176.5 166.5)
		(size 0.45)
		(drill 0.2)
		(layers "F.Cu" "B.Cu")
		(net 1)
	)
	(via
		(at 269.23 75.77)
		(size 0.45)
		(drill 0.2)
		(layers "F.Cu" "B.Cu")
		(net 1)
	)
	(via
		(at 173.6 147.6)
		(size 0.45)
		(drill 0.2)
		(layers "F.Cu" "B.Cu")
		(net 1)
	)
	(via
		(at 210.61 70.7)
		(size 0.45)
		(drill 0.2)
		(layers "F.Cu" "B.Cu")
		(net 1)
	)
	(via
		(at 184.15 144.999999)
		(size 0.45)
		(drill 0.2)
		(layers "F.Cu" "B.Cu")
		(net 1)
	)
	(via
		(at 155.650001 81.870001)
		(size 0.45)
		(drill 0.2)
		(layers "F.Cu" "B.Cu")
		(net 1)
	)
	(via
		(at 163.270001 89.490001)
		(size 0.45)
		(drill 0.2)
		(layers "F.Cu" "B.Cu")
		(net 1)
	)
	(via
		(at 184.425 86.625)
		(size 0.45)
		(drill 0.2)
		(layers "F.Cu" "B.Cu")
		(net 1)
	)
	(via
		(at 167.080001 102.190001)
		(size 0.45)
		(drill 0.2)
		(layers "F.Cu" "B.Cu")
		(net 1)
	)
	(via
		(at 224.7 92.75)
		(size 0.45)
		(drill 0.2)
		(layers "F.Cu" "B.Cu")
		(net 1)
	)
	(via
		(at 257.365 138.135)
		(size 0.45)
		(drill 0.2)
		(layers "F.Cu" "B.Cu")
		(net 1)
	)
	(via
		(at 187.500001 134.500001)
		(size 0.45)
		(drill 0.2)
		(layers "F.Cu" "B.Cu")
		(net 1)
	)
	(via
		(at 207.552499 91.1)
		(size 0.45)
		(drill 0.2)
		(layers "F.Cu" "B.Cu")
		(net 1)
	)
	(via
		(at 168.350001 107.270001)
		(size 0.45)
		(drill 0.2)
		(layers "F.Cu" "B.Cu")
		(net 1)
	)
	(via
		(at 170.4 143.6)
		(size 0.45)
		(drill 0.2)
		(layers "F.Cu" "B.Cu")
		(net 1)
	)
	(via
		(at 159.8 154.7)
		(size 0.45)
		(drill 0.2)
		(layers "F.Cu" "B.Cu")
		(free yes)
		(net 1)
	)
	(via
		(at 202 135)
		(size 0.45)
		(drill 0.2)
		(layers "F.Cu" "B.Cu")
		(net 1)
	)
	(via
		(at 175.77 188.64)
		(size 0.45)
		(drill 0.2)
		(layers "F.Cu" "B.Cu")
		(net 1)
	)
	(via
		(at 163.270001 119.970001)
		(size 0.45)
		(drill 0.2)
		(layers "F.Cu" "B.Cu")
		(net 1)
	)
	(via
		(at 151.2 146.165)
		(size 0.45)
		(drill 0.2)
		(layers "F.Cu" "B.Cu")
		(net 1)
	)
	(via
		(at 171.175237 92.550736)
		(size 0.45)
		(drill 0.2)
		(layers "F.Cu" "B.Cu")
		(net 1)
	)
	(via
		(at 160.730001 89.490001)
		(size 0.45)
		(drill 0.2)
		(layers "F.Cu" "B.Cu")
		(net 1)
	)
	(via
		(at 211 142)
		(size 0.45)
		(drill 0.2)
		(layers "F.Cu" "B.Cu")
		(net 1)
	)
	(via
		(at 165.6 189.36)
		(size 0.45)
		(drill 0.2)
		(layers "F.Cu" "B.Cu")
		(net 1)
	)
	(via
		(at 155.2 166.8)
		(size 0.45)
		(drill 0.2)
		(layers "F.Cu" "B.Cu")
		(net 1)
	)
	(via
		(at 160.730001 84.410001)
		(size 0.45)
		(drill 0.2)
		(layers "F.Cu" "B.Cu")
		(net 1)
	)
	(via
		(at 269.32 180.59)
		(size 0.45)
		(drill 0.2)
		(layers "F.Cu" "B.Cu")
		(net 1)
	)
	(via
		(at 159.460001 86.950001)
		(size 0.45)
		(drill 0.2)
		(layers "F.Cu" "B.Cu")
		(net 1)
	)
	(via
		(at 269.36 100.63)
		(size 0.45)
		(drill 0.2)
		(layers "F.Cu" "B.Cu")
		(net 1)
	)
	(via
		(at 264 181)
		(size 0.45)
		(drill 0.2)
		(layers "F.Cu" "B.Cu")
		(net 1)
	)
	(via
		(at 186.500001 131.500001)
		(size 0.45)
		(drill 0.2)
		(layers "F.Cu" "B.Cu")
		(net 1)
	)
	(via
		(at 170.2 151.425)
		(size 0.45)
		(drill 0.2)
		(layers "F.Cu" "B.Cu")
		(net 1)
	)
	(via
		(at 220.4 146.2)
		(size 0.45)
		(drill 0.2)
		(layers "F.Cu" "B.Cu")
		(net 1)
	)
	(via
		(at 230.7 160.4)
		(size 0.45)
		(drill 0.2)
		(layers "F.Cu" "B.Cu")
		(net 1)
	)
	(via
		(at 150.67 80.59)
		(size 0.45)
		(drill 0.2)
		(layers "F.Cu" "B.Cu")
		(net 1)
	)
	(via
		(at 258.4 84.285)
		(size 0.45)
		(drill 0.2)
		(layers "F.Cu" "B.Cu")
		(net 1)
	)
	(via
		(at 155.650001 130.130001)
		(size 0.45)
		(drill 0.2)
		(layers "F.Cu" "B.Cu")
		(net 1)
	)
	(via
		(at 162.000001 102.190001)
		(size 0.45)
		(drill 0.2)
		(layers "F.Cu" "B.Cu")
		(net 1)
	)
	(via
		(at 175.6 171.41)
		(size 0.45)
		(drill 0.2)
		(layers "F.Cu" "B.Cu")
		(net 1)
	)
	(via
		(at 257.272367 103.167361)
		(size 0.45)
		(drill 0.2)
		(layers "F.Cu" "B.Cu")
		(free yes)
		(net 1)
	)
	(via
		(at 208 143)
		(size 0.45)
		(drill 0.2)
		(layers "F.Cu" "B.Cu")
		(net 1)
	)
	(via
		(at 168.350001 97.110001)
		(size 0.45)
		(drill 0.2)
		(layers "F.Cu" "B.Cu")
		(net 1)
	)
	(via
		(at 213 138)
		(size 0.45)
		(drill 0.2)
		(layers "F.Cu" "B.Cu")
		(net 1)
	)
	(via
		(at 194.375 175.2)
		(size 0.45)
		(drill 0.2)
		(layers "F.Cu" "B.Cu")
		(net 1)
	)
	(via
		(at 269.32 170.59)
		(size 0.45)
		(drill 0.2)
		(layers "F.Cu" "B.Cu")
		(net 1)
	)
	(via
		(at 259.6 136)
		(size 0.45)
		(drill 0.2)
		(layers "F.Cu" "B.Cu")
		(net 1)
	)
	(via
		(at 200 118)
		(size 0.45)
		(drill 0.2)
		(layers "F.Cu" "B.Cu")
		(free yes)
		(net 1)
	)
	(via
		(at 167.080001 122.510001)
		(size 0.45)
		(drill 0.2)
		(layers "F.Cu" "B.Cu")
		(net 1)
	)
	(via
		(at 238.375 139.6)
		(size 0.45)
		(drill 0.2)
		(layers "F.Cu" "B.Cu")
		(net 1)
	)
	(via
		(at 172.05 169.2125)
		(size 0.45)
		(drill 0.2)
		(layers "F.Cu" "B.Cu")
		(net 1)
	)
	(via
		(at 162.25 150.75)
		(size 0.45)
		(drill 0.2)
		(layers "F.Cu" "B.Cu")
		(net 1)
	)
	(via
		(at 196.2 70.7)
		(size 0.45)
		(drill 0.2)
		(layers "F.Cu" "B.Cu")
		(net 1)
	)
	(via
		(at 220.25 130.65)
		(size 0.45)
		(drill 0.2)
		(layers "F.Cu" "B.Cu")
		(net 1)
	)
	(via
		(at 172.800001 103.720191)
		(size 0.45)
		(drill 0.2)
		(layers "F.Cu" "B.Cu")
		(net 1)
	)
	(via
		(at 186.475 125.5)
		(size 0.45)
		(drill 0.2)
		(layers "F.Cu" "B.Cu")
		(net 1)
	)
	(via
		(at 215 123)
		(size 0.45)
		(drill 0.2)
		(layers "F.Cu" "B.Cu")
		(net 1)
	)
	(via
		(at 257.7 71.025)
		(size 0.45)
		(drill 0.2)
		(layers "F.Cu" "B.Cu")
		(net 1)
	)
	(via
		(at 169.25 169.34)
		(size 0.45)
		(drill 0.2)
		(layers "F.Cu" "B.Cu")
		(net 1)
	)
	(via
		(at 190.5 127.5)
		(size 0.45)
		(drill 0.2)
		(layers "F.Cu" "B.Cu")
		(net 1)
	)
	(via
		(at 229.4 150.6)
		(size 0.45)
		(drill 0.2)
		(layers "F.Cu" "B.Cu")
		(net 1)
	)
	(via
		(at 226 131.2)
		(size 0.45)
		(drill 0.2)
		(layers "F.Cu" "B.Cu")
		(net 1)
	)
	(via
		(at 158.190001 109.810001)
		(size 0.45)
		(drill 0.2)
		(layers "F.Cu" "B.Cu")
		(net 1)
	)
	(via
		(at 262.8 149.2)
		(size 0.45)
		(drill 0.2)
		(layers "F.Cu" "B.Cu")
		(net 1)
	)
	(via
		(at 181.1 143.1)
		(size 0.45)
		(drill 0.2)
		(layers "F.Cu" "B.Cu")
		(net 1)
	)
	(via
		(at 221.7 155.6)
		(size 0.45)
		(drill 0.2)
		(layers "F.Cu" "B.Cu")
		(net 1)
	)
	(segment
		(start 186.985 187.5)
		(end 187.43 187.5)
		(width 0.4)
		(layer "B.Cu")
		(net 1)
	)
	(segment
		(start 214.64 116.4)
		(end 214.565 116.475)
		(width 0.4)
		(layer "B.Cu")
		(net 1)
	)
	(segment
		(start 244.2 158)
		(end 244.2 158.297)
		(width 0.4)
		(layer "B.Cu")
		(net 1)
	)
	(segment
		(start 252 160.6)
		(end 252 160)
		(width 0.256)
		(layer "B.Cu")
		(net 1)
	)
	(segment
		(start 211.5 120.5)
		(end 211 121)
		(width 0.4)
		(layer "B.Cu")
		(net 1)
	)
	(segment
		(start 199.376252 95.95)
		(end 199.376252 96.08)
		(width 0.177)
		(layer "B.Cu")
		(net 1)
	)
	(segment
		(start 194.5 116.5)
		(end 195 116)
		(width 0.4)
		(layer "B.Cu")
		(net 1)
	)
	(segment
		(start 220.052 150)
		(end 221.2 150)
		(width 0.1)
		(layer "B.Cu")
		(net 1)
	)
	(segment
		(start 258.75 123.4875)
		(end 258.75 123.9)
		(width 0.4)
		(layer "B.Cu")
		(net 1)
	)
	(segment
		(start 203.27 126)
		(end 203 126)
		(width 0.4)
		(layer "B.Cu")
		(net 1)
	)
	(segment
		(start 213.525 116.475)
		(end 213 117)
		(width 0.4)
		(layer "B.Cu")
		(net 1)
	)
	(segment
		(start 218.175 137.775)
		(end 217.8 137.4)
		(width 0.4)
		(layer "B.Cu")
		(net 1)
	)
	(segment
		(start 259.195 75.025)
		(end 259.195 75.795)
		(width 0.1)
		(layer "B.Cu")
		(net 1)
	)
	(segment
		(start 165.810001 125.050001)
		(end 165.810001 125.250001)
		(width 0.201)
		(layer "B.Cu")
		(net 1)
	)
	(segment
		(start 190.12 123.5)
		(end 190.5 123.5)
		(width 0.4)
		(layer "B.Cu")
		(net 1)
	)
	(segment
		(start 219.268 149.216)
		(end 220.052 150)
		(width 0.1)
		(layer "B.Cu")
		(net 1)
	)
	(segment
		(start 194.425 147.25)
		(end 194.31 147.25)
		(width 0.4)
		(layer "B.Cu")
		(net 1)
	)
	(segment
		(start 199.7 95.95)
		(end 200.376252 95.95)
		(width 0.177)
		(layer "B.Cu")
		(net 1)
	)
	(segment
		(start 253.775 130.775)
		(end 254.075 131.075)
		(width 0.4)
		(layer "B.Cu")
		(net 1)
	)
	(segment
		(start 252.51 112.61)
		(end 252.2 112.3)
		(width 0.201)
		(layer "B.Cu")
		(net 1)
	)
	(segment
		(start 194.31 147.25)
		(end 193.91 146.85)
		(width 0.4)
		(layer "B.Cu")
		(net 1)
	)
	(segment
		(start 208.5 124.5)
		(end 209 125)
		(width 0.4)
		(layer "B.Cu")
		(net 1)
	)
	(segment
		(start 190.5 115.5)
		(end 190.773726 115.773726)
		(width 0.4)
		(layer "B.Cu")
		(net 1)
	)
	(segment
		(start 202.65 128.18)
		(end 202.83 128)
		(width 0.4)
		(layer "B.Cu")
		(net 1)
	)
	(segment
		(start 202.83 126)
		(end 203 126)
		(width 0.4)
		(layer "B.Cu")
		(net 1)
	)
	(segment
		(start 203.45 126.18)
		(end 203.27 126)
		(width 0.4)
		(layer "B.Cu")
		(net 1)
	)
	(segment
		(start 201.82 127.25)
		(end 201.82 127.18)
		(width 0.4)
		(layer "B.Cu")
		(net 1)
	)
	(segment
		(start 191.5 145.1)
		(end 191.5 144.32)
		(width 0.256)
		(layer "B.Cu")
		(net 1)
	)
	(segment
		(start 191.49 136.14)
		(end 191.49 135.51)
		(width 0.4)
		(layer "B.Cu")
		(net 1)
	)
	(segment
		(start 202 129.075)
		(end 202 129)
		(width 0.4)
		(layer "B.Cu")
		(net 1)
	)
	(segment
		(start 253.75 110.685)
		(end 253.75 111.25)
		(width 0.182)
		(layer "B.Cu")
		(net 1)
	)
	(segment
		(start 192.5 141.5)
		(end 192.975 141.025)
		(width 0.4)
		(layer "B.Cu")
		(net 1)
	)
	(segment
		(start 201.82 134.45)
		(end 201.82 134.18)
		(width 0.4)
		(layer "B.Cu")
		(net 1)
	)
	(segment
		(start 237.9525 112.3275)
		(end 238.0045 112.2755)
		(width 0.182)
		(layer "B.Cu")
		(net 1)
	)
	(segment
		(start 218.175 134.825)
		(end 217.8 135.2)
		(width 0.4)
		(layer "B.Cu")
		(net 1)
	)
	(segment
		(start 252 160)
		(end 252.5 160.5)
		(width 0.256)
		(layer "B.Cu")
		(net 1)
	)
	(segment
		(start 202.226967 93.185)
		(end 202.2 93.185)
		(width 0.182)
		(layer "B.Cu")
		(net 1)
	)
	(segment
		(start 203.27 128)
		(end 203 128)
		(width 0.4)
		(layer "B.Cu")
		(net 1)
	)
	(segment
		(start 195.206252 97.85)
		(end 194.591252 97.85)
		(width 0.182)
		(layer "B.Cu")
		(net 1)
	)
	(segment
		(start 199.7 147.7)
		(end 199 147)
		(width 0.4)
		(layer "B.Cu")
		(net 1)
	)
	(segment
		(start 263.985 181.015)
		(end 264 181)
		(width 0.4)
		(layer "B.Cu")
		(net 1)
	)
	(segment
		(start 202.93 131)
		(end 203 131)
		(width 0.4)
		(layer "B.Cu")
		(net 1)
	)
	(segment
		(start 161.534 128.8)
		(end 161 128.8)
		(width 0.4)
		(layer "B.Cu")
		(net 1)
	)
	(segment
		(start 154.09 140.95)
		(end 154.1 140.96)
		(width 0.4)
		(layer "B.Cu")
		(net 1)
	)
	(segment
		(start 197.5 122.5)
		(end 197 122)
		(width 0.4)
		(layer "B.Cu")
		(net 1)
	)
	(segment
		(start 186.55 182)
		(end 186.7 181.85)
		(width 0.4)
		(layer "B.Cu")
		(net 1)
	)
	(segment
		(start 213.55 128.73)
		(end 213.55 130)
		(width 0.182)
		(layer "B.Cu")
		(net 1)
	)
	(segment
		(start 226.615 155.2)
		(end 226 155.2)
		(width 0.201)
		(layer "B.Cu")
		(net 1)
	)
	(segment
		(start 198.39 147.25)
		(end 199 146.64)
		(width 0.4)
		(layer "B.Cu")
		(net 1)
	)
	(segment
		(start 171.999999 148.499999)
		(end 171.699999 148.499999)
		(width 0.4)
		(layer "B.Cu")
		(net 1)
	)
	(segment
		(start 188 144)
		(end 188.5 144.5)
		(width 0.4)
		(layer "B.Cu")
		(net 1)
	)
	(segment
		(start 225.7 149.628)
		(end 225.7 149.7)
		(width 0.1)
		(layer "B.Cu")
		(net 1)
	)
	(segment
		(start 216.1 124.3)
		(end 216.3 124.5)
		(width 0.4)
		(layer "B.Cu")
		(net 1)
	)
	(segment
		(start 197.5 124.5)
		(end 198 125)
		(width 0.4)
		(layer "B.Cu")
		(net 1)
	)
	(segment
		(start 201.18 131.18)
		(end 201 131)
		(width 0.4)
		(layer "B.Cu")
		(net 1)
	)
	(segment
		(start 186.55 183.45)
		(end 186.55 182)
		(width 0.4)
		(layer "B.Cu")
		(net 1)
	)
	(segment
		(start 212.5 126.5)
		(end 213 127)
		(width 0.4)
		(layer "B.Cu")
		(net 1)
	)
	(segment
		(start 165.810001 125.250001)
		(end 166.245001 125.685001)
		(width 0.201)
		(layer "B.Cu")
		(net 1)
	)
	(segment
		(start 198.5 117.5)
		(end 199 118)
		(width 0.4)
		(layer "B.Cu")
		(net 1)
	)
	(segment
		(start 182.7 142.2)
		(end 182.6 142.2)
		(width 0.4)
		(layer "B.Cu")
		(net 1)
	)
	(segment
		(start 204.5 123.5)
		(end 205 123)
		(width 0.4)
		(layer "B.Cu")
		(net 1)
	)
	(segment
		(start 217.7 111.8)
		(end 217.95 111.55)
		(width 0.4)
		(layer "B.Cu")
		(net 1)
	)
	(segment
		(start 255.2 75.025)
		(end 255.2 75.795)
		(width 0.1)
		(layer "B.Cu")
		(net 1)
	)
	(segment
		(start 202.5 116.5)
		(end 203 117)
		(width 0.4)
		(layer "B.Cu")
		(net 1)
	)
	(segment
		(start 203.32 130.45)
		(end 203.32 130.68)
		(width 0.4)
		(layer "B.Cu")
		(net 1)
	)
	(segment
		(start 264.915 173)
		(end 264.915 171.815)
		(width 0.256)
		(layer "B.Cu")
		(net 1)
	)
	(segment
		(start 203.45 128.18)
		(end 203.27 128)
		(width 0.4)
		(layer "B.Cu")
		(net 1)
	)
	(segment
		(start 216.443553 128.863553)
		(end 217.003553 128.863553)
		(width 0.4)
		(layer "B.Cu")
		(net 1)
	)
	(segment
		(start 220.44 137.775)
		(end 218.175 137.775)
		(width 0.4)
		(layer "B.Cu")
		(net 1)
	)
	(segment
		(start 260.55 124.55)
		(end 261 124.1)
		(width 0.4)
		(layer "B.Cu")
		(net 1)
	)
	(segment
		(start 198.976252 91.55)
		(end 198.976252 95.55)
		(width 0.177)
		(layer "B.Cu")
		(net 1)
	)
	(segment
		(start 229.485 155.2)
		(end 229.9 155.2)
		(width 0.201)
		(layer "B.Cu")
		(net 1)
	)
	(segment
		(start 205.5 133.5)
		(end 205 134)
		(width 0.4)
		(layer "B.Cu")
		(net 1)
	)
	(segment
		(start 208.5 121.5)
		(end 208 122)
		(width 0.4)
		(layer "B.Cu")
		(net 1)
	)
	(segment
		(start 256.85 160.365)
		(end 256.1 161.115)
		(width 0.256)
		(layer "B.Cu")
		(net 1)
	)
	(segment
		(start 223.5975 82.6895)
		(end 223.5975 79.4175)
		(width 0.256)
		(layer "B.Cu")
		(net 1)
	)
	(segment
		(start 190.973726 127.973726)
		(end 190.5 127.5)
		(width 0.4)
		(layer "B.Cu")
		(net 1)
	)
	(segment
		(start 201.18 130.82)
		(end 201 131)
		(width 0.4)
		(layer "B.Cu")
		(net 1)
	)
	(segment
		(start 210.5 117.5)
		(end 210 118)
		(width 0.4)
		(layer "B.Cu")
		(net 1)
	)
	(segment
		(start 213.55 130)
		(end 214 130)
		(width 0.4)
		(layer "B.Cu")
		(net 1)
	)
	(segment
		(start 239.9 143.675)
		(end 239.25 144.325)
		(width 0.256)
		(layer "B.Cu")
		(net 1)
	)
	(segment
		(start 214.5 134.5)
		(end 215 134)
		(width 0.4)
		(layer "B.Cu")
		(net 1)
	)
	(segment
		(start 207.860001 147.13)
		(end 207.860001 147.117)
		(width 0.114)
		(layer "B.Cu")
		(net 1)
	)
	(segment
		(start 252.51 113.5)
		(end 252.51 112.61)
		(width 0.201)
		(layer "B.Cu")
		(net 1)
	)
	(segment
		(start 229.9 155.2)
		(end 230.2 155.5)
		(width 0.201)
		(layer "B.Cu")
		(net 1)
	)
	(segment
		(start 199.45 115.5)
		(end 200 114.95)
		(width 0.256)
		(layer "B.Cu")
		(net 1)
	)
	(segment
		(start 237.9525 112.3275)
		(end 237.9525 110.9755)
		(width 0.182)
		(layer "B.Cu")
		(net 1)
	)
	(segment
		(start 258.75 123.9)
		(end 258.3 124.35)
		(width 0.4)
		(layer "B.Cu")
		(net 1)
	)
	(segment
		(start 202.5 137.5)
		(end 203 138)
		(width 0.4)
		(layer "B.Cu")
		(net 1)
	)
	(segment
		(start 160.730001 130.130001)
		(end 160.730001 129.849999)
		(width 0.256)
		(layer "B.Cu")
		(net 1)
	)
	(segment
		(start 230.22 164.5)
		(end 229.82 164.9)
		(width 0.4)
		(layer "B.Cu")
		(net 1)
	)
	(segment
		(start 192 135)
		(end 191.5 135.5)
		(width 0.4)
		(layer "B.Cu")
		(net 1)
	)
	(segment
		(start 214.565 116.475)
		(end 213.525 116.475)
		(width 0.4)
		(layer "B.Cu")
		(net 1)
	)
	(segment
		(start 201.82 127.18)
		(end 202 127)
		(width 0.4)
		(layer "B.Cu")
		(net 1)
	)
	(segment
		(start 225.7 149.7)
		(end 225.6 149.8)
		(width 0.1)
		(layer "B.Cu")
		(net 1)
	)
	(segment
		(start 207 129)
		(end 207 128.985)
		(width 0.182)
		(layer "B.Cu")
		(net 1)
	)
	(segment
		(start 253.075 130.775)
		(end 253.775 130.775)
		(width 0.4)
		(layer "B.Cu")
		(net 1)
	)
	(segment
		(start 213.5 131.5)
		(end 213.975 131.025)
		(width 0.4)
		(layer "B.Cu")
		(net 1)
	)
	(segment
		(start 201.15 132.85)
		(end 201 133)
		(width 0.4)
		(layer "B.Cu")
		(net 1)
	)
	(segment
		(start 239.9 143)
		(end 239.9 143.675)
		(width 0.256)
		(layer "B.Cu")
		(net 1)
	)
	(segment
		(start 201 121)
		(end 201.05 121)
		(width 0.4)
		(layer "B.Cu")
		(net 1)
	)
	(segment
		(start 213.5 138.5)
		(end 213 138)
		(width 0.4)
		(layer "B.Cu")
		(net 1)
	)
	(segment
		(start 217.7 113.2)
		(end 217.7 111.8)
		(width 0.4)
		(layer "B.Cu")
		(net 1)
	)
	(segment
		(start 203.2 93.185)
		(end 202.2 93.185)
		(width 0.4)
		(layer "B.Cu")
		(net 1)
	)
	(segment
		(start 153.6 140.95)
		(end 154.1 140.45)
		(width 0.4)
		(layer "B.Cu")
		(net 1)
	)
	(segment
		(start 173.865683 141.7)
		(end 173.999999 141.834316)
		(width 0.4)
		(layer "B.Cu")
		(net 1)
	)
	(segment
		(start 197.5 143.5)
		(end 197 143)
		(width 0.4)
		(layer "B.Cu")
		(net 1)
	)
	(segment
		(start 263.985 181.75)
		(end 263.985 181.015)
		(width 0.4)
		(layer "B.Cu")
		(net 1)
	)
	(segment
		(start 188.475 137.475)
		(end 188.5 137.5)
		(width 0.4)
		(layer "B.Cu")
		(net 1)
	)
	(segment
		(start 196.849803 86.810197)
		(end 196.95 86.71)
		(width 0.1)
		(layer "B.Cu")
		(net 1)
	)
	(segment
		(start 206.5 118.5)
		(end 207 119)
		(width 0.4)
		(layer "B.Cu")
		(net 1)
	)
	(segment
		(start 193.18 127.18)
		(end 194 128)
		(width 0.4)
		(layer "B.Cu")
		(net 1)
	)
	(segment
		(start 167.585 188.885)
		(end 167.6 188.9)
		(width 0.182)
		(layer "B.Cu")
		(net 1)
	)
	(segment
		(start 169.6 149.425)
		(end 169.6 148.499999)
		(width 0.4)
		(layer "B.Cu")
		(net 1)
	)
	(segment
		(start 246.3475 79.4675)
		(end 247.115 78.7)
		(width 0.256)
		(layer "B.Cu")
		(net 1)
	)
	(segment
		(start 205.4955 116.5)
		(end 205.4955 115.5045)
		(width 0.4)
		(layer "B.Cu")
		(net 1)
	)
	(segment
		(start 264.915 171.815)
		(end 264.9 171.8)
		(width 0.256)
		(layer "B.Cu")
		(net 1)
	)
	(segment
		(start 266.485 127.7)
		(end 267.515 127.7)
		(width 0.201)
		(layer "B.Cu")
		(net 1)
	)
	(segment
		(start 191.58 145.18)
		(end 191.5 145.1)
		(width 0.256)
		(layer "B.Cu")
		(net 1)
	)
	(segment
		(start 202 129.47)
		(end 202 129)
		(width 0.4)
		(layer "B.Cu")
		(net 1)
	)
	(segment
		(start 201.5 147.7)
		(end 200 147.7)
		(width 0.4)
		(layer "B.Cu")
		(net 1)
	)
	(segment
		(start 217.8 137.4)
		(end 217.8 136.2)
		(width 0.4)
		(layer "B.Cu")
		(net 1)
	)
	(segment
		(start 211.5 135.5)
		(end 212 135)
		(width 0.4)
		(layer "B.Cu")
		(net 1)
	)
	(segment
		(start 208.5 132.5)
		(end 208 133)
		(width 0.4)
		(layer "B.Cu")
		(net 1)
	)
	(segment
		(start 202.5 135.5)
		(end 202 135)
		(width 0.4)
		(layer "B.Cu")
		(net 1)
	)
	(segment
		(start 206.5 137.5)
		(end 206 137)
		(width 0.4)
		(layer "B.Cu")
		(net 1)
	)
	(segment
		(start 188.5 136.5)
		(end 188.475 136.525)
		(width 0.4)
		(layer "B.Cu")
		(net 1)
	)
	(segment
		(start 201.82 129.65)
		(end 202 129.47)
		(width 0.4)
		(layer "B.Cu")
		(net 1)
	)
	(segment
		(start 211.5 144.5)
		(end 212 145)
		(width 0.4)
		(layer "B.Cu")
		(net 1)
	)
	(segment
		(start 154.1 141.5)
		(end 154.1 140.96)
		(width 0.4)
		(layer "B.Cu")
		(net 1)
	)
	(segment
		(start 201.18 130.45)
		(end 201.18 130.82)
		(width 0.4)
		(layer "B.Cu")
		(net 1)
	)
	(segment
		(start 257.25 108.01)
		(end 257.25 108.575)
		(width 0.182)
		(layer "B.Cu")
		(net 1)
	)
	(segment
		(start 217.525 118.025)
		(end 217.6 118.1)
		(width 0.4)
		(layer "B.Cu")
		(net 1)
	)
	(segment
		(start 225.6 149.8)
		(end 223.3 149.8)
		(width 0.1)
		(layer "B.Cu")
		(net 1)
	)
	(segment
		(start 200 142.5)
		(end 200 142.975001)
		(width 0.4)
		(layer "B.Cu")
		(net 1)
	)
	(segment
		(start 203.45 131.28)
		(end 203.28 131.28)
		(width 0.4)
		(layer "B.Cu")
		(net 1)
	)
	(segment
		(start 192.975 141.025)
		(end 193.075 141.025)
		(width 0.4)
		(layer "B.Cu")
		(net 1)
	)
	(segment
		(start 190.973726 119.973726)
		(end 190.5 119.5)
		(width 0.4)
		(layer "B.Cu")
		(net 1)
	)
	(segment
		(start 164.75 183.215)
		(end 164.585 183.215)
		(width 0.256)
		(layer "B.Cu")
		(net 1)
	)
	(segment
		(start 198.991252 96.465)
		(end 199.353126 96.103126)
		(width 0.177)
		(layer "B.Cu")
		(net 1)
	)
	(segment
		(start 213.32 128.5)
		(end 213.55 128.73)
		(width 0.182)
		(layer "B.Cu")
		(net 1)
	)
	(segment
		(start 190.325 135.5)
		(end 190.275 135.55)
		(width 0.4)
		(layer "B.Cu")
		(net 1)
	)
	(segment
		(start 190.12 117.5)
		(end 190.5 117.5)
		(width 0.4)
		(layer "B.Cu")
		(net 1)
	)
	(segment
		(start 201 126.27)
		(end 201 126)
		(width 0.4)
		(layer "B.Cu")
		(net 1)
	)
	(segment
		(start 229.82 164.9)
		(end 229.2 164.9)
		(width 0.4)
		(layer "B.Cu")
		(net 1)
	)
	(segment
		(start 214.5 143.5)
		(end 215 144)
		(width 0.4)
		(layer "B.Cu")
		(net 1)
	)
	(segment
		(start 201.18 126.45)
		(end 201 126.27)
		(width 0.4)
		(layer "B.Cu")
		(net 1)
	)
	(segment
		(start 205.4955 115.5045)
		(end 205.5 115.5)
		(width 0.4)
		(layer "B.Cu")
		(net 1)
	)
	(segment
		(start 190 73.075)
		(end 190 74.385)
		(width 0.256)
		(layer "B.Cu")
		(net 1)
	)
	(segment
		(start 200 147.7)
		(end 199.7 147.7)
		(width 0.4)
		(layer "B.Cu")
		(net 1)
	)
	(segment
		(start 267.5 127.7)
		(end 267 127.2)
		(width 0.201)
		(layer "B.Cu")
		(net 1)
	)
	(segment
		(start 203.28 131.28)
		(end 203 131)
		(width 0.4)
		(layer "B.Cu")
		(net 1)
	)
	(segment
		(start 194.5 143.5)
		(end 194 144)
		(width 0.4)
		(layer "B.Cu")
		(net 1)
	)
	(segment
		(start 203.32 130.45)
		(end 203.45 130.45)
		(width 0.4)
		(layer "B.Cu")
		(net 1)
	)
	(segment
		(start 161.560401 128.826401)
		(end 161.534 128.8)
		(width 0.4)
		(layer "B.Cu")
		(net 1)
	)
	(segment
		(start 251.5 161.1)
		(end 252 160.6)
		(width 0.256)
		(layer "B.Cu")
		(net 1)
	)
	(segment
		(start 223.101 149.2)
		(end 222.216 149.2)
		(width 0.1)
		(layer "B.Cu")
		(net 1)
	)
	(segment
		(start 201 125.83)
		(end 201 126)
		(width 0.4)
		(layer "B.Cu")
		(net 1)
	)
	(segment
		(start 260.3 123.5)
		(end 260.45 123.65)
		(width 0.4)
		(layer "B.Cu")
		(net 1)
	)
	(segment
		(start 190.12 119.5)
		(end 190.5 119.5)
		(width 0.4)
		(layer "B.Cu")
		(net 1)
	)
	(segment
		(start 201.82 134.18)
		(end 202 134)
		(width 0.4)
		(layer "B.Cu")
		(net 1)
	)
	(segment
		(start 220.44 134.825)
		(end 218.175 134.825)
		(width 0.4)
		(layer "B.Cu")
		(net 1)
	)
	(segment
		(start 216.3 124.5)
		(end 217 124.5)
		(width 0.4)
		(layer "B.Cu")
		(net 1)
	)
	(segment
		(start 216.375 118.025)
		(end 217.525 118.025)
		(width 0.4)
		(layer "B.Cu")
		(net 1)
	)
	(segment
		(start 174.649999 141.699999)
		(end 174.134316 141.699999)
		(width 0.4)
		(layer "B.Cu")
		(net 1)
	)
	(segment
		(start 202.65 126.18)
		(end 202.83 126)
		(width 0.4)
		(layer "B.Cu")
		(net 1)
	)
	(segment
		(start 190.217001 112.88)
		(end 190.23 112.88)
		(width 0.1)
		(layer "B.Cu")
		(net 1)
	)
	(segment
		(start 213.5 140.5)
		(end 214 141)
		(width 0.4)
		(layer "B.Cu")
		(net 1)
	)
	(segment
		(start 199 146.64)
		(end 199 146.62)
		(width 0.4)
		(layer "B.Cu")
		(net 1)
	)
	(segment
		(start 261 124.1)
		(end 261 123.65)
		(width 0.4)
		(layer "B.Cu")
		(net 1)
	)
	(segment
		(start 229.2 164.9)
		(end 228.9 164.6)
		(width 0.4)
		(layer "B.Cu")
		(net 1)
	)
	(segment
		(start 183.400001 133.100001)
		(end 183.800001 133.500001)
		(width 0.256)
		(layer "B.Cu")
		(net 1)
	)
	(segment
		(start 190.12 125.5)
		(end 190.5 125.5)
		(width 0.4)
		(layer "B.Cu")
		(net 1)
	)
	(segment
		(start 164.585 183.215)
		(end 164.15 183.65)
		(width 0.256)
		(layer "B.Cu")
		(net 1)
	)
	(segment
		(start 228.1 164.915)
		(end 228.1 164.6005)
		(width 0.4)
		(layer "B.Cu")
		(net 1)
	)
	(segment
		(start 202.65 133.18)
		(end 202.82 133.18)
		(width 0.4)
		(layer "B.Cu")
		(net 1)
	)
	(segment
		(start 192.5 137.5)
		(end 193.5 137.5)
		(width 0.256)
		(layer "B.Cu")
		(net 1)
	)
	(segment
		(start 191.49 135.51)
		(end 191.5 135.5)
		(width 0.4)
		(layer "B.Cu")
		(net 1)
	)
	(segment
		(start 160.730001 129.849999)
		(end 161.768768 128.811232)
		(width 0.256)
		(layer "B.Cu")
		(net 1)
	)
	(segment
		(start 203.45 130.45)
		(end 204 131)
		(width 0.4)
		(layer "B.Cu")
		(net 1)
	)
	(segment
		(start 259.195 76.095)
		(end 259.2 76.1)
		(width 0.1)
		(layer "B.Cu")
		(net 1)
	)
	(segment
		(start 201.5 141.5)
		(end 201 142)
		(width 0.4)
		(layer "B.Cu")
		(net 1)
	)
	(segment
		(start 181.7 143.1)
		(end 181.1 143.1)
		(width 0.4)
		(layer "B.Cu")
		(net 1)
	)
	(segment
		(start 222.216 149.2)
		(end 222.2 149.216)
		(width 0.1)
		(layer "B.Cu")
		(net 1)
	)
	(segment
		(start 199.376252 96.08)
		(end 199.353126 96.103126)
		(width 0.177)
		(layer "B.Cu")
		(net 1)
	)
	(segment
		(start 201.82 133.82)
		(end 202 134)
		(width 0.4)
		(layer "B.Cu")
		(net 1)
	)
	(segment
		(start 202.5 123.5)
		(end 202 124)
		(width 0.4)
		(layer "B.Cu")
		(net 1)
	)
	(segment
		(start 173.95533 141.878986)
		(end 173.999999 141.834316)
		(width 0.1)
		(layer "B.Cu")
		(net 1)
	)
	(segment
		(start 167.585 188.6)
		(end 167.585 188.885)
		(width 0.182)
		(layer "B.Cu")
		(net 1)
	)
	(segment
		(start 196.95 86.71)
		(end 196.95 86.33)
		(width 0.1)
		(layer "B.Cu")
		(net 1)
	)
	(segment
		(start 206.5 139.5)
		(end 207 140)
		(width 0.4)
		(layer "B.Cu")
		(net 1)
	)
	(segment
		(start 207 128.985)
		(end 206.615 128.6)
		(width 0.182)
		(layer "B.Cu")
		(net 1)
	)
	(segment
		(start 193.717 145.48)
		(end 193.73 145.48)
		(width 0.1)
		(layer "B.Cu")
		(net 1)
	)
	(segment
		(start 214.5 123.5)
		(end 215 123)
		(width 0.4)
		(layer "B.Cu")
		(net 1)
	)
	(segment
		(start 198.5 115.5)
		(end 199.45 115.5)
		(width 0.256)
		(layer "B.Cu")
		(net 1)
	)
	(segment
		(start 216.1 125.5)
		(end 216.1 124.3)
		(width 0.4)
		(layer "B.Cu")
		(net 1)
	)
	(segment
		(start 238.0045 112.2755)
		(end 240.4775 112.2755)
		(width 0.182)
		(layer "B.Cu")
		(net 1)
	)
	(segment
		(start 222.45 124.4)
		(end 222.425 124.425)
		(width 0.4)
		(layer "B.Cu")
		(net 1)
	)
	(segment
		(start 211.5 123.5)
		(end 212 124)
		(width 0.4)
		(layer "B.Cu")
		(net 1)
	)
	(segment
		(start 182.916916 138.176916)
		(end 182.505025 137.765025)
		(width 0.4)
		(layer "B.Cu")
		(net 1)
	)
	(segment
		(start 164.85 187.815)
		(end 164.85 187.55)
		(width 0.182)
		(layer "B.Cu")
		(net 1)
	)
	(segment
		(start 182.6 142.2)
		(end 181.7 143.1)
		(width 0.4)
		(layer "B.Cu")
		(net 1)
	)
	(segment
		(start 202.5 144.5)
		(end 202 145)
		(width 0.4)
		(layer "B.Cu")
		(net 1)
	)
	(segment
		(start 190.5 135.5)
		(end 190.325 135.5)
		(width 0.4)
		(layer "B.Cu")
		(net 1)
	)
	(segment
		(start 190.12 127.5)
		(end 190.5 127.5)
		(width 0.4)
		(layer "B.Cu")
		(net 1)
	)
	(segment
		(start 205.5 144.5)
		(end 205 144)
		(width 0.4)
		(layer "B.Cu")
		(net 1)
	)
	(segment
		(start 188.475 136.525)
		(end 188.475 137.475)
		(width 0.4)
		(layer "B.Cu")
		(net 1)
	)
	(segment
		(start 208.5 135.5)
		(end 209 136)
		(width 0.4)
		(layer "B.Cu")
		(net 1)
	)
	(segment
		(start 246.3475 82.6895)
		(end 246.3475 79.4675)
		(width 0.256)
		(layer "B.Cu")
		(net 1)
	)
	(segment
		(start 199 147)
		(end 199 146.62)
		(width 0.4)
		(layer "B.Cu")
		(net 1)
	)
	(segment
		(start 189.5 138.5)
		(end 189 139)
		(width 0.4)
		(layer "B.Cu")
		(net 1)
	)
	(segment
		(start 201.25 119.05)
		(end 201.0005 119.05)
		(width 0.1)
		(layer "B.Cu")
		(net 1)
	)
	(segment
		(start 153.55 140.95)
		(end 153.6 140.95)
		(width 0.4)
		(layer "B.Cu")
		(net 1)
	)
	(segment
		(start 198.976252 95.55)
		(end 199.376252 95.95)
		(width 0.177)
		(layer "B.Cu")
		(net 1)
	)
	(segment
		(start 266.485 124.7)
		(end 267.1 124.7)
		(width 0.201)
		(layer "B.Cu")
		(net 1)
	)
	(segment
		(start 190.12 121.5)
		(end 190.5 121.5)
		(width 0.4)
		(layer "B.Cu")
		(net 1)
	)
	(segment
		(start 269.05 145.35)
		(end 269.05 144.65)
		(width 0.201)
		(layer "B.Cu")
		(net 1)
	)
	(segment
		(start 226.111 149.217)
		(end 225.7 149.628)
		(width 0.1)
		(layer "B.Cu")
		(net 1)
	)
	(segment
		(start 255.2 75.795)
		(end 255.2 76.1)
		(width 0.1)
		(layer "B.Cu")
		(net 1)
	)
	(segment
		(start 201.18 131.25)
		(end 201.18 131.18)
		(width 0.4)
		(layer "B.Cu")
		(net 1)
	)
	(segment
		(start 244.2 158.297)
		(end 245.371 159.468)
		(width 0.4)
		(layer "B.Cu")
		(net 1)
	)
	(segment
		(start 199.506252 95.95)
		(end 199.7 95.95)
		(width 0.177)
		(layer "B.Cu")
		(net 1)
	)
	(segment
		(start 217.8 135.2)
		(end 217.8 136.2)
		(width 0.4)
		(layer "B.Cu")
		(net 1)
	)
	(segment
		(start 209.5 127.5)
		(end 210 128)
		(width 0.4)
		(layer "B.Cu")
		(net 1)
	)
	(segment
		(start 195.246447 144.246447)
		(end 194.5 143.5)
		(width 0.4)
		(layer "B.Cu")
		(net 1)
	)
	(segment
		(start 237.9525 116.5755)
		(end 237.9525 112.3275)
		(width 0.182)
		(layer "B.Cu")
		(net 1)
	)
	(segment
		(start 194.5 122.5)
		(end 194 123)
		(width 0.4)
		(layer "B.Cu")
		(net 1)
	)
	(segment
		(start 208.860001 147.117)
		(end 209.120001 146.857)
		(width 0.114)
		(layer "B.Cu")
		(net 1)
	)
	(segment
		(start 168.6 187.715)
		(end 168.47 187.715)
		(width 0.256)
		(layer "B.Cu")
		(net 1)
	)
	(segment
		(start 213.5 120.5)
		(end 214 120)
		(width 0.4)
		(layer "B.Cu")
		(net 1)
	)
	(segment
		(start 223.5975 79.4175)
		(end 224.315 78.7)
		(width 0.256)
		(layer "B.Cu")
		(net 1)
	)
	(segment
		(start 154.1 140.96)
		(end 154.1 140.45)
		(width 0.4)
		(layer "B.Cu")
		(net 1)
	)
	(segment
		(start 257.25 107.24)
		(end 257.25 108.01)
		(width 0.182)
		(layer "B.Cu")
		(net 1)
	)
	(segment
		(start 208.5 142.5)
		(end 208 143)
		(width 0.4)
		(layer "B.Cu")
		(net 1)
	)
	(segment
		(start 267.515 126.7)
		(end 267.515 127.7)
		(width 0.201)
		(layer "B.Cu")
		(net 1)
	)
	(segment
		(start 222.45 123.85)
		(end 222.45 124.4)
		(width 0.4)
		(layer "B.Cu")
		(net 1)
	)
	(segment
		(start 203.32 130.68)
		(end 203 131)
		(width 0.4)
		(layer "B.Cu")
		(net 1)
	)
	(segment
		(start 244.2 165)
		(end 243.6 165)
		(width 0.256)
		(layer "B.Cu")
		(net 1)
	)
	(segment
		(start 213.5 120.525)
		(end 213.5 120.5)
		(width 0.4)
		(layer "B.Cu")
		(net 1)
	)
	(segment
		(start 202.65 131.28)
		(end 202.93 131)
		(width 0.4)
		(layer "B.Cu")
		(net 1)
	)
	(segment
		(start 208 130)
		(end 208.35 130)
		(width 0.4)
		(layer "B.Cu")
		(net 1)
	)
	(segment
		(start 174.134316 141.699999)
		(end 173.999999 141.834316)
		(width 0.4)
		(layer "B.Cu")
		(net 1)
	)
	(segment
		(start 199.376252 95.95)
		(end 199.7 95.95)
		(width 0.177)
		(layer "B.Cu")
		(net 1)
	)
	(segment
		(start 190.23 112.88)
		(end 190.49 113.14)
		(width 0.1)
		(layer "B.Cu")
		(net 1)
	)
	(segment
		(start 203.172403 93.185)
		(end 203.2 93.185)
		(width 0.182)
		(layer "B.Cu")
		(net 1)
	)
	(segment
		(start 202.575 129.65)
		(end 202 129.075)
		(width 0.4)
		(layer "B.Cu")
		(net 1)
	)
	(segment
		(start 193.73 145.48)
		(end 193.99 145.22)
		(width 0.1)
		(layer "B.Cu")
		(net 1)
	)
	(segment
		(start 195.5 137.5)
		(end 195 137)
		(width 0.4)
		(layer "B.Cu")
		(net 1)
	)
	(segment
		(start 182.916916 138.301937)
		(end 182.916916 138.176916)
		(width 0.4)
		(layer "B.Cu")
		(net 1)
	)
	(segment
		(start 153.55 140.95)
		(end 154.09 140.95)
		(width 0.4)
		(layer "B.Cu")
		(net 1)
	)
	(segment
		(start 201.85 128.85)
		(end 202 129)
		(width 0.4)
		(layer "B.Cu")
		(net 1)
	)
	(segment
		(start 256.85 160)
		(end 256.85 160.365)
		(width 0.256)
		(layer "B.Cu")
		(net 1)
	)
	(segment
		(start 250.665 135.015)
		(end 250.625 134.975)
		(width 0.4)
		(layer "B.Cu")
		(net 1)
	)
	(segment
		(start 192.5 122.38)
		(end 192.5 122.5)
		(width 0.4)
		(layer "B.Cu")
		(net 1)
	)
	(segment
		(start 208.860001 147.13)
		(end 208.860001 147.117)
		(width 0.114)
		(layer "B.Cu")
		(net 1)
	)
	(segment
		(start 174.5 173.2775)
		(end 174.5 172.9625)
		(width 0.182)
		(layer "B.Cu")
		(net 1)
	)
	(segment
		(start 210.5 132.5)
		(end 211 132)
		(width 0.4)
		(layer "B.Cu")
		(net 1)
	)
	(segment
		(start 201.82 133.65)
		(end 201.82 133.82)
		(width 0.4)
		(layer "B.Cu")
		(net 1)
	)
	(segment
		(start 201.05 121)
		(end 201.3 121.25)
		(width 0.4)
		(layer "B.Cu")
		(net 1)
	)
	(segment
		(start 195.326447 144.246447)
		(end 195.246447 144.246447)
		(width 0.4)
		(layer "B.Cu")
		(net 1)
	)
	(segment
		(start 161.4 187)
		(end 161.4 187.5)
		(width 0.1)
		(layer "B.Cu")
		(net 1)
	)
	(segment
		(start 154.1 141.5)
		(end 153.55 140.95)
		(width 0.4)
		(layer "B.Cu")
		(net 1)
	)
	(segment
		(start 168.47 187.715)
		(end 167.585 188.6)
		(width 0.256)
		(layer "B.Cu")
		(net 1)
	)
	(segment
		(start 204.5 120.5)
		(end 204 120)
		(width 0.4)
		(layer "B.Cu")
		(net 1)
	)
	(segment
		(start 190.973726 123.973726)
		(end 190.5 123.5)
		(width 0.4)
		(layer "B.Cu")
		(net 1)
	)
	(segment
		(start 202.68 129.65)
		(end 202.575 129.65)
		(width 0.4)
		(layer "B.Cu")
		(net 1)
	)
	(segment
		(start 259.195 75.795)
		(end 259.195 76.095)
		(width 0.1)
		(layer "B.Cu")
		(net 1)
	)
	(segment
		(start 253.75 109.915)
		(end 253.75 110.685)
		(width 0.182)
		(layer "B.Cu")
		(net 1)
	)
	(segment
		(start 257.25 108.575)
		(end 257.275 108.6)
		(width 0.182)
		(layer "B.Cu")
		(net 1)
	)
	(segment
		(start 161.35 186.95)
		(end 161.4 187)
		(width 0.1)
		(layer "B.Cu")
		(net 1)
	)
	(segment
		(start 208.5 115.5)
		(end 209 115)
		(width 0.4)
		(layer "B.Cu")
		(net 1)
	)
	(segment
		(start 260.35 124.55)
		(end 260.55 124.55)
		(width 0.4)
		(layer "B.Cu")
		(net 1)
	)
	(segment
		(start 241.95 117.7)
		(end 241.5 118.15)
		(width 0.4)
		(layer "B.Cu")
		(net 1)
	)
	(segment
		(start 201.18 132.85)
		(end 201.15 132.85)
		(width 0.4)
		(layer "B.Cu")
		(net 1)
	)
	(segment
		(start 199.353126 96.103126)
		(end 199.506252 95.95)
		(width 0.177)
		(layer "B.Cu")
		(net 1)
	)
	(segment
		(start 196.5 140.5)
		(end 196 140)
		(width 0.4)
		(layer "B.Cu")
		(net 1)
	)
	(segment
		(start 193.18 127)
		(end 193.18 127.18)
		(width 0.4)
		(layer "B.Cu")
		(net 1)
	)
	(segment
		(start 202.699685 92.712282)
		(end 203.172403 93.185)
		(width 0.182)
		(layer "B.Cu")
		(net 1)
	)
	(segment
		(start 230.45 164.5)
		(end 230.22 164.5)
		(width 0.4)
		(layer "B.Cu")
		(net 1)
	)
	(segment
		(start 252.5 160.5)
		(end 252.5 161.115)
		(width 0.256)
		(layer "B.Cu")
		(net 1)
	)
	(segment
		(start 204.5 141.5)
		(end 204 141)
		(width 0.4)
		(layer "B.Cu")
		(net 1)
	)
	(segment
		(start 251.35 135.015)
		(end 250.665 135.015)
		(width 0.4)
		(layer "B.Cu")
		(net 1)
	)
	(segment
		(start 207.860001 147.117)
		(end 207.600001 146.857)
		(width 0.114)
		(layer "B.Cu")
		(net 1)
	)
	(segment
		(start 159.965 188.6)
		(end 159.965 188.935)
		(width 0.182)
		(layer "B.Cu")
		(net 1)
	)
	(segment
		(start 173.65 141.7)
		(end 173.865683 141.7)
		(width 0.4)
		(layer "B.Cu")
		(net 1)
	)
	(segment
		(start 202.82 133.18)
		(end 203 133)
		(width 0.4)
		(layer "B.Cu")
		(net 1)
	)
	(segment
		(start 201.82 128.85)
		(end 201.85 128.85)
		(width 0.4)
		(layer "B.Cu")
		(net 1)
	)
	(segment
		(start 262.4 179.7)
		(end 263.4 179.7)
		(width 0.4)
		(layer "B.Cu")
		(net 1)
	)
	(segment
		(start 269.05 144.65)
		(end 269.1 144.6)
		(width 0.201)
		(layer "B.Cu")
		(net 1)
	)
	(segment
		(start 200.376252 95.95)
		(end 200.891252 96.465)
		(width 0.177)
		(layer "B.Cu")
		(net 1)
	)
	(segment
		(start 190 142)
		(end 190.5 141.5)
		(width 0.4)
		(layer "B.Cu")
		(net 1)
	)
	(segment
		(start 186.6 186.58)
		(end 186.985 186.965)
		(width 0.4)
		(layer "B.Cu")
		(net 1)
	)
	(segment
		(start 203.72 131.28)
		(end 204 131)
		(width 0.4)
		(layer "B.Cu")
		(net 1)
	)
	(segment
		(start 205.5 126.5)
		(end 206 126)
		(width 0.4)
		(layer "B.Cu")
		(net 1)
	)
	(segment
		(start 260.45 123.65)
		(end 261 123.65)
		(width 0.4)
		(layer "B.Cu")
		(net 1)
	)
	(segment
		(start 184.55 144.999999)
		(end 184.15 144.999999)
		(width 0.4)
		(layer "B.Cu")
		(net 1)
	)
	(segment
		(start 171.699999 148.499999)
		(end 171.6 148.4)
		(width 0.4)
		(layer "B.Cu")
		(net 1)
	)
	(segment
		(start 198 136)
		(end 197.5 135.5)
		(width 0.4)
		(layer "B.Cu")
		(net 1)
	)
	(segment
		(start 217.003553 128.863553)
		(end 217.29 129.15)
		(width 0.4)
		(layer "B.Cu")
		(net 1)
	)
	(segment
		(start 186.985 186.965)
		(end 186.985 187.5)
		(width 0.4)
		(layer "B.Cu")
		(net 1)
	)
	(segment
		(start 183.400001 133.000001)
		(end 183.400001 132.900001)
		(width 0.256)
		(layer "B.Cu")
		(net 1)
	)
	(segment
		(start 202.699685 92.712282)
		(end 202.226967 93.185)
		(width 0.182)
		(layer "B.Cu")
		(net 1)
	)
	(segment
		(start 200 118)
		(end 200 117.6)
		(width 0.1)
		(layer "B.Cu")
		(net 1)
	)
	(segment
		(start 183.400001 132.900001)
		(end 183.800001 132.500001)
		(width 0.256)
		(layer "B.Cu")
		(net 1)
	)
	(segment
		(start 267.515 127.7)
		(end 267.5 127.7)
		(width 0.201)
		(layer "B.Cu")
		(net 1)
	)
	(segment
		(start 159.965 188.935)
		(end 159.95 188.95)
		(width 0.182)
		(layer "B.Cu")
		(net 1)
	)
	(segment
		(start 203.45 131.28)
		(end 203.72 131.28)
		(width 0.4)
		(layer "B.Cu")
		(net 1)
	)
	(segment
		(start 183.400001 133.000001)
		(end 183.400001 133.100001)
		(width 0.256)
		(layer "B.Cu")
		(net 1)
	)
	(segment
		(start 187 143)
		(end 187.5 142.5)
		(width 0.4)
		(layer "B.Cu")
		(net 1)
	)
	(segment
		(start 213.975 131.025)
		(end 214.004834 131.025)
		(width 0.4)
		(layer "B.Cu")
		(net 1)
	)
	(segment
		(start 186.6 183.7)
		(end 186.6 186.58)
		(width 0.4)
		(layer "B.Cu")
		(net 1)
	)
	(segment
		(start 201.18 125.65)
		(end 201 125.83)
		(width 0.4)
		(layer "B.Cu")
		(net 1)
	)
	(segment
		(start 202.83 128)
		(end 203 128)
		(width 0.4)
		(layer "B.Cu")
		(net 1)
	)
	(segment
		(start 150.71 70.67)
		(end 150.71 70.71)
		(width 0.1)
		(layer "In2.Cu")
		(net 1)
	)
	(segment
		(start 150.71 70.71)
		(end 153.5 73.5)
		(width 0.1)
		(layer "In2.Cu")
		(net 1)
	)
	(segment
		(start 210.5 126.5)
		(end 211 126)
		(width 0.4)
		(layer "F.Cu")
		(net 2)
	)
	(segment
		(start 216.8 100.8)
		(end 215.24 99.24)
		(width 0.4)
		(layer "F.Cu")
		(net 2)
	)
	(segment
		(start 204.5 128.5)
		(end 205 128)
		(width 0.4)
		(layer "F.Cu")
		(net 2)
	)
	(segment
		(start 207.5 127.5)
		(end 208 127)
		(width 0.4)
		(layer "F.Cu")
		(net 2)
	)
	(segment
		(start 213.5 125.5)
		(end 214 125)
		(width 0.4)
		(layer "F.Cu")
		(net 2)
	)
	(segment
		(start 232.365 100.235)
		(end 231.8 100.8)
		(width 0.4)
		(layer "F.Cu")
		(net 2)
	)
	(segment
		(start 215.24 99.24)
		(end 215.24 99.12)
		(width 0.4)
		(layer "F.Cu")
		(net 2)
	)
	(segment
		(start 206.5 124.5)
		(end 207 124)
		(width 0.4)
		(layer "F.Cu")
		(net 2)
	)
	(segment
		(start 209.5 123.5)
		(end 210 123)
		(width 0.4)
		(layer "F.Cu")
		(net 2)
	)
	(segment
		(start 231.8 100.8)
		(end 216.8 100.8)
		(width 0.4)
		(layer "F.Cu")
		(net 2)
	)
	(segment
		(start 232.365 98.575)
		(end 232.365 100.235)
		(width 0.4)
		(layer "F.Cu")
		(net 2)
	)
	(via
		(at 210 97.8)
		(size 0.45)
		(drill 0.2)
		(layers "F.Cu" "B.Cu")
		(net 2)
	)
	(via
		(at 212.35 95.4)
		(size 0.45)
		(drill 0.2)
		(layers "F.Cu" "B.Cu")
		(net 2)
	)
	(via
		(at 217 122.9)
		(size 0.45)
		(drill 0.2)
		(layers "F.Cu" "B.Cu")
		(net 2)
	)
	(via
		(at 210 99.3)
		(size 0.45)
		(drill 0.2)
		(layers "F.Cu" "B.Cu")
		(net 2)
	)
	(via
		(at 210 123)
		(size 0.45)
		(drill 0.2)
		(layers "F.Cu" "B.Cu")
		(net 2)
	)
	(via
		(at 208 127)
		(size 0.45)
		(drill 0.2)
		(layers "F.Cu" "B.Cu")
		(net 2)
	)
	(via
		(at 212.95 95.9)
		(size 0.45)
		(drill 0.2)
		(layers "F.Cu" "B.Cu")
		(net 2)
	)
	(via
		(at 212.7 95.05)
		(size 0.45)
		(drill 0.2)
		(layers "F.Cu" "B.Cu")
		(net 2)
	)
	(via
		(at 207 124)
		(size 0.45)
		(drill 0.2)
		(layers "F.Cu" "B.Cu")
		(net 2)
	)
	(via
		(at 212.95 95.45)
		(size 0.45)
		(drill 0.2)
		(layers "F.Cu" "B.Cu")
		(net 2)
	)
	(via
		(at 205 128)
		(size 0.45)
		(drill 0.2)
		(layers "F.Cu" "B.Cu")
		(net 2)
	)
	(via
		(at 210 98.8)
		(size 0.45)
		(drill 0.2)
		(layers "F.Cu" "B.Cu")
		(net 2)
	)
	(via
		(at 214 125)
		(size 0.45)
		(drill 0.2)
		(layers "F.Cu" "B.Cu")
		(net 2)
	)
	(via
		(at 210 98.3)
		(size 0.45)
		(drill 0.2)
		(layers "F.Cu" "B.Cu")
		(net 2)
	)
	(via
		(at 212.95 96.4)
		(size 0.45)
		(drill 0.2)
		(layers "F.Cu" "B.Cu")
		(net 2)
	)
	(via
		(at 210 99.8)
		(size 0.45)
		(drill 0.2)
		(layers "F.Cu" "B.Cu")
		(net 2)
	)
	(via
		(at 210 100.3)
		(size 0.45)
		(drill 0.2)
		(layers "F.Cu" "B.Cu")
		(net 2)
	)
	(via
		(at 212.35 95.9)
		(size 0.45)
		(drill 0.2)
		(layers "F.Cu" "B.Cu")
		(net 2)
	)
	(via
		(at 211 126)
		(size 0.45)
		(drill 0.2)
		(layers "F.Cu" "B.Cu")
		(net 2)
	)
	(segment
		(start 214.5 124.5)
		(end 214 125)
		(width 0.4)
		(layer "B.Cu")
		(net 2)
	)
	(segment
		(start 205.5 127.5)
		(end 205 128)
		(width 0.4)
		(layer "B.Cu")
		(net 2)
	)
	(segment
		(start 208.5 127.5)
		(end 208 127)
		(width 0.4)
		(layer "B.Cu")
		(net 2)
	)
	(segment
		(start 210.5 123.5)
		(end 210 123)
		(width 0.4)
		(layer "B.Cu")
		(net 2)
	)
	(segment
		(start 211.5 126.5)
		(end 211 126)
		(width 0.4)
		(layer "B.Cu")
		(net 2)
	)
	(segment
		(start 216.1 122.9)
		(end 217 122.9)
		(width 0.4)
		(layer "B.Cu")
		(net 2)
	)
	(segment
		(start 207.5 124.5)
		(end 207 124)
		(width 0.4)
		(layer "B.Cu")
		(net 2)
	)
	(segment
		(start 210 88.4)
		(end 210 88.9)
		(width 0.4)
		(layer "F.Cu")
		(net 3)
	)
	(segment
		(start 213.5 115.5)
		(end 214 115)
		(width 0.4)
		(layer "F.Cu")
		(net 3)
	)
	(segment
		(start 225.585 114.115)
		(end 225.6 114.1)
		(width 0.4)
		(layer "F.Cu")
		(net 3)
	)
	(segment
		(start 234.3955 111.7045)
		(end 234.4 111.7)
		(width 0.4)
		(layer "F.Cu")
		(net 3)
	)
	(segment
		(start 234.3955 111.6445)
		(end 235.44 110.6)
		(width 0.4)
		(layer "F.Cu")
		(net 3)
	)
	(segment
		(start 234.4 113.125)
		(end 234.89 113.125)
		(width 0.201)
		(layer "F.Cu")
		(net 3)
	)
	(segment
		(start 211.5 119.5)
		(end 212 119)
		(width 0.4)
		(layer "F.Cu")
		(net 3)
	)
	(segment
		(start 214.5 118.5)
		(end 215 118)
		(width 0.4)
		(layer "F.Cu")
		(net 3)
	)
	(segment
		(start 234.3955 111.95)
		(end 234.3955 111.71285)
		(width 0.4)
		(layer "F.Cu")
		(net 3)
	)
	(segment
		(start 226.625 110.175)
		(end 232.235 110.175)
		(width 0.4)
		(layer "F.Cu")
		(net 3)
	)
	(segment
		(start 225.585 114.2)
		(end 225.585 114.115)
		(width 0.4)
		(layer "F.Cu")
		(net 3)
	)
	(segment
		(start 234.3955 111.95)
		(end 234.3955 111.7045)
		(width 0.4)
		(layer "F.Cu")
		(net 3)
	)
	(segment
		(start 228.5 91.9)
		(end 228.5 92.7)
		(width 0.4)
		(layer "F.Cu")
		(net 3)
	)
	(segment
		(start 228.46 90.2875)
		(end 228.46 91.86)
		(width 0.4)
		(layer "F.Cu")
		(net 3)
	)
	(segment
		(start 210.5 116.5)
		(end 211 116)
		(width 0.4)
		(layer "F.Cu")
		(net 3)
	)
	(segment
		(start 233.305 111.245)
		(end 233.92765 111.245)
		(width 0.4)
		(layer "F.Cu")
		(net 3)
	)
	(segment
		(start 234.3955 111.71285)
		(end 233.92765 111.245)
		(width 0.4)
		(layer "F.Cu")
		(net 3)
	)
	(segment
		(start 208.5 120.5)
		(end 209 120)
		(width 0.4)
		(layer "F.Cu")
		(net 3)
	)
	(segment
		(start 234.89 113.125)
		(end 235.415 112.6)
		(width 0.201)
		(layer "F.Cu")
		(net 3)
	)
	(segment
		(start 234.3955 111.95)
		(end 234.3955 111.6445)
		(width 0.4)
		(layer "F.Cu")
		(net 3)
	)
	(segment
		(start 207.5 117.5)
		(end 208 117)
		(width 0.4)
		(layer "F.Cu")
		(net 3)
	)
	(segment
		(start 233.92765 111.245)
		(end 234.795 111.245)
		(width 0.4)
		(layer "F.Cu")
		(net 3)
	)
	(segment
		(start 227.9 92.7)
		(end 227.9 91.9)
		(width 0.4)
		(layer "F.Cu")
		(net 3)
	)
	(segment
		(start 228.46 91.86)
		(end 228.5 91.9)
		(width 0.4)
		(layer "F.Cu")
		(net 3)
	)
	(segment
		(start 212.5 122.5)
		(end 213 122)
		(width 0.4)
		(layer "F.Cu")
		(net 3)
	)
	(segment
		(start 234.795 111.245)
		(end 235.44 110.6)
		(width 0.4)
		(layer "F.Cu")
		(net 3)
	)
	(segment
		(start 227.9 92.7)
		(end 228.5 92.7)
		(width 0.4)
		(layer "F.Cu")
		(net 3)
	)
	(segment
		(start 232.235 110.175)
		(end 233.305 111.245)
		(width 0.4)
		(layer "F.Cu")
		(net 3)
	)
	(segment
		(start 227.9 91.9)
		(end 228.5 91.9)
		(width 0.4)
		(layer "F.Cu")
		(net 3)
	)
	(segment
		(start 225.6 111.2)
		(end 226.625 110.175)
		(width 0.4)
		(layer "F.Cu")
		(net 3)
	)
	(via
		(at 234.3955 111.95)
		(size 0.45)
		(drill 0.2)
		(layers "F.Cu" "B.Cu")
		(net 3)
	)
	(via
		(at 217.7 115.3)
		(size 0.45)
		(drill 0.2)
		(layers "F.Cu" "B.Cu")
		(net 3)
	)
	(via
		(at 212.35 86.925)
		(size 0.45)
		(drill 0.2)
		(layers "F.Cu" "B.Cu")
		(net 3)
	)
	(via
		(at 215 118)
		(size 0.45)
		(drill 0.2)
		(layers "F.Cu" "B.Cu")
		(net 3)
	)
	(via
		(at 215.4 89.05)
		(size 0.45)
		(drill 0.2)
		(layers "F.Cu" "B.Cu")
		(net 3)
	)
	(via
		(at 210 91.2)
		(size 0.45)
		(drill 0.2)
		(layers "F.Cu" "B.Cu")
		(net 3)
	)
	(via
		(at 228.5 91.9)
		(size 0.45)
		(drill 0.2)
		(layers "F.Cu" "B.Cu")
		(net 3)
	)
	(via
		(at 214 115)
		(size 0.45)
		(drill 0.2)
		(layers "F.Cu" "B.Cu")
		(net 3)
	)
	(via
		(at 214.85 90.05)
		(size 0.45)
		(drill 0.2)
		(layers "F.Cu" "B.Cu")
		(net 3)
	)
	(via
		(at 210 88.9)
		(size 0.45)
		(drill 0.2)
		(layers "F.Cu" "B.Cu")
		(net 3)
	)
	(via
		(at 227.9 91.9)
		(size 0.45)
		(drill 0.2)
		(layers "F.Cu" "B.Cu")
		(net 3)
	)
	(via
		(at 228.5 92.7)
		(size 0.45)
		(drill 0.2)
		(layers "F.Cu" "B.Cu")
		(net 3)
	)
	(via
		(at 210 88.4)
		(size 0.45)
		(drill 0.2)
		(layers "F.Cu" "B.Cu")
		(net 3)
	)
	(via
		(at 210 90.7)
		(size 0.45)
		(drill 0.2)
		(layers "F.Cu" "B.Cu")
		(net 3)
	)
	(via
		(at 225.6 114.1)
		(size 0.45)
		(drill 0.2)
		(layers "F.Cu" "B.Cu")
		(net 3)
	)
	(via
		(at 210 89.4)
		(size 0.45)
		(drill 0.2)
		(layers "F.Cu" "B.Cu")
		(net 3)
	)
	(via
		(at 212.4 86.4)
		(size 0.45)
		(drill 0.2)
		(layers "F.Cu" "B.Cu")
		(net 3)
	)
	(via
		(at 215.4 89.5)
		(size 0.45)
		(drill 0.2)
		(layers "F.Cu" "B.Cu")
		(net 3)
	)
	(via
		(at 212.65 87.4)
		(size 0.45)
		(drill 0.2)
		(layers "F.Cu" "B.Cu")
		(net 3)
	)
	(via
		(at 212.875 86.9)
		(size 0.45)
		(drill 0.2)
		(layers "F.Cu" "B.Cu")
		(net 3)
	)
	(via
		(at 213 86.4)
		(size 0.45)
		(drill 0.2)
		(layers "F.Cu" "B.Cu")
		(net 3)
	)
	(via
		(at 208 117)
		(size 0.45)
		(drill 0.2)
		(layers "F.Cu" "B.Cu")
		(net 3)
	)
	(via
		(at 215.4 90)
		(size 0.45)
		(drill 0.2)
		(layers "F.Cu" "B.Cu")
		(net 3)
	)
	(via
		(at 214.85 89.55)
		(size 0.45)
		(drill 0.2)
		(layers "F.Cu" "B.Cu")
		(net 3)
	)
	(via
		(at 225.6 111.2)
		(size 0.45)
		(drill 0.2)
		(layers "F.Cu" "B.Cu")
		(net 3)
	)
	(via
		(at 214.85 89.05)
		(size 0.45)
		(drill 0.2)
		(layers "F.Cu" "B.Cu")
		(net 3)
	)
	(via
		(at 212 119)
		(size 0.45)
		(drill 0.2)
		(layers "F.Cu" "B.Cu")
		(net 3)
	)
	(via
		(at 211 116)
		(size 0.45)
		(drill 0.2)
		(layers "F.Cu" "B.Cu")
		(net 3)
	)
	(via
		(at 212.25 87.75)
		(size 0.45)
		(drill 0.2)
		(layers "F.Cu" "B.Cu")
		(net 3)
	)
	(via
		(at 234.4 113.125)
		(size 0.45)
		(drill 0.2)
		(layers "F.Cu" "B.Cu")
		(net 3)
	)
	(via
		(at 209 120)
		(size 0.45)
		(drill 0.2)
		(layers "F.Cu" "B.Cu")
		(net 3)
	)
	(via
		(at 227.9 92.7)
		(size 0.45)
		(drill 0.2)
		(layers "F.Cu" "B.Cu")
		(net 3)
	)
	(via
		(at 213 122)
		(size 0.45)
		(drill 0.2)
		(layers "F.Cu" "B.Cu")
		(net 3)
	)
	(segment
		(start 208.5 120.5)
		(end 209 120)
		(width 0.4)
		(layer "B.Cu")
		(net 3)
	)
	(segment
		(start 217.7 114.6)
		(end 217.7 115.3)
		(width 0.4)
		(layer "B.Cu")
		(net 3)
	)
	(segment
		(start 213.475 121.525)
		(end 213 122)
		(width 0.4)
		(layer "B.Cu")
		(net 3)
	)
	(segment
		(start 215 118)
		(end 215.35 118)
		(width 0.4)
		(layer "B.Cu")
		(net 3)
	)
	(segment
		(start 234.4 111.9545)
		(end 234.3955 111.95)
		(width 0.4)
		(layer "B.Cu")
		(net 3)
	)
	(segment
		(start 214.44 115.44)
		(end 214 115)
		(width 0.4)
		(layer "B.Cu")
		(net 3)
	)
	(segment
		(start 211.5 119.5)
		(end 212 119)
		(width 0.4)
		(layer "B.Cu")
		(net 3)
	)
	(segment
		(start 213.5 121.525)
		(end 213.475 121.525)
		(width 0.4)
		(layer "B.Cu")
		(net 3)
	)
	(segment
		(start 215.35 118)
		(end 215.375 118.025)
		(width 0.4)
		(layer "B.Cu")
		(net 3)
	)
	(segment
		(start 210.5 116.5)
		(end 211 116)
		(width 0.4)
		(layer "B.Cu")
		(net 3)
	)
	(segment
		(start 214.64 115.44)
		(end 214.44 115.44)
		(width 0.4)
		(layer "B.Cu")
		(net 3)
	)
	(segment
		(start 234.4 113.125)
		(end 234.4 111.9545)
		(width 0.4)
		(layer "B.Cu")
		(net 3)
	)
	(segment
		(start 208.5 116.5)
		(end 208 117)
		(width 0.4)
		(layer "B.Cu")
		(net 3)
	)
	(segment
		(start 210 88.4)
		(end 210 91.2)
		(width 0.4)
		(layer "In2.Cu")
		(net 3)
	)
	(segment
		(start 225.6 114.1)
		(end 224.7 115)
		(width 0.4)
		(layer "In7.Cu")
		(net 3)
	)
	(segment
		(start 224.7 115)
		(end 214 115)
		(width 0.4)
		(layer "In7.Cu")
		(net 3)
	)
	(segment
		(start 225.6 114.1)
		(end 225.6 111.2)
		(width 0.4)
		(layer "In7.Cu")
		(net 3)
	)
	(via
		(at 193.5 186.5)
		(size 0.45)
		(drill 0.2)
		(layers "F.Cu" "B.Cu")
		(free yes)
		(net 4)
	)
	(via
		(at 193.5 187.5)
		(size 0.45)
		(drill 0.2)
		(layers "F.Cu" "B.Cu")
		(free yes)
		(net 4)
	)
	(via
		(at 193 189)
		(size 0.45)
		(drill 0.2)
		(layers "F.Cu" "B.Cu")
		(free yes)
		(net 4)
	)
	(via
		(at 193 188)
		(size 0.45)
		(drill 0.2)
		(layers "F.Cu" "B.Cu")
		(free yes)
		(net 4)
	)
	(via
		(at 193.5 188.5)
		(size 0.45)
		(drill 0.2)
		(layers "F.Cu" "B.Cu")
		(free yes)
		(net 4)
	)
	(via
		(at 193 187)
		(size 0.45)
		(drill 0.2)
		(layers "F.Cu" "B.Cu")
		(free yes)
		(net 4)
	)
	(segment
		(start 261.05 181.75)
		(end 261.05 179.75)
		(width 0.4)
		(layer "B.Cu")
		(net 4)
	)
	(segment
		(start 261.05 179.75)
		(end 261 179.7)
		(width 0.4)
		(layer "B.Cu")
		(net 4)
	)
	(segment
		(start 261.05 181.75)
		(end 263.015 181.75)
		(width 0.4)
		(layer "B.Cu")
		(net 4)
	)
	(segment
		(start 230.45 165.35)
		(end 229.66 165.35)
		(width 0.4)
		(layer "F.Cu")
		(net 5)
	)
	(segment
		(start 229.66 165.35)
		(end 229.65 165.36)
		(width 0.4)
		(layer "F.Cu")
		(net 5)
	)
	(via
		(at 230.45 165.35)
		(size 0.45)
		(drill 0.2)
		(layers "F.Cu" "B.Cu")
		(net 5)
	)
	(via
		(at 228.55 156.7495)
		(size 0.45)
		(drill 0.2)
		(layers "F.Cu" "B.Cu")
		(net 5)
	)
	(segment
		(start 230.45 165.9)
		(end 230.45 165.35)
		(width 0.4)
		(layer "B.Cu")
		(net 5)
	)
	(segment
		(start 230.45 165.35)
		(end 227.975 162.875)
		(width 0.4)
		(layer "In2.Cu")
		(net 5)
	)
	(segment
		(start 227.975 157.3245)
		(end 228.55 156.7495)
		(width 0.4)
		(layer "In2.Cu")
		(net 5)
	)
	(segment
		(start 227.975 162.875)
		(end 227.975 157.3245)
		(width 0.4)
		(layer "In2.Cu")
		(net 5)
	)
	(via
		(at 191.5 124.5)
		(size 0.45)
		(drill 0.2)
		(layers "F.Cu" "B.Cu")
		(net 6)
	)
	(via
		(at 154.6 160.6)
		(size 0.45)
		(drill 0.2)
		(layers "F.Cu" "B.Cu")
		(free yes)
		(net 6)
	)
	(via
		(at 190.49 112.38)
		(size 0.45)
		(drill 0.2)
		(layers "F.Cu" "B.Cu")
		(free yes)
		(net 6)
	)
	(via
		(at 191.5 118.5)
		(size 0.45)
		(drill 0.2)
		(layers "F.Cu" "B.Cu")
		(net 6)
	)
	(via
		(at 155 160)
		(size 0.45)
		(drill 0.2)
		(layers "F.Cu" "B.Cu")
		(free yes)
		(net 6)
	)
	(via
		(at 154.6 159.4)
		(size 0.45)
		(drill 0.2)
		(layers "F.Cu" "B.Cu")
		(free yes)
		(net 6)
	)
	(via
		(at 156.2 159.4)
		(size 0.45)
		(drill 0.2)
		(layers "F.Cu" "B.Cu")
		(free yes)
		(net 6)
	)
	(via
		(at 191.5 126.5)
		(size 0.45)
		(drill 0.2)
		(layers "F.Cu" "B.Cu")
		(net 6)
	)
	(via
		(at 191.5 122.5)
		(size 0.45)
		(drill 0.2)
		(layers "F.Cu" "B.Cu")
		(net 6)
	)
	(via
		(at 191.5 128.5)
		(size 0.45)
		(drill 0.2)
		(layers "F.Cu" "B.Cu")
		(net 6)
	)
	(via
		(at 191.5 120.5)
		(size 0.45)
		(drill 0.2)
		(layers "F.Cu" "B.Cu")
		(net 6)
	)
	(via
		(at 191.5 116.5)
		(size 0.45)
		(drill 0.2)
		(layers "F.Cu" "B.Cu")
		(net 6)
	)
	(via
		(at 156.2 160.6)
		(size 0.45)
		(drill 0.2)
		(layers "F.Cu" "B.Cu")
		(free yes)
		(net 6)
	)
	(via
		(at 155.4 160.6)
		(size 0.45)
		(drill 0.2)
		(layers "F.Cu" "B.Cu")
		(free yes)
		(net 6)
	)
	(via
		(at 191.500001 114)
		(size 0.45)
		(drill 0.2)
		(layers "F.Cu" "B.Cu")
		(net 6)
	)
	(via
		(at 155.8 160)
		(size 0.45)
		(drill 0.2)
		(layers "F.Cu" "B.Cu")
		(free yes)
		(net 6)
	)
	(via
		(at 155.4 159.4)
		(size 0.45)
		(drill 0.2)
		(layers "F.Cu" "B.Cu")
		(free yes)
		(net 6)
	)
	(segment
		(start 191.5 122.5)
		(end 191.5 122.38)
		(width 0.4)
		(layer "B.Cu")
		(net 6)
	)
	(segment
		(start 191.621178 128.426274)
		(end 192.073726 127.973726)
		(width 0.4)
		(layer "B.Cu")
		(net 6)
	)
	(segment
		(start 191.547452 120.5)
		(end 192.073726 119.973726)
		(width 0.4)
		(layer "B.Cu")
		(net 6)
	)
	(segment
		(start 191.226274 116.226274)
		(end 191.5 116.5)
		(width 0.4)
		(layer "B.Cu")
		(net 6)
	)
	(segment
		(start 191.5 120.5)
		(end 191.547452 120.5)
		(width 0.4)
		(layer "B.Cu")
		(net 6)
	)
	(segment
		(start 192.073726 115.973726)
		(end 192.026274 115.973726)
		(width 0.4)
		(layer "B.Cu")
		(net 6)
	)
	(segment
		(start 191.5 118.5)
		(end 191.5 118.48)
		(width 0.4)
		(layer "B.Cu")
		(net 6)
	)
	(segment
		(start 190.23 112.64)
		(end 190.49 112.38)
		(width 0.1)
		(layer "B.Cu")
		(net 6)
	)
	(segment
		(start 191.547452 124.5)
		(end 192.073726 123.973726)
		(width 0.4)
		(layer "B.Cu")
		(net 6)
	)
	(segment
		(start 191.500001 114)
		(end 191.9 114)
		(width 0.5)
		(layer "B.Cu")
		(net 6)
	)
	(segment
		(start 192.026274 115.973726)
		(end 191.5 116.5)
		(width 0.4)
		(layer "B.Cu")
		(net 6)
	)
	(segment
		(start 190.217 112.64)
		(end 190.23 112.64)
		(width 0.1)
		(layer "B.Cu")
		(net 6)
	)
	(segment
		(start 191.426274 128.426274)
		(end 191.621178 128.426274)
		(width 0.4)
		(layer "B.Cu")
		(net 6)
	)
	(via
		(at 164.599999 145.599999)
		(size 0.45)
		(drill 0.2)
		(layers "F.Cu" "B.Cu")
		(net 7)
	)
	(via
		(at 169.6 144.4)
		(size 0.45)
		(drill 0.2)
		(layers "F.Cu" "B.Cu")
		(net 7)
	)
	(via
		(at 175.225 148.3)
		(size 0.45)
		(drill 0.2)
		(layers "F.Cu" "B.Cu")
		(net 7)
	)
	(via
		(at 163.2 152.8)
		(size 0.45)
		(drill 0.2)
		(layers "F.Cu" "B.Cu")
		(free yes)
		(net 7)
	)
	(via
		(at 163.2 153.6)
		(size 0.45)
		(drill 0.2)
		(layers "F.Cu" "B.Cu")
		(free yes)
		(net 7)
	)
	(via
		(at 163.7 153.2)
		(size 0.45)
		(drill 0.2)
		(layers "F.Cu" "B.Cu")
		(free yes)
		(net 7)
	)
	(via
		(at 163.799999 145.599999)
		(size 0.45)
		(drill 0.2)
		(layers "F.Cu" "B.Cu")
		(net 7)
	)
	(via
		(at 163.7 152.4)
		(size 0.45)
		(drill 0.2)
		(layers "F.Cu" "B.Cu")
		(free yes)
		(net 7)
	)
	(via
		(at 165.599999 145.599999)
		(size 0.45)
		(drill 0.2)
		(layers "F.Cu" "B.Cu")
		(net 7)
	)
	(segment
		(start 169.500001 145.599999)
		(end 163.799999 145.599999)
		(width 0.5)
		(layer "In2.Cu")
		(net 7)
	)
	(segment
		(start 169.6 144.4)
		(end 169.6 145.5)
		(width 0.5)
		(layer "In2.Cu")
		(net 7)
	)
	(segment
		(start 175.049999 145.599999)
		(end 169.500001 145.599999)
		(width 0.5)
		(layer "In2.Cu")
		(net 7)
	)
	(segment
		(start 175.224999 148.299999)
		(end 175.224999 145.774999)
		(width 0.5)
		(layer "In2.Cu")
		(net 7)
	)
	(segment
		(start 175.224999 145.774999)
		(end 175.049999 145.599999)
		(width 0.5)
		(layer "In2.Cu")
		(net 7)
	)
	(segment
		(start 169.6 145.5)
		(end 169.500001 145.599999)
		(width 0.5)
		(layer "In2.Cu")
		(net 7)
	)
	(segment
		(start 152.3 142.8)
		(end 151.4 141.9)
		(width 0.5)
		(layer "F.Cu")
		(net 8)
	)
	(segment
		(start 155.8 142.8)
		(end 156.3 142.8)
		(width 0.5)
		(layer "F.Cu")
		(net 8)
	)
	(segment
		(start 156.3 142.8)
		(end 156.8 142.8)
		(width 0.5)
		(layer "F.Cu")
		(net 8)
	)
	(segment
		(start 155.3 142.8)
		(end 152.3 142.8)
		(width 0.5)
		(layer "F.Cu")
		(net 8)
	)
	(segment
		(start 151.4 141.9)
		(end 151.4 141.7)
		(width 0.5)
		(layer "F.Cu")
		(net 8)
	)
	(segment
		(start 155.3 142.8)
		(end 155.8 142.8)
		(width 0.5)
		(layer "F.Cu")
		(net 8)
	)
	(via
		(at 184.670001 127.500001)
		(size 0.45)
		(drill 0.2)
		(layers "F.Cu" "B.Cu")
		(net 8)
	)
	(via
		(at 184.670001 131.500001)
		(size 0.45)
		(drill 0.2)
		(layers "F.Cu" "B.Cu")
		(net 8)
	)
	(via
		(at 187.500001 118.500001)
		(size 0.45)
		(drill 0.2)
		(layers "F.Cu" "B.Cu")
		(net 8)
	)
	(via
		(at 189.5 131.5)
		(size 0.45)
		(drill 0.2)
		(layers "F.Cu" "B.Cu")
		(net 8)
	)
	(via
		(at 187.500001 124.500001)
		(size 0.45)
		(drill 0.2)
		(layers "F.Cu" "B.Cu")
		(net 8)
	)
	(via
		(at 187.500001 126.500001)
		(size 0.45)
		(drill 0.2)
		(layers "F.Cu" "B.Cu")
		(net 8)
	)
	(via
		(at 156.8 142.8)
		(size 0.45)
		(drill 0.2)
		(layers "F.Cu" "B.Cu")
		(net 8)
	)
	(via
		(at 189.5 117.5)
		(size 0.45)
		(drill 0.2)
		(layers "F.Cu" "B.Cu")
		(net 8)
	)
	(via
		(at 187.500001 116.500001)
		(size 0.45)
		(drill 0.2)
		(layers "F.Cu" "B.Cu")
		(net 8)
	)
	(via
		(at 189.5 123.5)
		(size 0.45)
		(drill 0.2)
		(layers "F.Cu" "B.Cu")
		(net 8)
	)
	(via
		(at 155.3 142.8)
		(size 0.45)
		(drill 0.2)
		(layers "F.Cu" "B.Cu")
		(net 8)
	)
	(via
		(at 156.3 142.8)
		(size 0.45)
		(drill 0.2)
		(layers "F.Cu" "B.Cu")
		(net 8)
	)
	(via
		(at 155.8 142.8)
		(size 0.45)
		(drill 0.2)
		(layers "F.Cu" "B.Cu")
		(net 8)
	)
	(via
		(at 189.5 133.5)
		(size 0.45)
		(drill 0.2)
		(layers "F.Cu" "B.Cu")
		(net 8)
	)
	(via
		(at 189.5 121.5)
		(size 0.45)
		(drill 0.2)
		(layers "F.Cu" "B.Cu")
		(net 8)
	)
	(via
		(at 189.5 125.5)
		(size 0.45)
		(drill 0.2)
		(layers "F.Cu" "B.Cu")
		(net 8)
	)
	(via
		(at 184.400001 133.500001)
		(size 0.45)
		(drill 0.2)
		(layers "F.Cu" "B.Cu")
		(net 8)
	)
	(via
		(at 189.5 129.5)
		(size 0.45)
		(drill 0.2)
		(layers "F.Cu" "B.Cu")
		(net 8)
	)
	(via
		(at 187.500001 120.500001)
		(size 0.45)
		(drill 0.2)
		(layers "F.Cu" "B.Cu")
		(net 8)
	)
	(via
		(at 187.500001 122.500001)
		(size 0.45)
		(drill 0.2)
		(layers "F.Cu" "B.Cu")
		(net 8)
	)
	(via
		(at 189.5 119.5)
		(size 0.45)
		(drill 0.2)
		(layers "F.Cu" "B.Cu")
		(net 8)
	)
	(via
		(at 187.500001 130.500001)
		(size 0.45)
		(drill 0.2)
		(layers "F.Cu" "B.Cu")
		(net 8)
	)
	(via
		(at 191.5 133.5)
		(size 0.45)
		(drill 0.2)
		(layers "F.Cu" "B.Cu")
		(net 8)
	)
	(via
		(at 189.5 127.5)
		(size 0.45)
		(drill 0.2)
		(layers "F.Cu" "B.Cu")
		(net 8)
	)
	(via
		(at 184.400001 132.500001)
		(size 0.45)
		(drill 0.2)
		(layers "F.Cu" "B.Cu")
		(net 8)
	)
	(via
		(at 186.956275 117.956275)
		(size 0.45)
		(drill 0.2)
		(layers "F.Cu" "B.Cu")
		(net 8)
	)
	(via
		(at 187.500001 132.500001)
		(size 0.45)
		(drill 0.2)
		(layers "F.Cu" "B.Cu")
		(net 8)
	)
	(via
		(at 187.500001 128.500001)
		(size 0.45)
		(drill 0.2)
		(layers "F.Cu" "B.Cu")
		(net 8)
	)
	(segment
		(start 184.800001 133.000001)
		(end 184.800001 133.100001)
		(width 0.4)
		(layer "B.Cu")
		(net 8)
	)
	(segment
		(start 187.500001 118.500001)
		(end 186.956275 117.956275)
		(width 0.4)
		(layer "B.Cu")
		(net 8)
	)
	(segment
		(start 191.5 133.485)
		(end 191.315 133.3)
		(width 0.4)
		(layer "B.Cu")
		(net 8)
	)
	(segment
		(start 184.800001 132.900001)
		(end 184.400001 132.500001)
		(width 0.4)
		(layer "B.Cu")
		(net 8)
	)
	(segment
		(start 187.500001 122.500001)
		(end 186.950001 121.950001)
		(width 0.4)
		(layer "B.Cu")
		(net 8)
	)
	(segment
		(start 184.800001 133.100001)
		(end 184.400001 133.500001)
		(width 0.4)
		(layer "B.Cu")
		(net 8)
	)
	(segment
		(start 184.800001 133.000001)
		(end 184.800001 132.900001)
		(width 0.4)
		(layer "B.Cu")
		(net 8)
	)
	(segment
		(start 191.5 133.5)
		(end 191.5 133.485)
		(width 0.4)
		(layer "B.Cu")
		(net 8)
	)
	(segment
		(start 221.1805 157.4895)
		(end 221.1805 156.7945)
		(width 0.153)
		(layer "F.Cu")
		(net 9)
	)
	(segment
		(start 221.7223 162.7545)
		(end 221.8593 162.6175)
		(width 0.153)
		(layer "F.Cu")
		(net 9)
	)
	(segment
		(start 221.1805 156.7945)
		(end 221.275 156.7)
		(width 0.153)
		(layer "F.Cu")
		(net 9)
	)
	(segment
		(start 220.9805 162.375234)
		(end 221.359766 162.7545)
		(width 0.153)
		(layer "F.Cu")
		(net 9)
	)
	(segment
		(start 198.1 132.0015)
		(end 198.1 131.9)
		(width 0.256)
		(layer "F.Cu")
		(net 9)
	)
	(segment
		(start 221.285 158.95)
		(end 220.9805 159.2545)
		(width 0.153)
		(layer "F.Cu")
		(net 9)
	)
	(segment
		(start 220.9805 159.2545)
		(end 220.9805 162.375234)
		(width 0.153)
		(layer "F.Cu")
		(net 9)
	)
	(segment
		(start 198.1 131.9)
		(end 198.5 131.5)
		(width 0.256)
		(layer "F.Cu")
		(net 9)
	)
	(segment
		(start 221.285 158.95)
		(end 220.9805 158.6455)
		(width 0.153)
		(layer "F.Cu")
		(net 9)
	)
	(segment
		(start 220.9805 157.6895)
		(end 221.1805 157.4895)
		(width 0.153)
		(layer "F.Cu")
		(net 9)
	)
	(segment
		(start 221.359766 162.7545)
		(end 221.7223 162.7545)
		(width 0.153)
		(layer "F.Cu")
		(net 9)
	)
	(segment
		(start 220.9805 158.6455)
		(end 220.9805 157.6895)
		(width 0.153)
		(layer "F.Cu")
		(net 9)
	)
	(segment
		(start 221.8593 162.6175)
		(end 222.4543 162.6175)
		(width 0.153)
		(layer "F.Cu")
		(net 9)
	)
	(via
		(at 221.275 156.7)
		(size 0.45)
		(drill 0.2)
		(layers "F.Cu" "B.Cu")
		(net 9)
	)
	(via
		(at 198.1 132.0015)
		(size 0.45)
		(drill 0.2)
		(layers "F.Cu" "B.Cu")
		(net 9)
	)
	(segment
		(start 194.45 146.858578)
		(end 192.7 148.608578)
		(width 0.1)
		(layer "In7.Cu")
		(net 9)
	)
	(segment
		(start 196.4 133.658578)
		(end 196.4 137.658578)
		(width 0.1)
		(layer "In7.Cu")
		(net 9)
	)
	(segment
		(start 192.7 154.241422)
		(end 205.908578 167.45)
		(width 0.1)
		(layer "In7.Cu")
		(net 9)
	)
	(segment
		(start 195.9 138.808578)
		(end 193.85 140.858578)
		(width 0.1)
		(layer "In7.Cu")
		(net 9)
	)
	(segment
		(start 198.1 132.0015)
		(end 198.4 132.3015)
		(width 0.1)
		(layer "In7.Cu")
		(net 9)
	)
	(segment
		(start 198.208578 133.4)
		(end 196.658578 133.4)
		(width 0.1)
		(layer "In7.Cu")
		(net 9)
	)
	(segment
		(start 205.908578 167.45)
		(end 216.691422 167.45)
		(width 0.1)
		(layer "In7.Cu")
		(net 9)
	)
	(segment
		(start 194.45 143.341422)
		(end 194.45 146.858578)
		(width 0.1)
		(layer "In7.Cu")
		(net 9)
	)
	(segment
		(start 193.85 140.858578)
		(end 193.85 142.741422)
		(width 0.1)
		(layer "In7.Cu")
		(net 9)
	)
	(segment
		(start 193.85 142.741422)
		(end 194.45 143.341422)
		(width 0.1)
		(layer "In7.Cu")
		(net 9)
	)
	(segment
		(start 221.1 156.875)
		(end 221.275 156.7)
		(width 0.1)
		(layer "In7.Cu")
		(net 9)
	)
	(segment
		(start 196.658578 133.4)
		(end 196.4 133.658578)
		(width 0.1)
		(layer "In7.Cu")
		(net 9)
	)
	(segment
		(start 192.7 148.608578)
		(end 192.7 154.241422)
		(width 0.1)
		(layer "In7.Cu")
		(net 9)
	)
	(segment
		(start 196.4 137.658578)
		(end 195.9 138.158578)
		(width 0.1)
		(layer "In7.Cu")
		(net 9)
	)
	(segment
		(start 198.4 132.3015)
		(end 198.4 133.208578)
		(width 0.1)
		(layer "In7.Cu")
		(net 9)
	)
	(segment
		(start 195.9 138.158578)
		(end 195.9 138.808578)
		(width 0.1)
		(layer "In7.Cu")
		(net 9)
	)
	(segment
		(start 198.4 133.208578)
		(end 198.208578 133.4)
		(width 0.1)
		(layer "In7.Cu")
		(net 9)
	)
	(segment
		(start 216.691422 167.45)
		(end 221.1 163.041422)
		(width 0.1)
		(layer "In7.Cu")
		(net 9)
	)
	(segment
		(start 221.1 163.041422)
		(end 221.1 156.875)
		(width 0.1)
		(layer "In7.Cu")
		(net 9)
	)
	(segment
		(start 221.210234 163.1155)
		(end 221.7223 163.1155)
		(width 0.153)
		(layer "F.Cu")
		(net 10)
	)
	(segment
		(start 220.6195 162.524766)
		(end 221.210234 163.1155)
		(width 0.153)
		(layer "F.Cu")
		(net 10)
	)
	(segment
		(start 220.315 158.95)
		(end 220.6195 159.2545)
		(width 0.153)
		(layer "F.Cu")
		(net 10)
	)
	(segment
		(start 221.7223 163.1155)
		(end 221.8593 163.2525)
		(width 0.153)
		(layer "F.Cu")
		(net 10)
	)
	(segment
		(start 221.8593 163.2525)
		(end 222.4543 163.2525)
		(width 0.153)
		(layer "F.Cu")
		(net 10)
	)
	(segment
		(start 198.9 132)
		(end 199 132)
		(width 0.256)
		(layer "F.Cu")
		(net 10)
	)
	(segment
		(start 220.8195 156.7945)
		(end 220.725 156.7)
		(width 0.153)
		(layer "F.Cu")
		(net 10)
	)
	(segment
		(start 220.6195 157.5205)
		(end 220.8195 157.3205)
		(width 0.153)
		(layer "F.Cu")
		(net 10)
	)
	(segment
		(start 220.6195 159.2545)
		(end 220.6195 162.524766)
		(width 0.153)
		(layer "F.Cu")
		(net 10)
	)
	(segment
		(start 220.8195 157.3205)
		(end 220.8195 156.7945)
		(width 0.153)
		(layer "F.Cu")
		(net 10)
	)
	(segment
		(start 220.315 158.95)
		(end 220.6195 158.6455)
		(width 0.153)
		(layer "F.Cu")
		(net 10)
	)
	(segment
		(start 199 132)
		(end 199.5 131.5)
		(width 0.256)
		(layer "F.Cu")
		(net 10)
	)
	(segment
		(start 220.6195 158.6455)
		(end 220.6195 157.5205)
		(width 0.153)
		(layer "F.Cu")
		(net 10)
	)
	(via
		(at 198.9 132)
		(size 0.45)
		(drill 0.2)
		(layers "F.Cu" "B.Cu")
		(net 10)
	)
	(via
		(at 220.725 156.7)
		(size 0.45)
		(drill 0.2)
		(layers "F.Cu" "B.Cu")
		(net 10)
	)
	(segment
		(start 205.991422 167.25)
		(end 216.608578 167.25)
		(width 0.1)
		(layer "In7.Cu")
		(net 10)
	)
	(segment
		(start 194.05 140.941422)
		(end 194.05 142.658578)
		(width 0.1)
		(layer "In7.Cu")
		(net 10)
	)
	(segment
		(start 194.65 146.941422)
		(end 192.9 148.691422)
		(width 0.1)
		(layer "In7.Cu")
		(net 10)
	)
	(segment
		(start 196.6 133.741422)
		(end 196.6 137.741422)
		(width 0.1)
		(layer "In7.Cu")
		(net 10)
	)
	(segment
		(start 192.9 154.158578)
		(end 205.991422 167.25)
		(width 0.1)
		(layer "In7.Cu")
		(net 10)
	)
	(segment
		(start 196.1 138.241422)
		(end 196.1 138.891422)
		(width 0.1)
		(layer "In7.Cu")
		(net 10)
	)
	(segment
		(start 198.6 133.291422)
		(end 198.291422 133.6)
		(width 0.1)
		(layer "In7.Cu")
		(net 10)
	)
	(segment
		(start 194.65 143.258578)
		(end 194.65 146.941422)
		(width 0.1)
		(layer "In7.Cu")
		(net 10)
	)
	(segment
		(start 196.741422 133.6)
		(end 196.6 133.741422)
		(width 0.1)
		(layer "In7.Cu")
		(net 10)
	)
	(segment
		(start 220.9 162.958578)
		(end 220.9 156.875)
		(width 0.1)
		(layer "In7.Cu")
		(net 10)
	)
	(segment
		(start 192.9 148.691422)
		(end 192.9 154.158578)
		(width 0.1)
		(layer "In7.Cu")
		(net 10)
	)
	(segment
		(start 198.6 132.3)
		(end 198.6 133.291422)
		(width 0.1)
		(layer "In7.Cu")
		(net 10)
	)
	(segment
		(start 216.608578 167.25)
		(end 220.9 162.958578)
		(width 0.1)
		(layer "In7.Cu")
		(net 10)
	)
	(segment
		(start 196.1 138.891422)
		(end 194.05 140.941422)
		(width 0.1)
		(layer "In7.Cu")
		(net 10)
	)
	(segment
		(start 220.9 156.875)
		(end 220.725 156.7)
		(width 0.1)
		(layer "In7.Cu")
		(net 10)
	)
	(segment
		(start 198.9 132)
		(end 198.6 132.3)
		(width 0.1)
		(layer "In7.Cu")
		(net 10)
	)
	(segment
		(start 198.291422 133.6)
		(end 196.741422 133.6)
		(width 0.1)
		(layer "In7.Cu")
		(net 10)
	)
	(segment
		(start 194.05 142.658578)
		(end 194.65 143.258578)
		(width 0.1)
		(layer "In7.Cu")
		(net 10)
	)
	(segment
		(start 196.6 137.741422)
		(end 196.1 138.241422)
		(width 0.1)
		(layer "In7.Cu")
		(net 10)
	)
	(segment
		(start 191 139)
		(end 191.5 138.5)
		(width 0.4)
		(layer "F.Cu")
		(net 11)
	)
	(segment
		(start 191.993793 142.006069)
		(end 191.993931 142.006069)
		(width 0.4)
		(layer "F.Cu")
		(net 11)
	)
	(segment
		(start 167.6 148)
		(end 168 148.4)
		(width 0.4)
		(layer "F.Cu")
		(net 11)
	)
	(segment
		(start 191.993931 142.006069)
		(end 192.5 141.5)
		(width 0.4)
		(layer "F.Cu")
		(net 11)
	)
	(segment
		(start 153.05 152.4)
		(end 153 152.35)
		(width 0.256)
		(layer "F.Cu")
		(net 11)
	)
	(segment
		(start 170.799999 142.400003)
		(end 170.799999 141.834316)
		(width 0.4)
		(layer "F.Cu")
		(net 11)
	)
	(segment
		(start 153.74 152.4)
		(end 153.05 152.4)
		(width 0.256)
		(layer "F.Cu")
		(net 11)
	)
	(segment
		(start 153.75 152.41)
		(end 153.74 152.4)
		(width 0.256)
		(layer "F.Cu")
		(net 11)
	)
	(segment
		(start 153.75 153.7)
		(end 153.75 152.41)
		(width 0.256)
		(layer "F.Cu")
		(net 11)
	)
	(via
		(at 191.993793 142.006069)
		(size 0.45)
		(drill 0.2)
		(layers "F.Cu" "B.Cu")
		(net 11)
	)
	(via
		(at 168 148.4)
		(size 0.45)
		(drill 0.2)
		(layers "F.Cu" "B.Cu")
		(net 11)
	)
	(via
		(at 170.799999 141.834316)
		(size 0.45)
		(drill 0.2)
		(layers "F.Cu" "B.Cu")
		(net 11)
	)
	(via
		(at 191 139)
		(size 0.45)
		(drill 0.2)
		(layers "F.Cu" "B.Cu")
		(net 11)
	)
	(via
		(at 166.75 150.4)
		(size 0.45)
		(drill 0.2)
		(layers "F.Cu" "B.Cu")
		(net 11)
	)
	(via
		(at 153 152.35)
		(size 0.45)
		(drill 0.2)
		(layers "F.Cu" "B.Cu")
		(net 11)
	)
	(segment
		(start 191.993793 141.993793)
		(end 191.993793 142.006069)
		(width 0.4)
		(layer "B.Cu")
		(net 11)
	)
	(segment
		(start 191.5 141.5)
		(end 191.993793 141.993793)
		(width 0.4)
		(layer "B.Cu")
		(net 11)
	)
	(segment
		(start 191 139)
		(end 190.5 138.5)
		(width 0.4)
		(layer "B.Cu")
		(net 11)
	)
	(segment
		(start 166.75 150.4)
		(end 167.05 150.1)
		(width 0.4)
		(layer "In2.Cu")
		(net 11)
	)
	(segment
		(start 168.3 150.1)
		(end 168.45 150.25)
		(width 0.4)
		(layer "In2.Cu")
		(net 11)
	)
	(segment
		(start 175.55 148.85)
		(end 176.05 148.35)
		(width 0.4)
		(layer "In2.Cu")
		(net 11)
	)
	(segment
		(start 169.85 150.25)
		(end 170 150.1)
		(width 0.4)
		(layer "In2.Cu")
		(net 11)
	)
	(segment
		(start 170 150.1)
		(end 174.9 150.1)
		(width 0.4)
		(layer "In2.Cu")
		(net 11)
	)
	(segment
		(start 168.45 150.25)
		(end 168.45 150.65)
		(width 0.4)
		(layer "In2.Cu")
		(net 11)
	)
	(segment
		(start 175.25 149)
		(end 175.4 148.85)
		(width 0.4)
		(layer "In2.Cu")
		(net 11)
	)
	(segment
		(start 176.05 148.35)
		(end 176.05 147.75)
		(width 0.4)
		(layer "In2.Cu")
		(net 11)
	)
	(segment
		(start 167.05 150.1)
		(end 168.3 150.1)
		(width 0.4)
		(layer "In2.Cu")
		(net 11)
	)
	(segment
		(start 175.25 149.75)
		(end 175.25 149)
		(width 0.4)
		(layer "In2.Cu")
		(net 11)
	)
	(segment
		(start 169.5 150.95)
		(end 169.85 150.6)
		(width 0.4)
		(layer "In2.Cu")
		(net 11)
	)
	(segment
		(start 168.45 150.65)
		(end 168.75 150.95)
		(width 0.4)
		(layer "In2.Cu")
		(net 11)
	)
	(segment
		(start 169.85 150.6)
		(end 169.85 150.25)
		(width 0.4)
		(layer "In2.Cu")
		(net 11)
	)
	(segment
		(start 175.4 148.85)
		(end 175.55 148.85)
		(width 0.4)
		(layer "In2.Cu")
		(net 11)
	)
	(segment
		(start 174.9 150.1)
		(end 175.25 149.75)
		(width 0.4)
		(layer "In2.Cu")
		(net 11)
	)
	(segment
		(start 168.75 150.95)
		(end 169.5 150.95)
		(width 0.4)
		(layer "In2.Cu")
		(net 11)
	)
	(segment
		(start 167.225 139.15)
		(end 168.115683 139.15)
		(width 0.4)
		(layer "In3.Cu")
		(net 11)
	)
	(segment
		(start 162.3 150.2)
		(end 155.15 150.2)
		(width 0.4)
		(layer "In3.Cu")
		(net 11)
	)
	(segment
		(start 168.25 150.2)
		(end 166.7 150.2)
		(width 0.4)
		(layer "In3.Cu")
		(net 11)
	)
	(segment
		(start 168.7 149.75)
		(end 168.25 150.2)
		(width 0.4)
		(layer "In3.Cu")
		(net 11)
	)
	(segment
		(start 162.3 150.2)
		(end 162.3 141.8)
		(width 0.4)
		(layer "In3.Cu")
		(net 11)
	)
	(segment
		(start 168.7 149.05)
		(end 168.7 149.75)
		(width 0.4)
		(layer "In3.Cu")
		(net 11)
	)
	(segment
		(start 168.115683 139.15)
		(end 170.799999 141.834316)
		(width 0.4)
		(layer "In3.Cu")
		(net 11)
	)
	(segment
		(start 166.7 150.2)
		(end 162.3 150.2)
		(width 0.4)
		(layer "In3.Cu")
		(net 11)
	)
	(segment
		(start 155.15 150.2)
		(end 153 152.35)
		(width 0.4)
		(layer "In3.Cu")
		(net 11)
	)
	(segment
		(start 166.7 150.35)
		(end 166.75 150.4)
		(width 0.4)
		(layer "In3.Cu")
		(net 11)
	)
	(segment
		(start 162.3 141.8)
		(end 163.9 140.2)
		(width 0.4)
		(layer "In3.Cu")
		(net 11)
	)
	(segment
		(start 166.175 140.2)
		(end 167.225 139.15)
		(width 0.4)
		(layer "In3.Cu")
		(net 11)
	)
	(segment
		(start 163.9 140.2)
		(end 166.175 140.2)
		(width 0.4)
		(layer "In3.Cu")
		(net 11)
	)
	(segment
		(start 166.7 150.2)
		(end 166.7 150.35)
		(width 0.4)
		(layer "In3.Cu")
		(net 11)
	)
	(segment
		(start 168.050004 148.400004)
		(end 168.7 149.05)
		(width 0.4)
		(layer "In3.Cu")
		(net 11)
	)
	(segment
		(start 168 148.400004)
		(end 168.050004 148.400004)
		(width 0.4)
		(layer "In3.Cu")
		(net 11)
	)
	(segment
		(start 245.2 165)
		(end 246.443 165)
		(width 0.256)
		(layer "B.Cu")
		(net 12)
	)
	(segment
		(start 246.443 165)
		(end 246.641 164.802)
		(width 0.256)
		(layer "B.Cu")
		(net 12)
	)
	(segment
		(start 245.185 166)
		(end 245.185 165.015)
		(width 0.256)
		(layer "B.Cu")
		(net 12)
	)
	(segment
		(start 245.185 165.015)
		(end 245.2 165)
		(width 0.256)
		(layer "B.Cu")
		(net 12)
	)
	(segment
		(start 261.6 84.8)
		(end 264.75 84.8)
		(width 0.1)
		(layer "F.Cu")
		(net 13)
	)
	(segment
		(start 264.75 84.8)
		(end 266.485 84.8)
		(width 0.1)
		(layer "F.Cu")
		(net 13)
	)
	(segment
		(start 194.5 135.5)
		(end 194 136)
		(width 0.256)
		(layer "F.Cu")
		(net 13)
	)
	(segment
		(start 268.85 84.8)
		(end 267.115 84.8)
		(width 0.1)
		(layer "F.Cu")
		(net 13)
	)
	(segment
		(start 266.485 84.8)
		(end 266.8 84.485)
		(width 0.1)
		(layer "F.Cu")
		(net 13)
	)
	(segment
		(start 267.115 84.8)
		(end 266.8 84.485)
		(width 0.1)
		(layer "F.Cu")
		(net 13)
	)
	(via
		(at 266.8 84.485)
		(size 0.45)
		(drill 0.2)
		(layers "F.Cu" "B.Cu")
		(net 13)
	)
	(via
		(at 264.75 84.7)
		(size 0.45)
		(drill 0.2)
		(layers "F.Cu" "B.Cu")
		(net 13)
	)
	(via
		(at 261.6 84.8)
		(size 0.45)
		(drill 0.2)
		(layers "F.Cu" "B.Cu")
		(net 13)
	)
	(via
		(at 194 136)
		(size 0.45)
		(drill 0.2)
		(layers "F.Cu" "B.Cu")
		(net 13)
	)
	(segment
		(start 261.8 84.6)
		(end 261.6 84.8)
		(width 0.1)
		(layer "In3.Cu")
		(net 13)
	)
	(segment
		(start 208.025 83.773)
		(end 207.388 83.136)
		(width 0.1)
		(layer "In3.Cu")
		(net 13)
	)
	(segment
		(start 207.388 76.294842)
		(end 210.682842 73)
		(width 0.1)
		(layer "In3.Cu")
		(net 13)
	)
	(segment
		(start 207.388 83.136)
		(end 207.388 76.294842)
		(width 0.1)
		(layer "In3.Cu")
		(net 13)
	)
	(segment
		(start 195.175 132.4)
		(end 195.42 132.155)
		(width 0.1)
		(layer "In3.Cu")
		(net 13)
	)
	(segment
		(start 208.025 95.425)
		(end 208.025 83.773)
		(width 0.1)
		(layer "In3.Cu")
		(net 13)
	)
	(segment
		(start 260 73)
		(end 261.8 74.8)
		(width 0.1)
		(layer "In3.Cu")
		(net 13)
	)
	(segment
		(start 194 136)
		(end 193.4 135.4)
		(width 0.1)
		(layer "In3.Cu")
		(net 13)
	)
	(segment
		(start 195.42 108.03)
		(end 208.025 95.425)
		(width 0.1)
		(layer "In3.Cu")
		(net 13)
	)
	(segment
		(start 193.4 135.4)
		(end 193.4 132.742158)
		(width 0.1)
		(layer "In3.Cu")
		(net 13)
	)
	(segment
		(start 193.742158 132.4)
		(end 195.175 132.4)
		(width 0.1)
		(layer "In3.Cu")
		(net 13)
	)
	(segment
		(start 195.42 132.155)
		(end 195.42 108.03)
		(width 0.1)
		(layer "In3.Cu")
		(net 13)
	)
	(segment
		(start 193.4 132.742158)
		(end 193.742158 132.4)
		(width 0.1)
		(layer "In3.Cu")
		(net 13)
	)
	(segment
		(start 261.8 74.8)
		(end 261.8 84.6)
		(width 0.1)
		(layer "In3.Cu")
		(net 13)
	)
	(segment
		(start 210.682842 73)
		(end 260 73)
		(width 0.1)
		(layer "In3.Cu")
		(net 13)
	)
	(segment
		(start 169.2 188.7)
		(end 169.915 188.7)
		(width 0.1)
		(layer "F.Cu")
		(net 14)
	)
	(segment
		(start 168.5 188.4)
		(end 168.5 189.2)
		(width 0.182)
		(layer "F.Cu")
		(net 14)
	)
	(segment
		(start 168.9 188.4)
		(end 169.2 188.7)
		(width 0.1)
		(layer "F.Cu")
		(net 14)
	)
	(segment
		(start 168.5 188.4)
		(end 168.9 188.4)
		(width 0.1)
		(layer "F.Cu")
		(net 14)
	)
	(via
		(at 168.5 189.16)
		(size 0.45)
		(drill 0.2)
		(layers "F.Cu" "B.Cu")
		(net 14)
	)
	(segment
		(start 159.65 147.465)
		(end 159.215 147.9)
		(width 0.4)
		(layer "F.Cu")
		(net 15)
	)
	(segment
		(start 159.65 146.6)
		(end 159.65 147.465)
		(width 0.4)
		(layer "F.Cu")
		(net 15)
	)
	(segment
		(start 158.185 147.9)
		(end 159.215 147.9)
		(width 0.4)
		(layer "F.Cu")
		(net 15)
	)
	(segment
		(start 267.725 129.825)
		(end 268.125 129.825)
		(width 0.4)
		(layer "B.Cu")
		(net 16)
	)
	(segment
		(start 255.325 140.975)
		(end 253.075 140.975)
		(width 0.4)
		(layer "B.Cu")
		(net 16)
	)
	(segment
		(start 260.125 142.8)
		(end 259.15 142.8)
		(width 0.4)
		(layer "B.Cu")
		(net 16)
	)
	(segment
		(start 265.6 140.15)
		(end 265.6 142.025)
		(width 0.4)
		(layer "B.Cu")
		(net 16)
	)
	(segment
		(start 268.5 126.715)
		(end 268.485 126.7)
		(width 0.4)
		(layer "B.Cu")
		(net 16)
	)
	(segment
		(start 265.6 142.025)
		(end 266.9 143.325)
		(width 0.4)
		(layer "B.Cu")
		(net 16)
	)
	(segment
		(start 256.125 142.975)
		(end 256.125 141.775)
		(width 0.4)
		(layer "B.Cu")
		(net 16)
	)
	(segment
		(start 259.15 142.8)
		(end 256.9 145.05)
		(width 0.4)
		(layer "B.Cu")
		(net 16)
	)
	(segment
		(start 266.3 131.775)
		(end 265.6 132.475)
		(width 0.4)
		(layer "B.Cu")
		(net 16)
	)
	(segment
		(start 267.725 129.825)
		(end 266.9 129.825)
		(width 0.4)
		(layer "B.Cu")
		(net 16)
	)
	(segment
		(start 255 144.1)
		(end 256.125 142.975)
		(width 0.4)
		(layer "B.Cu")
		(net 16)
	)
	(segment
		(start 266.9 143.325)
		(end 268.175 143.325)
		(width 0.4)
		(layer "B.Cu")
		(net 16)
	)
	(segment
		(start 262.775 140.15)
		(end 260.125 142.8)
		(width 0.4)
		(layer "B.Cu")
		(net 16)
	)
	(segment
		(start 268.125 129.825)
		(end 268.5 129.45)
		(width 0.4)
		(layer "B.Cu")
		(net 16)
	)
	(segment
		(start 255 144.825)
		(end 255 144.1)
		(width 0.4)
		(layer "B.Cu")
		(net 16)
	)
	(segment
		(start 265.6 132.475)
		(end 265.6 140.15)
		(width 0.4)
		(layer "B.Cu")
		(net 16)
	)
	(segment
		(start 263 132.475)
		(end 260.35 129.825)
		(width 0.4)
		(layer "B.Cu")
		(net 16)
	)
	(segment
		(start 255.225 145.05)
		(end 255 144.825)
		(width 0.4)
		(layer "B.Cu")
		(net 16)
	)
	(segment
		(start 265.6 140.15)
		(end 262.775 140.15)
		(width 0.4)
		(layer "B.Cu")
		(net 16)
	)
	(segment
		(start 268.5 129.45)
		(end 268.5 126.715)
		(width 0.4)
		(layer "B.Cu")
		(net 16)
	)
	(segment
		(start 265.6 132.475)
		(end 263 132.475)
		(width 0.4)
		(layer "B.Cu")
		(net 16)
	)
	(segment
		(start 256.125 141.775)
		(end 255.325 140.975)
		(width 0.4)
		(layer "B.Cu")
		(net 16)
	)
	(segment
		(start 266.3 130.425)
		(end 266.3 131.775)
		(width 0.4)
		(layer "B.Cu")
		(net 16)
	)
	(segment
		(start 266.9 129.825)
		(end 266.3 130.425)
		(width 0.4)
		(layer "B.Cu")
		(net 16)
	)
	(segment
		(start 260.35 129.825)
		(end 257.375 129.825)
		(width 0.4)
		(layer "B.Cu")
		(net 16)
	)
	(segment
		(start 256.9 145.05)
		(end 255.225 145.05)
		(width 0.4)
		(layer "B.Cu")
		(net 16)
	)
	(segment
		(start 207.225 74.955)
		(end 207.99 75.72)
		(width 0.182)
		(layer "F.Cu")
		(net 17)
	)
	(segment
		(start 206.69 74.955)
		(end 207.225 74.955)
		(width 0.182)
		(layer "F.Cu")
		(net 17)
	)
	(segment
		(start 256.13 185.77)
		(end 256.13 184.745)
		(width 0.1)
		(layer "F.Cu")
		(net 18)
	)
	(segment
		(start 256.31 185.95)
		(end 256.13 185.77)
		(width 0.1)
		(layer "F.Cu")
		(net 18)
	)
	(segment
		(start 266.385 148.3)
		(end 267.55 148.3)
		(width 0.177)
		(layer "B.Cu")
		(net 19)
	)
	(segment
		(start 266.385 145.35)
		(end 267.55 145.35)
		(width 0.177)
		(layer "B.Cu")
		(net 20)
	)
	(segment
		(start 259.35 86.2)
		(end 260.75 86.2)
		(width 0.1)
		(layer "F.Cu")
		(net 21)
	)
	(segment
		(start 259.35 88.6)
		(end 260.75 88.6)
		(width 0.1)
		(layer "F.Cu")
		(net 22)
	)
	(segment
		(start 259.35 91)
		(end 260.75 91)
		(width 0.1)
		(layer "F.Cu")
		(net 23)
	)
	(segment
		(start 233.87765 118.05265)
		(end 233.87765 118.02)
		(width 0.4)
		(layer "F.Cu")
		(net 24)
	)
	(segment
		(start 239.05 132.3)
		(end 239.05 133.1)
		(width 0.177)
		(layer "F.Cu")
		(net 24)
	)
	(segment
		(start 238.8 127.315)
		(end 238.8 127.075)
		(width 0.4)
		(layer "F.Cu")
		(net 24)
	)
	(segment
		(start 239 146.2)
		(end 239 148.07)
		(width 0.4)
		(layer "F.Cu")
		(net 24)
	)
	(segment
		(start 150.85 156.6)
		(end 150.85 155.89)
		(width 0.4)
		(layer "F.Cu")
		(net 24)
	)
	(segment
		(start 153.75 155.7)
		(end 153.75 156.1)
		(width 0.4)
		(layer "F.Cu")
		(net 24)
	)
	(segment
		(start 199.4 105.37)
		(end 199.79 104.98)
		(width 0.4)
		(layer "F.Cu")
		(net 24)
	)
	(segment
		(start 234.91 118.02)
		(end 235.43 117.5)
		(width 0.4)
		(layer "F.Cu")
		(net 24)
	)
	(segment
		(start 203.4 115.22)
		(end 203.4 114.82)
		(width 0.4)
		(layer "F.Cu")
		(net 24)
	)
	(segment
		(start 152.985 148.15)
		(end 152.985 147.95)
		(width 0.4)
		(layer "F.Cu")
		(net 24)
	)
	(segment
		(start 211.5 129.5)
		(end 212 129)
		(width 0.4)
		(layer "F.Cu")
		(net 24)
	)
	(segment
		(start 210.5 136.5)
		(end 211 137)
		(width 0.4)
		(layer "F.Cu")
		(net 24)
	)
	(segment
		(start 163.448001 126.148001)
		(end 163.905001 125.691001)
		(width 0.182)
		(layer "F.Cu")
		(net 24)
	)
	(segment
		(start 238.935188 149.204812)
		(end 238.91 149.179624)
		(width 0.4)
		(layer "F.Cu")
		(net 24)
	)
	(segment
		(start 199.79 104.98)
		(end 199.79 103.1)
		(width 0.4)
		(layer "F.Cu")
		(net 24)
	)
	(segment
		(start 200.0245 116.899501)
		(end 200 116.875001)
		(width 0.182)
		(layer "F.Cu")
		(net 24)
	)
	(segment
		(start 220.8 155.7)
		(end 219.9 154.8)
		(width 0.256)
		(layer "F.Cu")
		(net 24)
	)
	(segment
		(start 151.95 166.05)
		(end 152 166.1)
		(width 0.4)
		(layer "F.Cu")
		(net 24)
	)
	(segment
		(start 199.4 106.2)
		(end 199.4 105.37)
		(width 0.4)
		(layer "F.Cu")
		(net 24)
	)
	(segment
		(start 211.5 139.5)
		(end 212 140)
		(width 0.4)
		(layer "F.Cu")
		(net 24)
	)
	(segment
		(start 196.5 124.5)
		(end 196 124)
		(width 0.4)
		(layer "F.Cu")
		(net 24)
	)
	(segment
		(start 220.675 140.925)
		(end 220.05 141.55)
		(width 0.256)
		(layer "F.Cu")
		(net 24)
	)
	(segment
		(start 153.6 156.25)
		(end 152.595 156.25)
		(width 0.4)
		(layer "F.Cu")
		(net 24)
	)
	(segment
		(start 238.8 127.075)
		(end 239.2 126.675)
		(width 0.4)
		(layer "F.Cu")
		(net 24)
	)
	(segment
		(start 153.715 155.735)
		(end 153.75 155.7)
		(width 0.4)
		(layer "F.Cu")
		(net 24)
	)
	(segment
		(start 233.9 146)
		(end 233.8 145.9)
		(width 0.201)
		(layer "F.Cu")
		(net 24)
	)
	(segment
		(start 219.285 165.7)
		(end 220.315 165.7)
		(width 0.4)
		(layer "F.Cu")
		(net 24)
	)
	(segment
		(start 198.66 106.52)
		(end 198.98 106.2)
		(width 0.4)
		(layer "F.Cu")
		(net 24)
	)
	(segment
		(start 163.905001 128.225001)
		(end 163.905001 128.332601)
		(width 0.182)
		(layer "F.Cu")
		(net 24)
	)
	(segment
		(start 196.291252 95.65)
		(end 196.341252 95.6)
		(width 0.182)
		(layer "F.Cu")
		(net 24)
	)
	(segment
		(start 200.0245 116.9755)
		(end 200.0245 116.899501)
		(width 0.182)
		(layer "F.Cu")
		(net 24)
	)
	(segment
		(start 208.751 77.833)
		(end 208.751 74.981)
		(width 0.182)
		(layer "F.Cu")
		(net 24)
	)
	(segment
		(start 200.2 98.141252)
		(end 200.091252 98.25)
		(width 0.182)
		(layer "F.Cu")
		(net 24)
	)
	(segment
		(start 235.43 116.535)
		(end 235.44 116.525)
		(width 0.201)
		(layer "F.Cu")
		(net 24)
	)
	(segment
		(start 219.29 141.55)
		(end 218.715 140.975)
		(width 0.256)
		(layer "F.Cu")
		(net 24)
	)
	(segment
		(start 239 148.07)
		(end 238.91 148.16)
		(width 0.4)
		(layer "F.Cu")
		(net 24)
	)
	(segment
		(start 192.6 113)
		(end 190.5 110.9)
		(width 0.4)
		(layer "F.Cu")
		(net 24)
	)
	(segment
		(start 220.315 166.485)
		(end 220.2 166.6)
		(width 0.4)
		(layer "F.Cu")
		(net 24)
	)
	(segment
		(start 233.9 146.5)
		(end 233.9 146)
		(width 0.201)
		(layer "F.Cu")
		(net 24)
	)
	(segment
		(start 195.5 121.5)
		(end 195 121)
		(width 0.4)
		(layer "F.Cu")
		(net 24)
	)
	(segment
		(start 153.715 157)
		(end 153.715 155.735)
		(width 0.4)
		(layer "F.Cu")
		(net 24)
	)
	(segment
		(start 233.54 85.84)
		(end 233.54 86.2225)
		(width 0.5)
		(layer "F.Cu")
		(net 24)
	)
	(segment
		(start 202.7 88.875)
		(end 202.65 88.825)
		(width 0.182)
		(layer "F.Cu")
		(net 24)
	)
	(segment
		(start 220.3 138.425)
		(end 219.685 138.425)
		(width 0.256)
		(layer "F.Cu")
		(net 24)
	)
	(segment
		(start 221.4 140.925)
		(end 220.675 140.925)
		(width 0.256)
		(layer "F.Cu")
		(net 24)
	)
	(segment
		(start 200.2 98.808748)
		(end 200.241252 98.85)
		(width 0.256)
		(layer "F.Cu")
		(net 24)
	)
	(segment
		(start 220.05 141.55)
		(end 219.29 141.55)
		(width 0.256)
		(layer "F.Cu")
		(net 24)
	)
	(segment
		(start 152.985 147.95)
		(end 153.8 147.135)
		(width 0.4)
		(layer "F.Cu")
		(net 24)
	)
	(segment
		(start 196.341252 95.6)
		(end 198.022851 95.6)
		(width 0.182)
		(layer "F.Cu")
		(net 24)
	)
	(segment
		(start 198.98 106.2)
		(end 199.4 106.2)
		(width 0.4)
		(layer "F.Cu")
		(net 24)
	)
	(segment
		(start 220.315 165.7)
		(end 220.315 165.0568)
		(width 0.4)
		(layer "F.Cu")
		(net 24)
	)
	(segment
		(start 238.65 133.1)
		(end 238.85 133.3)
		(width 0.182)
		(layer "F.Cu")
		(net 24)
	)
	(segment
		(start 163.905001 130.765001)
		(end 163.905001 131.509301)
		(width 0.182)
		(layer "F.Cu")
		(net 24)
	)
	(segment
		(start 155.1 150.2375)
		(end 153.3375 150.2375)
		(width 0.4)
		(layer "F.Cu")
		(net 24)
	)
	(segment
		(start 233.635 94.51)
		(end 233.635 92.835)
		(width 0.5)
		(layer "F.Cu")
		(net 24)
	)
	(segment
		(start 208.751 74.981)
		(end 207.99 74.22)
		(width 0.182)
		(layer "F.Cu")
		(net 24)
	)
	(segment
		(start 195.67663 96.347131)
		(end 196.291252 95.732509)
		(width 0.182)
		(layer "F.Cu")
		(net 24)
	)
	(segment
		(start 163.905001 128.332601)
		(end 163.411201 128.826401)
		(width 0.182)
		(layer "F.Cu")
		(net 24)
	)
	(segment
		(start 233.87765 118.02)
		(end 234.91 118.02)
		(width 0.4)
		(layer "F.Cu")
		(net 24)
	)
	(segment
		(start 204.5 138.5)
		(end 205 139)
		(width 0.4)
		(layer "F.Cu")
		(net 24)
	)
	(segment
		(start 152.46 157.19)
		(end 151.95 157.7)
		(width 0.4)
		(layer "F.Cu")
		(net 24)
	)
	(segment
		(start 234.2 146.6)
		(end 234 146.6)
		(width 0.201)
		(layer "F.Cu")
		(net 24)
	)
	(segment
		(start 209.5 143.5)
		(end 210 144)
		(width 0.4)
		(layer "F.Cu")
		(net 24)
	)
	(segment
		(start 151.95 157.7)
		(end 151.95 166.05)
		(width 0.4)
		(layer "F.Cu")
		(net 24)
	)
	(segment
		(start 202.5 122.5)
		(end 203 122)
		(width 0.4)
		(layer "F.Cu")
		(net 24)
	)
	(segment
		(start 232.275 117.2)
		(end 233.095 118.02)
		(width 0.4)
		(layer "F.Cu")
		(net 24)
	)
	(segment
		(start 239.05 133.1)
		(end 238.85 133.3)
		(width 0.177)
		(layer "F.Cu")
		(net 24)
	)
	(segment
		(start 234.35 118.525)
		(end 233.87765 118.05265)
		(width 0.4)
		(layer "F.Cu")
		(net 24)
	)
	(segment
		(start 223.625 130.275)
		(end 224 130.65)
		(width 0.184)
		(layer "F.Cu")
		(net 24)
	)
	(segment
		(start 208.751 74.989)
		(end 209.52 74.22)
		(width 0.182)
		(layer "F.Cu")
		(net 24)
	)
	(segment
		(start 219.715 154.615)
		(end 219.9 154.8)
		(width 0.256)
		(layer "F.Cu")
		(net 24)
	)
	(segment
		(start 233.095 118.02)
		(end 233.87765 118.02)
		(width 0.4)
		(layer "F.Cu")
		(net 24)
	)
	(segment
		(start 203.5 125.5)
		(end 204 125)
		(width 0.4)
		(layer "F.Cu")
		(net 24)
	)
	(segment
		(start 191.55 107.5)
		(end 191.3 107.25)
		(width 0.4)
		(layer "F.Cu")
		(net 24)
	)
	(segment
		(start 163.905001 131.509301)
		(end 163.919201 131.523501)
		(width 0.182)
		(layer "F.Cu")
		(net 24)
	)
	(segment
		(start 218.725 139.975)
		(end 219.685 139.015)
		(width 0.256)
		(layer "F.Cu")
		(net 24)
	)
	(segment
		(start 196.291252 95.732509)
		(end 196.291252 95.65)
		(width 0.182)
		(layer "F.Cu")
		(net 24)
	)
	(segment
		(start 208.751 77.833)
		(end 208.751 74.989)
		(width 0.182)
		(layer "F.Cu")
		(net 24)
	)
	(segment
		(start 238.942482 140.042482)
		(end 239.1 140.2)
		(width 0.182)
		(layer "F.Cu")
		(net 24)
	)
	(segment
		(start 198.5 120.5)
		(end 198 120)
		(width 0.4)
		(layer "F.Cu")
		(net 24)
	)
	(segment
		(start 205.5 121.5)
		(end 206 121)
		(width 0.4)
		(layer "F.Cu")
		(net 24)
	)
	(segment
		(start 200.415 110.82)
		(end 200.415 110.385)
		(width 0.4)
		(layer "F.Cu")
		(net 24)
	)
	(segment
		(start 231.095 146.445)
		(end 230.89 146.65)
		(width 0.4)
		(layer "F.Cu")
		(net 24)
	)
	(segment
		(start 234.3 147.2)
		(end 234.3 146.7)
		(width 0.201)
		(layer "F.Cu")
		(net 24)
	)
	(segment
		(start 219.685 139.015)
		(end 219.685 138.425)
		(width 0.256)
		(layer "F.Cu")
		(net 24)
	)
	(segment
		(start 234.405 118.525)
		(end 234.91 118.02)
		(width 0.4)
		(layer "F.Cu")
		(net 24)
	)
	(segment
		(start 198.44 107.5)
		(end 198.66 107.28)
		(width 0.4)
		(layer "F.Cu")
		(net 24)
	)
	(segment
		(start 196.31 96.980501)
		(end 196.31 97.075)
		(width 0.182)
		(layer "F.Cu")
		(net 24)
	)
	(segment
		(start 212.5 142.5)
		(end 213 143)
		(width 0.4)
		(layer "F.Cu")
		(net 24)
	)
	(segment
		(start 239.35 139.95)
		(end 239.1 140.2)
		(width 0.177)
		(layer "F.Cu")
		(net 24)
	)
	(segment
		(start 200.2 97.277149)
		(end 200.2 98.141252)
		(width 0.182)
		(layer "F.Cu")
		(net 24)
	)
	(segment
		(start 203.5 115.32)
		(end 203.43 115.25)
		(width 0.4)
		(layer "F.Cu")
		(net 24)
	)
	(segment
		(start 219.285 158.95)
		(end 219.285 158.315)
		(width 0.201)
		(layer "F.Cu")
		(net 24)
	)
	(segment
		(start 150.85 155.89)
		(end 151.49 155.25)
		(width 0.4)
		(layer "F.Cu")
		(net 24)
	)
	(segment
		(start 212.5 132.5)
		(end 213 133)
		(width 0.4)
		(layer "F.Cu")
		(net 24)
	)
	(segment
		(start 225.975 117.5)
		(end 226.275 117.2)
		(width 0.4)
		(layer "F.Cu")
		(net 24)
	)
	(segment
		(start 229.135 145.885)
		(end 231.095 145.885)
		(width 0.4)
		(layer "F.Cu")
		(net 24)
	)
	(segment
		(start 207.5 137.5)
		(end 208 138)
		(width 0.4)
		(layer "F.Cu")
		(net 24)
	)
	(segment
		(start 152.985 149.215)
		(end 152.985 148.15)
		(width 0.4)
		(layer "F.Cu")
		(net 24)
	)
	(segment
		(start 214.5 138.5)
		(end 215 139)
		(width 0.4)
		(layer "F.Cu")
		(net 24)
	)
	(segment
		(start 209.5 133.5)
		(end 210 134)
		(width 0.4)
		(layer "F.Cu")
		(net 24)
	)
	(segment
		(start 151.95 157.7)
		(end 150.85 156.6)
		(width 0.4)
		(layer "F.Cu")
		(net 24)
	)
	(segment
		(start 163.905001 125.691001)
		(end 163.905001 125.685001)
		(width 0.182)
		(layer "F.Cu")
		(net 24)
	)
	(segment
		(start 214.5 128.5)
		(end 215 128)
		(width 0.4)
		(layer "F.Cu")
		(net 24)
	)
	(segment
		(start 208.56 98.85)
		(end 209 98.41)
		(width 0.4)
		(layer "F.Cu")
		(net 24)
	)
	(segment
		(start 195.67663 96.347131)
		(end 196.31 96.980501)
		(width 0.182)
		(layer "F.Cu")
		(net 24)
	)
	(segment
		(start 167.75 131.65)
		(end 168.100002 131.65)
		(width 0.4)
		(layer "F.Cu")
		(net 24)
	)
	(segment
		(start 219.875 131.025)
		(end 219.5 130.65)
		(width 0.184)
		(layer "F.Cu")
		(net 24)
	)
	(segment
		(start 204.5 118.5)
		(end 205 118)
		(width 0.4)
		(layer "F.Cu")
		(net 24)
	)
	(segment
		(start 203.43 115.25)
		(end 203.4 115.22)
		(width 0.4)
		(layer "F.Cu")
		(net 24)
	)
	(segment
		(start 206.5 134.5)
		(end 207 135)
		(width 0.4)
		(layer "F.Cu")
		(net 24)
	)
	(segment
		(start 218.8 154.615)
		(end 219.715 154.615)
		(width 0.256)
		(layer "F.Cu")
		(net 24)
	)
	(segment
		(start 225.51 117.5)
		(end 225.975 117.5)
		(width 0.4)
		(layer "F.Cu")
		(net 24)
	)
	(segment
		(start 153.75 156.1)
		(end 153.6 156.25)
		(width 0.4)
		(layer "F.Cu")
		(net 24)
	)
	(segment
		(start 153.3375 150.2375)
		(end 152.65 149.55)
		(width 0.4)
		(layer "F.Cu")
		(net 24)
	)
	(segment
		(start 207.929 98.85)
		(end 208.56 98.85)
		(width 0.4)
		(layer "F.Cu")
		(net 24)
	)
	(segment
		(start 199.5 123.5)
		(end 199 123)
		(width 0.4)
		(layer "F.Cu")
		(net 24)
	)
	(segment
		(start 205.5 141.5)
		(end 206 142)
		(width 0.4)
		(layer "F.Cu")
		(net 24)
	)
	(segment
		(start 229.09 145.84)
		(end 229.135 145.885)
		(width 0.4)
		(layer "F.Cu")
		(net 24)
	)
	(segment
		(start 209 95.84)
		(end 210.16 94.68)
		(width 0.4)
		(layer "F.Cu")
		(net 24)
	)
	(segment
		(start 151.49 150.71)
		(end 152.65 149.55)
		(width 0.4)
		(layer "F.Cu")
		(net 24)
	)
	(segment
		(start 151.49 155.25)
		(end 151.49 150.71)
		(width 0.4)
		(layer "F.Cu")
		(net 24)
	)
	(segment
		(start 192.85 107.5)
		(end 191.55 107.5)
		(width 0.4)
		(layer "F.Cu")
		(net 24)
	)
	(segment
		(start 193.5 130.5)
		(end 193 130)
		(width 0.4)
		(layer "F.Cu")
		(net 24)
	)
	(segment
		(start 220.315 165.7)
		(end 220.315 166.485)
		(width 0.4)
		(layer "F.Cu")
		(net 24)
	)
	(segment
		(start 220.315 165.0568)
		(end 221.4843 163.8875)
		(width 0.4)
		(layer "F.Cu")
		(net 24)
	)
	(segment
		(start 220.4 138.325)
		(end 220.3 138.425)
		(width 0.256)
		(layer "F.Cu")
		(net 24)
	)
	(segment
		(start 239.35 139.2)
		(end 239.35 139.95)
		(width 0.177)
		(layer "F.Cu")
		(net 24)
	)
	(segment
		(start 225.985 130.215)
		(end 225.5 130.215)
		(width 0.256)
		(layer "F.Cu")
		(net 24)
	)
	(segment
		(start 208.125 81.75)
		(end 208.125 83.405)
		(width 0.182)
		(layer "F.Cu")
		(net 24)
	)
	(segment
		(start 233.635 92.835)
		(end 233.6 92.8)
		(width 0.5)
		(layer "F.Cu")
		(net 24)
	)
	(segment
		(start 219.285 158.315)
		(end 219.4 158.2)
		(width 0.201)
		(layer "F.Cu")
		(net 24)
	)
	(segment
		(start 238.91 149.179624)
		(end 238.91 148.16)
		(width 0.4)
		(layer "F.Cu")
		(net 24)
	)
	(segment
		(start 226.275 117.2)
		(end 232.275 117.2)
		(width 0.4)
		(layer "F.Cu")
		(net 24)
	)
	(segment
		(start 197.5 117.5)
		(end 197 117)
		(width 0.4)
		(layer "F.Cu")
		(net 24)
	)
	(segment
		(start 210.345 81.74)
		(end 210.345 83.395)
		(width 0.182)
		(layer "F.Cu")
		(net 24)
	)
	(segment
		(start 206.5 144.5)
		(end 207 145)
		(width 0.4)
		(layer "F.Cu")
		(net 24)
	)
	(segment
		(start 197.8 107.5)
		(end 198.44 107.5)
		(width 0.4)
		(layer "F.Cu")
		(net 24)
	)
	(segment
		(start 194.5 118.5)
		(end 194 118)
		(width 0.4)
		(layer "F.Cu")
		(net 24)
	)
	(segment
		(start 200.5 116.5)
		(end 200.0245 116.9755)
		(width 0.4)
		(layer "F.Cu")
		(net 24)
	)
	(segment
		(start 208.5 130.5)
		(end 209 131)
		(width 0.4)
		(layer "F.Cu")
		(net 24)
	)
	(segment
		(start 205.5 131.5)
		(end 206 132)
		(width 0.4)
		(layer "F.Cu")
		(net 24)
	)
	(segment
		(start 201.5 119.5)
		(end 202 119)
		(width 0.4)
		(layer "F.Cu")
		(net 24)
	)
	(segment
		(start 234 146.6)
		(end 233.9 146.5)
		(width 0.201)
		(layer "F.Cu")
		(net 24)
	)
	(segment
		(start 234.3 146.7)
		(end 234.2 146.6)
		(width 0.201)
		(layer "F.Cu")
		(net 24)
	)
	(segment
		(start 190.5 136.5)
		(end 190 137)
		(width 0.4)
		(layer "F.Cu")
		(net 24)
	)
	(segment
		(start 190.5 110.9)
		(end 190.5 107.6)
		(width 0.4)
		(layer "F.Cu")
		(net 24)
	)
	(segment
		(start 193.1 112.5)
		(end 193.815 112.5)
		(width 0.182)
		(layer "F.Cu")
		(net 24)
	)
	(segment
		(start 213.5 135.5)
		(end 214 136)
		(width 0.4)
		(layer "F.Cu")
		(net 24)
	)
	(segment
		(start 233.8 145.9)
		(end 232.73 145.9)
		(width 0.4)
		(layer "F.Cu")
		(net 24)
	)
	(segment
		(start 238.942482 139.5995)
		(end 238.942482 140.042482)
		(width 0.182)
		(layer "F.Cu")
		(net 24)
	)
	(segment
		(start 231.095 145.885)
		(end 231.095 146.445)
		(width 0.4)
		(layer "F.Cu")
		(net 24)
	)
	(segment
		(start 200.415 110.385)
		(end 200 109.97)
		(width 0.4)
		(layer "F.Cu")
		(net 24)
	)
	(segment
		(start 190.5 107.6)
		(end 190.85 107.25)
		(width 0.4)
		(layer "F.Cu")
		(net 24)
	)
	(segment
		(start 202.7 90.422851)
		(end 202.7 88.875)
		(width 0.182)
		(layer "F.Cu")
		(net 24)
	)
	(segment
		(start 233.5 85.8)
		(end 233.54 85.84)
		(width 0.5)
		(layer "F.Cu")
		(net 24)
	)
	(segment
		(start 208.5 140.5)
		(end 209 141)
		(width 0.4)
		(layer "F.Cu")
		(net 24)
	)
	(segment
		(start 168.100002 131.65)
		(end 168.985001 130.765001)
		(width 0.4)
		(layer "F.Cu")
		(net 24)
	)
	(segment
		(start 165.175001 129.495001)
		(end 163.905001 128.225001)
		(width 0.182)
		(layer "F.Cu")
		(net 24)
	)
	(segment
		(start 200.2 97.277149)
		(end 200.2 98.808748)
		(width 0.256)
		(layer "F.Cu")
		(net 24)
	)
	(segment
		(start 218.715 139.975)
		(end 218.725 139.975)
		(width 0.256)
		(layer "F.Cu")
		(net 24)
	)
	(segment
		(start 231.095 145.885)
		(end 232.8 145.885)
		(width 0.4)
		(layer "F.Cu")
		(net 24)
	)
	(segment
		(start 226 130.2)
		(end 225.985 130.215)
		(width 0.256)
		(layer "F.Cu")
		(net 24)
	)
	(segment
		(start 212 130)
		(end 211.5 129.5)
		(width 0.4)
		(layer "F.Cu")
		(net 24)
	)
	(segment
		(start 192.6 113)
		(end 193.1 112.5)
		(width 0.182)
		(layer "F.Cu")
		(net 24)
	)
	(segment
		(start 218.715 140.975)
		(end 218.715 139.975)
		(width 0.256)
		(layer "F.Cu")
		(net 24)
	)
	(segment
		(start 198.66 107.28)
		(end 198.66 106.52)
		(width 0.4)
		(layer "F.Cu")
		(net 24)
	)
	(segment
		(start 233.9 147.2)
		(end 233.9 146.5)
		(width 0.201)
		(layer "F.Cu")
		(net 24)
	)
	(segment
		(start 235.43 117.5)
		(end 235.43 116.535)
		(width 0.201)
		(layer "F.Cu")
		(net 24)
	)
	(segment
		(start 152.46 156.225)
		(end 152.46 157.19)
		(width 0.4)
		(layer "F.Cu")
		(net 24)
	)
	(segment
		(start 221.4843 163.8875)
		(end 222.4543 163.8875)
		(width 0.4)
		(layer "F.Cu")
		(net 24)
	)
	(segment
		(start 152.65 149.55)
		(end 152.985 149.215)
		(width 0.4)
		(layer "F.Cu")
		(net 24)
	)
	(segment
		(start 238.65 132.7)
		(end 238.65 133.1)
		(width 0.182)
		(layer "F.Cu")
		(net 24)
	)
	(segment
		(start 234.35 118.525)
		(end 234.405 118.525)
		(width 0.4)
		(layer "F.Cu")
		(net 24)
	)
	(segment
		(start 203.5 115.5)
		(end 203.5 115.32)
		(width 0.4)
		(layer "F.Cu")
		(net 24)
	)
	(segment
		(start 190.85 107.25)
		(end 191.3 107.25)
		(width 0.4)
		(layer "F.Cu")
		(net 24)
	)
	(segment
		(start 221.4 138.325)
		(end 220.4 138.325)
		(width 0.256)
		(layer "F.Cu")
		(net 24)
	)
	(segment
		(start 209 98.41)
		(end 209 95.84)
		(width 0.4)
		(layer "F.Cu")
		(net 24)
	)
	(via
		(at 230.89 146.65)
		(size 0.45)
		(drill 0.2)
		(layers "F.Cu" "B.Cu")
		(net 24)
	)
	(via
		(at 214 136)
		(size 0.45)
		(drill 0.2)
		(layers "F.Cu" "B.Cu")
		(net 24)
	)
	(via
		(at 194 118)
		(size 0.45)
		(drill 0.2)
		(layers "F.Cu" "B.Cu")
		(net 24)
	)
	(via
		(at 207 135)
		(size 0.45)
		(drill 0.2)
		(layers "F.Cu" "B.Cu")
		(net 24)
	)
	(via
		(at 218.715 139.975)
		(size 0.45)
		(drill 0.2)
		(layers "F.Cu" "B.Cu")
		(net 24)
	)
	(via
		(at 195 76)
		(size 0.45)
		(drill 0.2)
		(layers "F.Cu" "B.Cu")
		(net 24)
	)
	(via
		(at 181.4 178)
		(size 0.45)
		(drill 0.2)
		(layers "F.Cu" "B.Cu")
		(free yes)
		(net 24)
	)
	(via
		(at 163.448001 126.148001)
		(size 0.45)
		(drill 0.2)
		(layers "F.Cu" "B.Cu")
		(net 24)
	)
	(via
		(at 202.101 73.748)
		(size 0.45)
		(drill 0.2)
		(layers "F.Cu" "B.Cu")
		(net 24)
	)
	(via
		(at 158.2 118.7)
		(size 0.45)
		(drill 0.2)
		(layers "F.Cu" "B.Cu")
		(free yes)
		(net 24)
	)
	(via
		(at 176.7 159.8)
		(size 0.45)
		(drill 0.2)
		(layers "F.Cu" "B.Cu")
		(free yes)
		(net 24)
	)
	(via
		(at 181.4 177.4)
		(size 0.45)
		(drill 0.2)
		(layers "F.Cu" "B.Cu")
		(free yes)
		(net 24)
	)
	(via
		(at 155.7 118.7)
		(size 0.45)
		(drill 0.2)
		(layers "F.Cu" "B.Cu")
		(free yes)
		(net 24)
	)
	(via
		(at 176.1 160.395389)
		(size 0.45)
		(drill 0.2)
		(layers "F.Cu" "B.Cu")
		(free yes)
		(net 24)
	)
	(via
		(at 209 131)
		(size 0.45)
		(drill 0.2)
		(layers "F.Cu" "B.Cu")
		(net 24)
	)
	(via
		(at 205.75 84.5)
		(size 0.45)
		(drill 0.2)
		(layers "F.Cu" "B.Cu")
		(free yes)
		(net 24)
	)
	(via
		(at 208.360001 146.857)
		(size 0.45)
		(drill 0.2)
		(layers "F.Cu" "B.Cu")
		(net 24)
	)
	(via
		(at 206 142)
		(size 0.45)
		(drill 0.2)
		(layers "F.Cu" "B.Cu")
		(net 24)
	)
	(via
		(at 206 121)
		(size 0.45)
		(drill 0.2)
		(layers "F.Cu" "B.Cu")
		(net 24)
	)
	(via
		(at 207.25 84.5)
		(size 0.45)
		(drill 0.2)
		(layers "F.Cu" "B.Cu")
		(free yes)
		(net 24)
	)
	(via
		(at 238.942482 139.5995)
		(size 0.45)
		(drill 0.2)
		(layers "F.Cu" "B.Cu")
		(net 24)
	)
	(via
		(at 251.2 171.2)
		(size 0.45)
		(drill 0.2)
		(layers "F.Cu" "B.Cu")
		(net 24)
	)
	(via
		(at 263.2 151.6)
		(size 0.45)
		(drill 0.2)
		(layers "F.Cu" "B.Cu")
		(net 24)
	)
	(via
		(at 152 166.1)
		(size 0.45)
		(drill 0.2)
		(layers "F.Cu" "B.Cu")
		(net 24)
	)
	(via
		(at 202 119)
		(size 0.45)
		(drill 0.2)
		(layers "F.Cu" "B.Cu")
		(net 24)
	)
	(via
		(at 177.3 161)
		(size 0.45)
		(drill 0.2)
		(layers "F.Cu" "B.Cu")
		(free yes)
		(net 24)
	)
	(via
		(at 210 144)
		(size 0.45)
		(drill 0.2)
		(layers "F.Cu" "B.Cu")
		(net 24)
	)
	(via
		(at 198.5 83.5)
		(size 0.45)
		(drill 0.2)
		(layers "F.Cu" "B.Cu")
		(free yes)
		(net 24)
	)
	(via
		(at 205 139)
		(size 0.45)
		(drill 0.2)
		(layers "F.Cu" "B.Cu")
		(net 24)
	)
	(via
		(at 197.5 83.5)
		(size 0.45)
		(drill 0.2)
		(layers "F.Cu" "B.Cu")
		(free yes)
		(net 24)
	)
	(via
		(at 208 138)
		(size 0.45)
		(drill 0.2)
		(layers "F.Cu" "B.Cu")
		(net 24)
	)
	(via
		(at 176.1 161)
		(size 0.45)
		(drill 0.2)
		(layers "F.Cu" "B.Cu")
		(free yes)
		(net 24)
	)
	(via
		(at 200 116.875001)
		(size 0.45)
		(drill 0.2)
		(layers "F.Cu" "B.Cu")
		(net 24)
	)
	(via
		(at 208.751 77.833)
		(size 0.45)
		(drill 0.2)
		(layers "F.Cu" "B.Cu")
		(net 24)
	)
	(via
		(at 178.8 78.23)
		(size 0.45)
		(drill 0.2)
		(layers "F.Cu" "B.Cu")
		(net 24)
	)
	(via
		(at 177.3 159.8)
		(size 0.45)
		(drill 0.2)
		(layers "F.Cu" "B.Cu")
		(free yes)
		(net 24)
	)
	(via
		(at 215 128)
		(size 0.45)
		(drill 0.2)
		(layers "F.Cu" "B.Cu")
		(net 24)
	)
	(via
		(at 207 145)
		(size 0.45)
		(drill 0.2)
		(layers "F.Cu" "B.Cu")
		(net 24)
	)
	(via
		(at 233.6 92.8)
		(size 0.45)
		(drill 0.2)
		(layers "F.Cu" "B.Cu")
		(net 24)
	)
	(via
		(at 260.3 121.75)
		(size 0.45)
		(drill 0.2)
		(layers "F.Cu" "B.Cu")
		(net 24)
	)
	(via
		(at 205 83.75)
		(size 0.45)
		(drill 0.2)
		(layers "F.Cu" "B.Cu")
		(free yes)
		(net 24)
	)
	(via
		(at 200 122)
		(size 0.45)
		(drill 0.2)
		(layers "F.Cu" "B.Cu")
		(net 24)
	)
	(via
		(at 265.4 147.55)
		(size 0.45)
		(drill 0.2)
		(layers "F.Cu" "B.Cu")
		(net 24)
	)
	(via
		(at 200.091252 98.25)
		(size 0.45)
		(drill 0.2)
		(layers "F.Cu" "B.Cu")
		(net 24)
	)
	(via
		(at 203.4 114.82)
		(size 0.45)
		(drill 0.2)
		(layers "F.Cu" "B.Cu")
		(net 24)
	)
	(via
		(at 211 137)
		(size 0.45)
		(drill 0.2)
		(layers "F.Cu" "B.Cu")
		(net 24)
	)
	(via
		(at 176.7 161)
		(size 0.45)
		(drill 0.2)
		(layers "F.Cu" "B.Cu")
		(free yes)
		(net 24)
	)
	(via
		(at 195.8 90.8)
		(size 0.45)
		(drill 0.2)
		(layers "F.Cu" "B.Cu")
		(free yes)
		(net 24)
	)
	(via
		(at 215 139)
		(size 0.45)
		(drill 0.2)
		(layers "F.Cu" "B.Cu")
		(net 24)
	)
	(via
		(at 205.75 83.75)
		(size 0.45)
		(drill 0.2)
		(layers "F.Cu" "B.Cu")
		(free yes)
		(net 24)
	)
	(via
		(at 195 121)
		(size 0.45)
		(drill 0.2)
		(layers "F.Cu" "B.Cu")
		(net 24)
	)
	(via
		(at 167.75 131.65)
		(size 0.45)
		(drill 0.2)
		(layers "F.Cu" "B.Cu")
		(net 24)
	)
	(via
		(at 217.8 133.8)
		(size 0.45)
		(drill 0.2)
		(layers "F.Cu" "B.Cu")
		(net 24)
	)
	(via
		(at 213 133)
		(size 0.45)
		(drill 0.2)
		(layers "F.Cu" "B.Cu")
		(net 24)
	)
	(via
		(at 204 125)
		(size 0.45)
		(drill 0.2)
		(layers "F.Cu" "B.Cu")
		(net 24)
	)
	(via
		(at 198.5 82.5)
		(size 0.45)
		(drill 0.2)
		(layers "F.Cu" "B.Cu")
		(free yes)
		(net 24)
	)
	(via
		(at 213 143)
		(size 0.45)
		(drill 0.2)
		(layers "F.Cu" "B.Cu")
		(net 24)
	)
	(via
		(at 212 140)
		(size 0.45)
		(drill 0.2)
		(layers "F.Cu" "B.Cu")
		(net 24)
	)
	(via
		(at 207.25 83.75)
		(size 0.45)
		(drill 0.2)
		(layers "F.Cu" "B.Cu")
		(free yes)
		(net 24)
	)
	(via
		(at 233.5 85.8)
		(size 0.45)
		(drill 0.2)
		(layers "F.Cu" "B.Cu")
		(net 24)
	)
	(via
		(at 175.5 161)
		(size 0.45)
		(drill 0.2)
		(layers "F.Cu" "B.Cu")
		(free yes)
		(net 24)
	)
	(via
		(at 156.9 118.7)
		(size 0.45)
		(drill 0.2)
		(layers "F.Cu" "B.Cu")
		(free yes)
		(net 24)
	)
	(via
		(at 234.35 118.525)
		(size 0.45)
		(drill 0.2)
		(layers "F.Cu" "B.Cu")
		(net 24)
	)
	(via
		(at 259.2 171.2)
		(size 0.45)
		(drill 0.2)
		(layers "F.Cu" "B.Cu")
		(net 24)
	)
	(via
		(at 190 137)
		(size 0.45)
		(drill 0.2)
		(layers "F.Cu" "B.Cu")
		(net 24)
	)
	(via
		(at 204.101 73.748)
		(size 0.45)
		(drill 0.2)
		(layers "F.Cu" "B.Cu")
		(net 24)
	)
	(via
		(at 198 120)
		(size 0.45)
		(drill 0.2)
		(layers "F.Cu" "B.Cu")
		(net 24)
	)
	(via
		(at 210 134)
		(size 0.45)
		(drill 0.2)
		(layers "F.Cu" "B.Cu")
		(net 24)
	)
	(via
		(at 199.79 103.1)
		(size 0.45)
		(drill 0.2)
		(layers "F.Cu" "B.Cu")
		(net 24)
	)
	(via
		(at 193 130)
		(size 0.45)
		(drill 0.2)
		(layers "F.Cu" "B.Cu")
		(net 24)
	)
	(via
		(at 220.8 155.7)
		(size 0.45)
		(drill 0.2)
		(layers "F.Cu" "B.Cu")
		(net 24)
	)
	(via
		(at 163.919201 131.523501)
		(size 0.45)
		(drill 0.2)
		(layers "F.Cu" "B.Cu")
		(net 24)
	)
	(via
		(at 238.65 132.7)
		(size 0.45)
		(drill 0.2)
		(layers "F.Cu" "B.Cu")
		(net 24)
	)
	(via
		(at 219.5 130.65)
		(size 0.45)
		(drill 0.2)
		(layers "F.Cu" "B.Cu")
		(net 24)
	)
	(via
		(at 181.4 176.8)
		(size 0.45)
		(drill 0.2)
		(layers "F.Cu" "B.Cu")
		(free yes)
		(net 24)
	)
	(via
		(at 195.67663 96.347131)
		(size 0.45)
		(drill 0.2)
		(layers "F.Cu" "B.Cu")
		(net 24)
	)
	(via
		(at 196.5 82.5)
		(size 0.45)
		(drill 0.2)
		(layers "F.Cu" "B.Cu")
		(free yes)
		(net 24)
	)
	(via
		(at 206.5 83.75)
		(size 0.45)
		(drill 0.2)
		(layers "F.Cu" "B.Cu")
		(free yes)
		(net 24)
	)
	(via
		(at 206.5 84.5)
		(size 0.45)
		(drill 0.2)
		(layers "F.Cu" "B.Cu")
		(free yes)
		(net 24)
	)
	(via
		(at 205 84.5)
		(size 0.45)
		(drill 0.2)
		(layers "F.Cu" "B.Cu")
		(free yes)
		(net 24)
	)
	(via
		(at 203.101 73.748)
		(size 0.45)
		(drill 0.2)
		(layers "F.Cu" "B.Cu")
		(net 24)
	)
	(via
		(at 188.100001 79.300001)
		(size 0.45)
		(drill 0.2)
		(layers "F.Cu" "B.Cu")
		(net 24)
	)
	(via
		(at 205 118)
		(size 0.45)
		(drill 0.2)
		(layers "F.Cu" "B.Cu")
		(net 24)
	)
	(via
		(at 174.9 159.8)
		(size 0.45)
		(drill 0.2)
		(layers "F.Cu" "B.Cu")
		(free yes)
		(net 24)
	)
	(via
		(at 244 128.8)
		(size 0.45)
		(drill 0.2)
		(layers "F.Cu" "B.Cu")
		(net 24)
	)
	(via
		(at 195.4 90.2)
		(size 0.45)
		(drill 0.2)
		(layers "F.Cu" "B.Cu")
		(free yes)
		(net 24)
	)
	(via
		(at 180.6 177.4)
		(size 0.45)
		(drill 0.2)
		(layers "F.Cu" "B.Cu")
		(free yes)
		(net 24)
	)
	(via
		(at 175.5 160.4)
		(size 0.45)
		(drill 0.2)
		(layers "F.Cu" "B.Cu")
		(free yes)
		(net 24)
	)
	(via
		(at 219.4 158.2)
		(size 0.45)
		(drill 0.2)
		(layers "F.Cu" "B.Cu")
		(net 24)
	)
	(via
		(at 203 122)
		(size 0.45)
		(drill 0.2)
		(layers "F.Cu" "B.Cu")
		(net 24)
	)
	(via
		(at 231.9 151.4)
		(size 0.45)
		(drill 0.2)
		(layers "F.Cu" "B.Cu")
		(net 24)
	)
	(via
		(at 200 109.97)
		(size 0.45)
		(drill 0.2)
		(layers "F.Cu" "B.Cu")
		(net 24)
	)
	(via
		(at 254.8 132.925)
		(size 0.45)
		(drill 0.2)
		(layers "F.Cu" "B.Cu")
		(net 24)
	)
	(via
		(at 197 117)
		(size 0.45)
		(drill 0.2)
		(layers "F.Cu" "B.Cu")
		(net 24)
	)
	(via
		(at 174.9 161)
		(size 0.45)
		(drill 0.2)
		(layers "F.Cu" "B.Cu")
		(free yes)
		(net 24)
	)
	(via
		(at 225.51 117.5)
		(size 0.45)
		(drill 0.2)
		(layers "F.Cu" "B.Cu")
		(net 24)
	)
	(via
		(at 194.6 90.2)
		(size 0.45)
		(drill 0.2)
		(layers "F.Cu" "B.Cu")
		(free yes)
		(net 24)
	)
	(via
		(at 209 141)
		(size 0.45)
		(drill 0.2)
		(layers "F.Cu" "B.Cu")
		(net 24)
	)
	(via
		(at 199 123)
		(size 0.45)
		(drill 0.2)
		(layers "F.Cu" "B.Cu")
		(net 24)
	)
	(via
		(at 180.6 176.8)
		(size 0.45)
		(drill 0.2)
		(layers "F.Cu" "B.Cu")
		(free yes)
		(net 24)
	)
	(via
		(at 177.3 160.4)
		(size 0.45)
		(drill 0.2)
		(layers "F.Cu" "B.Cu")
		(free yes)
		(net 24)
	)
	(via
		(at 212 130)
		(size 0.45)
		(drill 0.2)
		(layers "F.Cu" "B.Cu")
		(net 24)
	)
	(via
		(at 200 119)
		(size 0.45)
		(drill 0.2)
		(layers "F.Cu" "B.Cu")
		(net 24)
	)
	(via
		(at 196 124)
		(size 0.45)
		(drill 0.2)
		(layers "F.Cu" "B.Cu")
		(net 24)
	)
	(via
		(at 225.51 120.5)
		(size 0.45)
		(drill 0.2)
		(layers "F.Cu" "B.Cu")
		(net 24)
	)
	(via
		(at 180.6 178)
		(size 0.45)
		(drill 0.2)
		(layers "F.Cu" "B.Cu")
		(free yes)
		(net 24)
	)
	(via
		(at 210 130)
		(size 0.45)
		(drill 0.2)
		(layers "F.Cu" "B.Cu")
		(net 24)
	)
	(via
		(at 159.5 118.7)
		(size 0.45)
		(drill 0.2)
		(layers "F.Cu" "B.Cu")
		(free yes)
		(net 24)
	)
	(via
		(at 226 130.2)
		(size 0.45)
		(drill 0.2)
		(layers "F.Cu" "B.Cu")
		(net 24)
	)
	(via
		(at 202.65 88.8)
		(size 0.45)
		(drill 0.2)
		(layers "F.Cu" "B.Cu")
		(net 24)
	)
	(via
		(at 174.9 160.4)
		(size 0.45)
		(drill 0.2)
		(layers "F.Cu" "B.Cu")
		(free yes)
		(net 24)
	)
	(via
		(at 206 132)
		(size 0.45)
		(drill 0.2)
		(layers "F.Cu" "B.Cu")
		(net 24)
	)
	(via
		(at 224 130.65)
		(size 0.45)
		(drill 0.2)
		(layers "F.Cu" "B.Cu")
		(net 24)
	)
	(via
		(at 192.6 113)
		(size 0.45)
		(drill 0.2)
		(layers "F.Cu" "B.Cu")
		(net 24)
	)
	(via
		(at 212 129)
		(size 0.45)
		(drill 0.2)
		(layers "F.Cu" "B.Cu")
		(net 24)
	)
	(via
		(at 175.5 159.8)
		(size 0.45)
		(drill 0.2)
		(layers "F.Cu" "B.Cu")
		(free yes)
		(net 24)
	)
	(via
		(at 163.411201 128.826401)
		(size 0.45)
		(drill 0.2)
		(layers "F.Cu" "B.Cu")
		(net 24)
	)
	(via
		(at 235.43 119.5)
		(size 0.45)
		(drill 0.2)
		(layers "F.Cu" "B.Cu")
		(net 24)
	)
	(via
		(at 239.2 126.675)
		(size 0.45)
		(drill 0.2)
		(layers "F.Cu" "B.Cu")
		(net 24)
	)
	(via
		(at 176.7 160.4)
		(size 0.45)
		(drill 0.2)
		(layers "F.Cu" "B.Cu")
		(free yes)
		(net 24)
	)
	(via
		(at 238.935188 149.204812)
		(size 0.45)
		(drill 0.2)
		(layers "F.Cu" "B.Cu")
		(net 24)
	)
	(via
		(at 196.5 83.5)
		(size 0.45)
		(drill 0.2)
		(layers "F.Cu" "B.Cu")
		(free yes)
		(net 24)
	)
	(via
		(at 220.2 166.6)
		(size 0.45)
		(drill 0.2)
		(layers "F.Cu" "B.Cu")
		(net 24)
	)
	(via
		(at 154.4 118.7)
		(size 0.45)
		(drill 0.2)
		(layers "F.Cu" "B.Cu")
		(free yes)
		(net 24)
	)
	(via
		(at 253.4 79.5)
		(size 0.45)
		(drill 0.2)
		(layers "F.Cu" "B.Cu")
		(net 24)
	)
	(via
		(at 176.1 159.8)
		(size 0.45)
		(drill 0.2)
		(layers "F.Cu" "B.Cu")
		(free yes)
		(net 24)
	)
	(via
		(at 195 90.8)
		(size 0.45)
		(drill 0.2)
		(layers "F.Cu" "B.Cu")
		(free yes)
		(net 24)
	)
	(via
		(at 197.5 82.5)
		(size 0.45)
		(drill 0.2)
		(layers "F.Cu" "B.Cu")
		(free yes)
		(net 24)
	)
	(segment
		(start 263.2 151.6)
		(end 262.6 151.6)
		(width 0.4)
		(layer "B.Cu")
		(net 24)
	)
	(segment
		(start 254 135.225)
		(end 254.8 134.425)
		(width 0.4)
		(layer "B.Cu")
		(net 24)
	)
	(segment
		(start 190.275 136.725)
		(end 190 137)
		(width 0.4)
		(layer "B.Cu")
		(net 24)
	)
	(segment
		(start 247.925 140.35)
		(end 247.925 137.825)
		(width 0.4)
		(layer "B.Cu")
		(net 24)
	)
	(segment
		(start 207.5 135.5)
		(end 207 135)
		(width 0.4)
		(layer "B.Cu")
		(net 24)
	)
	(segment
		(start 234.455 118.525)
		(end 235.43 119.5)
		(width 0.4)
		(layer "B.Cu")
		(net 24)
	)
	(segment
		(start 208.5 141.5)
		(end 209 141)
		(width 0.4)
		(layer "B.Cu")
		(net 24)
	)
	(segment
		(start 244.9 129.7)
		(end 244 128.8)
		(width 0.4)
		(layer "B.Cu")
		(net 24)
	)
	(segment
		(start 205.5 118.5)
		(end 205 118)
		(width 0.4)
		(layer "B.Cu")
		(net 24)
	)
	(segment
		(start 260.5 79.5)
		(end 261 79)
		(width 0.4)
		(layer "B.Cu")
		(net 24)
	)
	(segment
		(start 197.5 119.5)
		(end 198 120)
		(width 0.4)
		(layer "B.Cu")
		(net 24)
	)
	(segment
		(start 254.8 134.425)
		(end 254.8 132.925)
		(width 0.4)
		(layer "B.Cu")
		(net 24)
	)
	(segment
		(start 202.65 88.8)
		(end 202.65 89.865)
		(width 0.182)
		(layer "B.Cu")
		(net 24)
	)
	(segment
		(start 247.925 137.825)
		(end 249.765 135.985)
		(width 0.4)
		(layer "B.Cu")
		(net 24)
	)
	(segment
		(start 251.49 136.125)
		(end 251.35 135.985)
		(width 0.4)
		(layer "B.Cu")
		(net 24)
	)
	(segment
		(start 206.5 144.5)
		(end 207 145)
		(width 0.4)
		(layer "B.Cu")
		(net 24)
	)
	(segment
		(start 195.206252 96.817509)
		(end 195.206252 96.85)
		(width 0.182)
		(layer "B.Cu")
		(net 24)
	)
	(segment
		(start 260.5 80.6)
		(end 260.5 79.5)
		(width 0.4)
		(layer "B.Cu")
		(net 24)
	)
	(segment
		(start 199.95 99.3)
		(end 200.091252 99.158748)
		(width 0.177)
		(layer "B.Cu")
		(net 24)
	)
	(segment
		(start 200.232504 99.3)
		(end 200.316252 99.383748)
		(width 0.177)
		(layer "B.Cu")
		(net 24)
	)
	(segment
		(start 265.415 148.3)
		(end 265.415 147.565)
		(width 0.4)
		(layer "B.Cu")
		(net 24)
	)
	(segment
		(start 201.5 116.5)
		(end 201.48 116.48)
		(width 0.4)
		(layer "B.Cu")
		(net 24)
	)
	(segment
		(start 253.85 135.775)
		(end 254 135.625)
		(width 0.4)
		(layer "B.Cu")
		(net 24)
	)
	(segment
		(start 200.13 116.48)
		(end 200 116.35)
		(width 0.4)
		(layer "B.Cu")
		(net 24)
	)
	(segment
		(start 249.765 135.985)
		(end 251.35 135.985)
		(width 0.4)
		(layer "B.Cu")
		(net 24)
	)
	(segment
		(start 249.3 141.735)
		(end 249.3 141.725)
		(width 0.4)
		(layer "B.Cu")
		(net 24)
	)
	(segment
		(start 212.5 140.5)
		(end 212 140)
		(width 0.4)
		(layer "B.Cu")
		(net 24)
	)
	(segment
		(start 200.191252 99.258748)
		(end 200.091252 99.158748)
		(width 0.177)
		(layer "B.Cu")
		(net 24)
	)
	(segment
		(start 261.015 81.115)
		(end 260.5 80.6)
		(width 0.4)
		(layer "B.Cu")
		(net 24)
	)
	(segment
		(start 208.100001 147.13)
		(end 208.100001 147.117)
		(width 0.114)
		(layer "B.Cu")
		(net 24)
	)
	(segment
		(start 253.8 79.1)
		(end 253.4 79.5)
		(width 0.4)
		(layer "B.Cu")
		(net 24)
	)
	(segment
		(start 166.357601 117.877401)
		(end 166.357601 116.685201)
		(width 0.182)
		(layer "B.Cu")
		(net 24)
	)
	(segment
		(start 209.55 130)
		(end 210 130)
		(width 0.4)
		(layer "B.Cu")
		(net 24)
	)
	(segment
		(start 218.4 125.7)
		(end 218.4 124.4)
		(width 0.4)
		(layer "B.Cu")
		(net 24)
	)
	(segment
		(start 214.5 138.5)
		(end 215 139)
		(width 0.4)
		(layer "B.Cu")
		(net 24)
	)
	(segment
		(start 216.1 127.2)
		(end 216.1 126.9)
		(width 0.4)
		(layer "B.Cu")
		(net 24)
	)
	(segment
		(start 202.5575 89.9575)
		(end 202.2 90.315)
		(width 0.182)
		(layer "B.Cu")
		(net 24)
	)
	(segment
		(start 205.5 132.5)
		(end 206 132)
		(width 0.4)
		(layer "B.Cu")
		(net 24)
	)
	(segment
		(start 254 135.475)
		(end 254 135.225)
		(width 0.4)
		(layer "B.Cu")
		(net 24)
	)
	(segment
		(start 200.316252 99.383748)
		(end 200.191252 99.258748)
		(width 0.177)
		(layer "B.Cu")
		(net 24)
	)
	(segment
		(start 260.5 80.2)
		(end 256.8 80.2)
		(width 0.4)
		(layer "B.Cu")
		(net 24)
	)
	(segment
		(start 215.5 127.8)
		(end 216.1 127.2)
		(width 0.4)
		(layer "B.Cu")
		(net 24)
	)
	(segment
		(start 257.5 152.5)
		(end 261.7 152.5)
		(width 0.4)
		(layer "B.Cu")
		(net 24)
	)
	(segment
		(start 194.5 117.5)
		(end 194 118)
		(width 0.4)
		(layer "B.Cu")
		(net 24)
	)
	(segment
		(start 202.65 89.865)
		(end 202.5575 89.9575)
		(width 0.182)
		(layer "B.Cu")
		(net 24)
	)
	(segment
		(start 166.357601 116.685201)
		(end 165.849601 116.177201)
		(width 0.182)
		(layer "B.Cu")
		(net 24)
	)
	(segment
		(start 215.5 128)
		(end 215.5 127.8)
		(width 0.4)
		(layer "B.Cu")
		(net 24)
	)
	(segment
		(start 217.8 133.4)
		(end 217.8 132.2)
		(width 0.182)
		(layer "B.Cu")
		(net 24)
	)
	(segment
		(start 225.51 117.5)
		(end 225.51 120.5)
		(width 0.4)
		(layer "B.Cu")
		(net 24)
	)
	(segment
		(start 234.35 118.525)
		(end 234.455 118.525)
		(width 0.4)
		(layer "B.Cu")
		(net 24)
	)
	(segment
		(start 248.8875 82.6895)
		(end 248.8875 79.5025)
		(width 0.256)
		(layer "B.Cu")
		(net 24)
	)
	(segment
		(start 202.7425 89.9575)
		(end 202.5575 89.9575)
		(width 0.182)
		(layer "B.Cu")
		(net 24)
	)
	(segment
		(start 256.8 80.2)
		(end 255.7 79.1)
		(width 0.4)
		(layer "B.Cu")
		(net 24)
	)
	(segment
		(start 199.515 99.735)
		(end 199.95 99.3)
		(width 0.177)
		(layer "B.Cu")
		(net 24)
	)
	(segment
		(start 210.5 133.5)
		(end 210 134)
		(width 0.4)
		(layer "B.Cu")
		(net 24)
	)
	(segment
		(start 200 121.35)
		(end 199.9 121.25)
		(width 0.4)
		(layer "B.Cu")
		(net 24)
	)
	(segment
		(start 205.5 120.5)
		(end 206 121)
		(width 0.4)
		(layer "B.Cu")
		(net 24)
	)
	(segment
		(start 211.5 136.5)
		(end 211 137)
		(width 0.4)
		(layer "B.Cu")
		(net 24)
	)
	(segment
		(start 203.2 90.315)
		(end 203.1 90.315)
		(width 0.182)
		(layer "B.Cu")
		(net 24)
	)
	(segment
		(start 261.015 95.8)
		(end 261.015 81.115)
		(width 0.4)
		(layer "B.Cu")
		(net 24)
	)
	(segment
		(start 197.991252 99.735)
		(end 198.991252 99.735)
		(width 0.177)
		(layer "B.Cu")
		(net 24)
	)
	(segment
		(start 259.85 122.5)
		(end 260.3 122.5)
		(width 0.4)
		(layer "B.Cu")
		(net 24)
	)
	(segment
		(start 214.5 135.5)
		(end 214 136)
		(width 0.4)
		(layer "B.Cu")
		(net 24)
	)
	(segment
		(start 253.075 136.125)
		(end 253.5 136.125)
		(width 0.4)
		(layer "B.Cu")
		(net 24)
	)
	(segment
		(start 159.445001 79.445001)
		(end 159.448801 79.448801)
		(width 0.182)
		(layer "B.Cu")
		(net 24)
	)
	(segment
		(start 198.991252 99.735)
		(end 199.515 99.735)
		(width 0.177)
		(layer "B.Cu")
		(net 24)
	)
	(segment
		(start 238.65 137.7)
		(end 238.325 137.7)
		(width 0.256)
		(layer "B.Cu")
		(net 24)
	)
	(segment
		(start 208.62 147.116999)
		(end 208.360001 146.857)
		(width 0.114)
		(layer "B.Cu")
		(net 24)
	)
	(segment
		(start 202.5 122.5)
		(end 203 122)
		(width 0.4)
		(layer "B.Cu")
		(net 24)
	)
	(segment
		(start 210.5 144.5)
		(end 210 144)
		(width 0.4)
		(layer "B.Cu")
		(net 24)
	)
	(segment
		(start 217.8 133.4)
		(end 217.8 133.8)
		(width 0.182)
		(layer "B.Cu")
		(net 24)
	)
	(segment
		(start 195.67663 96.347131)
		(end 195.67663 96.320378)
		(width 0.182)
		(layer "B.Cu")
		(net 24)
	)
	(segment
		(start 200.091252 99.158748)
		(end 200.091252 98.25)
		(width 0.177)
		(layer "B.Cu")
		(net 24)
	)
	(segment
		(start 253.5 136.125)
		(end 253.85 135.775)
		(width 0.4)
		(layer "B.Cu")
		(net 24)
	)
	(segment
		(start 259.5375 122.8125)
		(end 259.85 122.5)
		(width 0.4)
		(layer "B.Cu")
		(net 24)
	)
	(segment
		(start 226.1375 82.6895)
		(end 226.1375 79.5525)
		(width 0.256)
		(layer "B.Cu")
		(net 24)
	)
	(segment
		(start 195.67663 96.347131)
		(end 195.206252 96.817509)
		(width 0.182)
		(layer "B.Cu")
		(net 24)
	)
	(segment
		(start 253.075 136.125)
		(end 251.49 136.125)
		(width 0.4)
		(layer "B.Cu")
		(net 24)
	)
	(segment
		(start 195.206252 95.85)
		(end 195.206252 91.85)
		(width 0.182)
		(layer "B.Cu")
		(net 24)
	)
	(segment
		(start 199.95 99.3)
		(end 200.15 99.3)
		(width 0.177)
		(layer "B.Cu")
		(net 24)
	)
	(segment
		(start 265.415 147.565)
		(end 265.4 147.55)
		(width 0.4)
		(layer "B.Cu")
		(net 24)
	)
	(segment
		(start 197.5 117.5)
		(end 197 117)
		(width 0.4)
		(layer "B.Cu")
		(net 24)
	)
	(segment
		(start 238.942482 139.5995)
		(end 238.942482 137.992482)
		(width 0.256)
		(layer "B.Cu")
		(net 24)
	)
	(segment
		(start 218.4 124.4)
		(end 219 123.8)
		(width 0.4)
		(layer "B.Cu")
		(net 24)
	)
	(segment
		(start 265.415 146.85)
		(end 265.415 147.535)
		(width 0.4)
		(layer "B.Cu")
		(net 24)
	)
	(segment
		(start 200 122)
		(end 200 121.35)
		(width 0.4)
		(layer "B.Cu")
		(net 24)
	)
	(segment
		(start 202.7425 89.9575)
		(end 202.65 89.865)
		(width 0.182)
		(layer "B.Cu")
		(net 24)
	)
	(segment
		(start 217.2 126.9)
		(end 218.4 125.7)
		(width 0.4)
		(layer "B.Cu")
		(net 24)
	)
	(segment
		(start 158.825001 79.445001)
		(end 159.445001 79.445001)
		(width 0.182)
		(layer "B.Cu")
		(net 24)
	)
	(segment
		(start 249.3 141.735)
		(end 251.3 141.735)
		(width 0.4)
		(layer "B.Cu")
		(net 24)
	)
	(segment
		(start 203.82 114.82)
		(end 204.5 115.5)
		(width 0.4)
		(layer "B.Cu")
		(net 24)
	)
	(segment
		(start 215.5 128)
		(end 215 128)
		(width 0.4)
		(layer "B.Cu")
		(net 24)
	)
	(segment
		(start 200 116.35)
		(end 200 116.875001)
		(width 0.4)
		(layer "B.Cu")
		(net 24)
	)
	(segment
		(start 226.1375 79.5525)
		(end 225.285 78.7)
		(width 0.256)
		(layer "B.Cu")
		(net 24)
	)
	(segment
		(start 260.1 170.3)
		(end 259.2 171.2)
		(width 0.1)
		(layer "B.Cu")
		(net 24)
	)
	(segment
		(start 208.5 131.5)
		(end 209 131)
		(width 0.4)
		(layer "B.Cu")
		(net 24)
	)
	(segment
		(start 262.6 151.6)
		(end 261.7 152.5)
		(width 0.4)
		(layer "B.Cu")
		(net 24)
	)
	(segment
		(start 265.415 147.535)
		(end 265.4 147.55)
		(width 0.4)
		(layer "B.Cu")
		(net 24)
	)
	(segment
		(start 205.5 139.5)
		(end 205 139)
		(width 0.4)
		(layer "B.Cu")
		(net 24)
	)
	(segment
		(start 260.3 122.5)
		(end 260.3 121.75)
		(width 0.4)
		(layer "B.Cu")
		(net 24)
	)
	(segment
		(start 213.5 143.5)
		(end 213 143)
		(width 0.4)
		(layer "B.Cu")
		(net 24)
	)
	(segment
		(start 203.1 90.315)
		(end 202.7425 89.9575)
		(width 0.182)
		(layer "B.Cu")
		(net 24)
	)
	(segment
		(start 216.1 126.9)
		(end 217.2 126.9)
		(width 0.4)
		(layer "B.Cu")
		(net 24)
	)
	(segment
		(start 219 123.8)
		(end 220.115 123.8)
		(width 0.4)
		(layer "B.Cu")
		(net 24)
	)
	(segment
		(start 166.170001 118.065001)
		(end 166.357601 117.877401)
		(width 0.182)
		(layer "B.Cu")
		(net 24)
	)
	(segment
		(start 255.7 79.1)
		(end 253.8 79.1)
		(width 0.4)
		(layer "B.Cu")
		(net 24)
	)
	(segment
		(start 259.25 122.8125)
		(end 259.5375 122.8125)
		(width 0.4)
		(layer "B.Cu")
		(net 24)
	)
	(segment
		(start 195.67663 96.320378)
		(end 195.206252 95.85)
		(width 0.182)
		(layer "B.Cu")
		(net 24)
	)
	(segment
		(start 261 79)
		(end 261.015 79)
		(width 0.4)
		(layer "B.Cu")
		(net 24)
	)
	(segment
		(start 208.62 147.130001)
		(end 208.62 147.116999)
		(width 0.114)
		(layer "B.Cu")
		(net 24)
	)
	(segment
		(start 205.5 141.5)
		(end 206 142)
		(width 0.4)
		(layer "B.Cu")
		(net 24)
	)
	(segment
		(start 200.667504 99.735)
		(end 200.316252 99.383748)
		(width 0.177)
		(layer "B.Cu")
		(net 24)
	)
	(segment
		(start 254 135.625)
		(end 254 135.475)
		(width 0.4)
		(layer "B.Cu")
		(net 24)
	)
	(segment
		(start 203.4 114.82)
		(end 203.82 114.82)
		(width 0.4)
		(layer "B.Cu")
		(net 24)
	)
	(segment
		(start 208.100001 147.117)
		(end 208.360001 146.857)
		(width 0.114)
		(layer "B.Cu")
		(net 24)
	)
	(segment
		(start 213.5 132.5)
		(end 213 133)
		(width 0.4)
		(layer "B.Cu")
		(net 24)
	)
	(segment
		(start 204.5 124.5)
		(end 204 125)
		(width 0.4)
		(layer "B.Cu")
		(net 24)
	)
	(segment
		(start 212.5 128.5)
		(end 212 129)
		(width 0.4)
		(layer "B.Cu")
		(net 24)
	)
	(segment
		(start 238.942482 137.992482)
		(end 238.65 137.7)
		(width 0.256)
		(layer "B.Cu")
		(net 24)
	)
	(segment
		(start 166.170001 118.065001)
		(end 166.170001 119.335001)
		(width 0.182)
		(layer "B.Cu")
		(net 24)
	)
	(segment
		(start 201.48 116.48)
		(end 200.13 116.48)
		(width 0.4)
		(layer "B.Cu")
		(net 24)
	)
	(segment
		(start 261.7 170.3)
		(end 260.1 170.3)
		(width 0.1)
		(layer "B.Cu")
		(net 24)
	)
	(segment
		(start 249.3 141.725)
		(end 247.925 140.35)
		(width 0.4)
		(layer "B.Cu")
		(net 24)
	)
	(segment
		(start 166.170001 118.041201)
		(end 166.170001 118.065001)
		(width 0.182)
		(layer "B.Cu")
		(net 24)
	)
	(segment
		(start 198.5 122.5)
		(end 199 123)
		(width 0.4)
		(layer "B.Cu")
		(net 24)
	)
	(segment
		(start 200.15 99.3)
		(end 200.191252 99.258748)
		(width 0.177)
		(layer "B.Cu")
		(net 24)
	)
	(segment
		(start 248.8875 79.5025)
		(end 248.085 78.7)
		(width 0.256)
		(layer "B.Cu")
		(net 24)
	)
	(segment
		(start 248.515 129.7)
		(end 244.9 129.7)
		(width 0.4)
		(layer "B.Cu")
		(net 24)
	)
	(segment
		(start 201.891252 99.735)
		(end 200.891252 99.735)
		(width 0.177)
		(layer "B.Cu")
		(net 24)
	)
	(segment
		(start 196 124)
		(end 196.5 124.5)
		(width 0.4)
		(layer "B.Cu")
		(net 24)
	)
	(segment
		(start 194.5 121.5)
		(end 195 121)
		(width 0.4)
		(layer "B.Cu")
		(net 24)
	)
	(segment
		(start 190.275 136.55)
		(end 190.275 136.725)
		(width 0.4)
		(layer "B.Cu")
		(net 24)
	)
	(segment
		(start 251.2 170.4)
		(end 251.2 171.2)
		(width 0.1)
		(layer "B.Cu")
		(net 24)
	)
	(segment
		(start 251.1 170.3)
		(end 251.2 170.4)
		(width 0.1)
		(layer "B.Cu")
		(net 24)
	)
	(segment
		(start 207.5 137.5)
		(end 208 138)
		(width 0.4)
		(layer "B.Cu")
		(net 24)
	)
	(segment
		(start 200.15 99.3)
		(end 200.232504 99.3)
		(width 0.177)
		(layer "B.Cu")
		(net 24)
	)
	(segment
		(start 200.891252 99.735)
		(end 200.667504 99.735)
		(width 0.177)
		(layer "B.Cu")
		(net 24)
	)
	(segment
		(start 238.935188 149.204812)
		(end 238.932725 149.204812)
		(width 0.4)
		(layer "In2.Cu")
		(net 24)
	)
	(segment
		(start 238.09 150.047537)
		(end 238.09 151.35)
		(width 0.4)
		(layer "In2.Cu")
		(net 24)
	)
	(segment
		(start 238.932725 149.204812)
		(end 238.09 150.047537)
		(width 0.4)
		(layer "In2.Cu")
		(net 24)
	)
	(segment
		(start 231.9 149.99)
		(end 230.89 148.98)
		(width 0.4)
		(layer "In3.Cu")
		(net 24)
	)
	(segment
		(start 205 86.9)
		(end 205 84.5)
		(width 0.4)
		(layer "In3.Cu")
		(net 24)
	)
	(segment
		(start 230.89 148.98)
		(end 230.89 146.65)
		(width 0.4)
		(layer "In3.Cu")
		(net 24)
	)
	(segment
		(start 231.9 151.4)
		(end 231.9 149.99)
		(width 0.4)
		(layer "In3.Cu")
		(net 24)
	)
	(segment
		(start 202.7 88.8)
		(end 203.7 87.8)
		(width 0.4)
		(layer "In3.Cu")
		(net 24)
	)
	(segment
		(start 203.7 87.8)
		(end 204.1 87.8)
		(width 0.4)
		(layer "In3.Cu")
		(net 24)
	)
	(segment
		(start 202.65 88.8)
		(end 202.7 88.8)
		(width 0.4)
		(layer "In3.Cu")
		(net 24)
	)
	(segment
		(start 204.1 87.8)
		(end 205 86.9)
		(width 0.4)
		(layer "In3.Cu")
		(net 24)
	)
	(segment
		(start 167.623501 131.523501)
		(end 167.75 131.65)
		(width 0.4)
		(layer "In7.Cu")
		(net 24)
	)
	(segment
		(start 163.919201 131.523501)
		(end 167.623501 131.523501)
		(width 0.4)
		(layer "In7.Cu")
		(net 24)
	)
	(segment
		(start 165.185 139)
		(end 165.185 139.985)
		(width 0.4)
		(layer "F.Cu")
		(net 25)
	)
	(segment
		(start 155.8 148.5)
		(end 156 148.7)
		(width 0.201)
		(layer "F.Cu")
		(net 25)
	)
	(segment
		(start 167.625 150.4)
		(end 169 150.4)
		(width 0.4)
		(layer "F.Cu")
		(net 25)
	)
	(segment
		(start 157.5 148.7)
		(end 157.8 149)
		(width 0.201)
		(layer "F.Cu")
		(net 25)
	)
	(segment
		(start 189.006207 143.993793)
		(end 189.006207 143.993931)
		(width 0.4)
		(layer "F.Cu")
		(net 25)
	)
	(segment
		(start 189.5 143.5)
		(end 189.006207 143.993793)
		(width 0.4)
		(layer "F.Cu")
		(net 25)
	)
	(segment
		(start 166.802 148.8)
		(end 166.802 148.798002)
		(width 0.177)
		(layer "F.Cu")
		(net 25)
	)
	(segment
		(start 159.8 156.185)
		(end 157.93 156.185)
		(width 0.4)
		(layer "F.Cu")
		(net 25)
	)
	(segment
		(start 165.2 140)
		(end 166.2 140)
		(width 0.4)
		(layer "F.Cu")
		(net 25)
	)
	(segment
		(start 173.999999 148.800003)
		(end 174.4 148.400002)
		(width 0.177)
		(layer "F.Cu")
		(net 25)
	)
	(segment
		(start 191.5 139.5)
		(end 191 140)
		(width 0.4)
		(layer "F.Cu")
		(net 25)
	)
	(segment
		(start 166.45 149.225)
		(end 167.625 150.4)
		(width 0.4)
		(layer "F.Cu")
		(net 25)
	)
	(segment
		(start 169.185 150.585)
		(end 169 150.4)
		(width 0.4)
		(layer "F.Cu")
		(net 25)
	)
	(segment
		(start 165.199999 149.499999)
		(end 165.3 149.6)
		(width 0.4)
		(layer "F.Cu")
		(net 25)
	)
	(segment
		(start 157.775 155.375)
		(end 157.7 155.3)
		(width 0.5)
		(layer "F.Cu")
		(net 25)
	)
	(segment
		(start 166.802 148.8)
		(end 166.45 149.152)
		(width 0.4)
		(layer "F.Cu")
		(net 25)
	)
	(segment
		(start 163 149.2)
		(end 163.4 149.6)
		(width 0.4)
		(layer "F.Cu")
		(net 25)
	)
	(segment
		(start 157.93 156.185)
		(end 157.775 156.03)
		(width 0.4)
		(layer "F.Cu")
		(net 25)
	)
	(segment
		(start 170.799999 148.800003)
		(end 170.399998 149.200004)
		(width 0.177)
		(layer "F.Cu")
		(net 25)
	)
	(segment
		(start 172.399999 142.400003)
		(end 172.399999 141.834316)
		(width 0.4)
		(layer "F.Cu")
		(net 25)
	)
	(segment
		(start 188.5 140.5)
		(end 188 141)
		(width 0.4)
		(layer "F.Cu")
		(net 25)
	)
	(segment
		(start 166.45 149.152)
		(end 166.45 149.225)
		(width 0.4)
		(layer "F.Cu")
		(net 25)
	)
	(segment
		(start 192.5 142.5)
		(end 192 143)
		(width 0.4)
		(layer "F.Cu")
		(net 25)
	)
	(segment
		(start 189.227 146.349999)
		(end 189.240001 146.349999)
		(width 0.114)
		(layer "F.Cu")
		(net 25)
	)
	(segment
		(start 156 148.7)
		(end 157.5 148.7)
		(width 0.201)
		(layer "F.Cu")
		(net 25)
	)
	(segment
		(start 169.200002 150.4)
		(end 170.399998 149.200004)
		(width 0.4)
		(layer "F.Cu")
		(net 25)
	)
	(segment
		(start 157.775 156.03)
		(end 157.775 155.375)
		(width 0.5)
		(layer "F.Cu")
		(net 25)
	)
	(segment
		(start 156.6 155.2)
		(end 157 155.2)
		(width 0.4)
		(layer "F.Cu")
		(net 25)
	)
	(segment
		(start 163.4 149.6)
		(end 165.3 149.6)
		(width 0.4)
		(layer "F.Cu")
		(net 25)
	)
	(segment
		(start 162.9 149.1)
		(end 163 149.2)
		(width 0.4)
		(layer "F.Cu")
		(net 25)
	)
	(segment
		(start 169 150.4)
		(end 169.200002 150.4)
		(width 0.4)
		(layer "F.Cu")
		(net 25)
	)
	(segment
		(start 185.5 141.5)
		(end 185 142)
		(width 0.4)
		(layer "F.Cu")
		(net 25)
	)
	(segment
		(start 157.1 155.3)
		(end 157.7 155.3)
		(width 0.4)
		(layer "F.Cu")
		(net 25)
	)
	(segment
		(start 165.199999 148.800003)
		(end 165.199999 149.499999)
		(width 0.4)
		(layer "F.Cu")
		(net 25)
	)
	(segment
		(start 156.1 149.5625)
		(end 156.1 148.8)
		(width 0.201)
		(layer "F.Cu")
		(net 25)
	)
	(segment
		(start 162.2 149.1)
		(end 162.9 149.1)
		(width 0.4)
		(layer "F.Cu")
		(net 25)
	)
	(segment
		(start 170.8 143.2)
		(end 170.4 142.8)
		(width 0.4)
		(layer "F.Cu")
		(net 25)
	)
	(segment
		(start 189.240001 146.349999)
		(end 189.5 146.09)
		(width 0.114)
		(layer "F.Cu")
		(net 25)
	)
	(segment
		(start 187.5 137.5)
		(end 187 138)
		(width 0.4)
		(layer "F.Cu")
		(net 25)
	)
	(segment
		(start 160.8 156.185)
		(end 159.8 156.185)
		(width 0.4)
		(layer "F.Cu")
		(net 25)
	)
	(segment
		(start 166.802 148.798002)
		(end 167.2 148.400002)
		(width 0.177)
		(layer "F.Cu")
		(net 25)
	)
	(segment
		(start 186.5 144.5)
		(end 186 145)
		(width 0.4)
		(layer "F.Cu")
		(net 25)
	)
	(segment
		(start 173.999999 143.200003)
		(end 174.4 142.800002)
		(width 0.4)
		(layer "F.Cu")
		(net 25)
	)
	(segment
		(start 169.185 151.2)
		(end 169.185 150.585)
		(width 0.4)
		(layer "F.Cu")
		(net 25)
	)
	(segment
		(start 165.185 139.985)
		(end 165.2 140)
		(width 0.4)
		(layer "F.Cu")
		(net 25)
	)
	(segment
		(start 169.2 148)
		(end 169.6 147.6)
		(width 0.4)
		(layer "F.Cu")
		(net 25)
	)
	(segment
		(start 169.2 143.2)
		(end 169.6 142.8)
		(width 0.4)
		(layer "F.Cu")
		(net 25)
	)
	(segment
		(start 155.1 148.8)
		(end 155.4 148.5)
		(width 0.201)
		(layer "F.Cu")
		(net 25)
	)
	(segment
		(start 171.6 147.2)
		(end 172 147.6)
		(width 0.4)
		(layer "F.Cu")
		(net 25)
	)
	(segment
		(start 155.1 149.5625)
		(end 155.1 148.8)
		(width 0.201)
		(layer "F.Cu")
		(net 25)
	)
	(segment
		(start 155.4 148.5)
		(end 155.8 148.5)
		(width 0.201)
		(layer "F.Cu")
		(net 25)
	)
	(segment
		(start 157 155.2)
		(end 157.1 155.3)
		(width 0.4)
		(layer "F.Cu")
		(net 25)
	)
	(segment
		(start 156.1 148.8)
		(end 156 148.7)
		(width 0.201)
		(layer "F.Cu")
		(net 25)
	)
	(segment
		(start 173.199999 148.800003)
		(end 173.6 148.400002)
		(width 0.177)
		(layer "F.Cu")
		(net 25)
	)
	(via
		(at 174.4 148.4)
		(size 0.45)
		(drill 0.2)
		(layers "F.Cu" "B.Cu")
		(net 25)
	)
	(via
		(at 169.6 142.8)
		(size 0.45)
		(drill 0.2)
		(layers "F.Cu" "B.Cu")
		(net 25)
	)
	(via
		(at 169 150.4)
		(size 0.45)
		(drill 0.2)
		(layers "F.Cu" "B.Cu")
		(net 25)
	)
	(via
		(at 192 138)
		(size 0.45)
		(drill 0.2)
		(layers "F.Cu" "B.Cu")
		(net 25)
	)
	(via
		(at 159.4 149)
		(size 0.45)
		(drill 0.2)
		(layers "F.Cu" "B.Cu")
		(free yes)
		(net 25)
	)
	(via
		(at 186 145)
		(size 0.45)
		(drill 0.2)
		(layers "F.Cu" "B.Cu")
		(net 25)
	)
	(via
		(at 158.6 149)
		(size 0.45)
		(drill 0.2)
		(layers "F.Cu" "B.Cu")
		(free yes)
		(net 25)
	)
	(via
		(at 168.2 170.3)
		(size 0.45)
		(drill 0.2)
		(layers "F.Cu" "B.Cu")
		(free yes)
		(net 25)
	)
	(via
		(at 189.5 146.09)
		(size 0.45)
		(drill 0.2)
		(layers "F.Cu" "B.Cu")
		(net 25)
	)
	(via
		(at 173.6 148.4)
		(size 0.45)
		(drill 0.2)
		(layers "F.Cu" "B.Cu")
		(net 25)
	)
	(via
		(at 172 147.6)
		(size 0.45)
		(drill 0.2)
		(layers "F.Cu" "B.Cu")
		(net 25)
	)
	(via
		(at 188 141)
		(size 0.45)
		(drill 0.2)
		(layers "F.Cu" "B.Cu")
		(net 25)
	)
	(via
		(at 185 142)
		(size 0.45)
		(drill 0.2)
		(layers "F.Cu" "B.Cu")
		(net 25)
	)
	(via
		(at 166.45 149.225)
		(size 0.45)
		(drill 0.2)
		(layers "F.Cu" "B.Cu")
		(net 25)
	)
	(via
		(at 191 140)
		(size 0.45)
		(drill 0.2)
		(layers "F.Cu" "B.Cu")
		(net 25)
	)
	(via
		(at 174.4 142.800002)
		(size 0.45)
		(drill 0.2)
		(layers "F.Cu" "B.Cu")
		(net 25)
	)
	(via
		(at 170.4 149.2)
		(size 0.45)
		(drill 0.2)
		(layers "F.Cu" "B.Cu")
		(net 25)
	)
	(via
		(at 157.8 149)
		(size 0.45)
		(drill 0.2)
		(layers "F.Cu" "B.Cu")
		(free yes)
		(net 25)
	)
	(via
		(at 168.8 170.3)
		(size 0.45)
		(drill 0.2)
		(layers "F.Cu" "B.Cu")
		(free yes)
		(net 25)
	)
	(via
		(at 165.3 149.6)
		(size 0.45)
		(drill 0.2)
		(layers "F.Cu" "B.Cu")
		(net 25)
	)
	(via
		(at 168.8 170.9)
		(size 0.45)
		(drill 0.2)
		(layers "F.Cu" "B.Cu")
		(free yes)
		(net 25)
	)
	(via
		(at 189.006207 143.993931)
		(size 0.45)
		(drill 0.2)
		(layers "F.Cu" "B.Cu")
		(net 25)
	)
	(via
		(at 187 138)
		(size 0.45)
		(drill 0.2)
		(layers "F.Cu" "B.Cu")
		(net 25)
	)
	(via
		(at 167.23 141.33)
		(size 0.45)
		(drill 0.2)
		(layers "F.Cu" "B.Cu")
		(free yes)
		(net 25)
	)
	(via
		(at 169.4 170.9)
		(size 0.45)
		(drill 0.2)
		(layers "F.Cu" "B.Cu")
		(free yes)
		(net 25)
	)
	(via
		(at 168.2 170.9)
		(size 0.45)
		(drill 0.2)
		(layers "F.Cu" "B.Cu")
		(free yes)
		(net 25)
	)
	(via
		(at 169.6 147.6)
		(size 0.45)
		(drill 0.2)
		(layers "F.Cu" "B.Cu")
		(net 25)
	)
	(via
		(at 160.2 149)
		(size 0.45)
		(drill 0.2)
		(layers "F.Cu" "B.Cu")
		(free yes)
		(net 25)
	)
	(via
		(at 183.79 137.8)
		(size 0.45)
		(drill 0.2)
		(layers "F.Cu" "B.Cu")
		(net 25)
	)
	(via
		(at 170.4 142.8)
		(size 0.45)
		(drill 0.2)
		(layers "F.Cu" "B.Cu")
		(net 25)
	)
	(via
		(at 167.55 140.9)
		(size 0.45)
		(drill 0.2)
		(layers "F.Cu" "B.Cu")
		(free yes)
		(net 25)
	)
	(via
		(at 163 149.2)
		(size 0.45)
		(drill 0.2)
		(layers "F.Cu" "B.Cu")
		(net 25)
	)
	(via
		(at 172.399999 141.834316)
		(size 0.45)
		(drill 0.2)
		(layers "F.Cu" "B.Cu")
		(net 25)
	)
	(via
		(at 192 143)
		(size 0.45)
		(drill 0.2)
		(layers "F.Cu" "B.Cu")
		(net 25)
	)
	(via
		(at 169.4 170.3)
		(size 0.45)
		(drill 0.2)
		(layers "F.Cu" "B.Cu")
		(free yes)
		(net 25)
	)
	(via
		(at 167.2 148.4)
		(size 0.45)
		(drill 0.2)
		(layers "F.Cu" "B.Cu")
		(net 25)
	)
	(via
		(at 157.7 155.3)
		(size 0.45)
		(drill 0.2)
		(layers "F.Cu" "B.Cu")
		(net 25)
	)
	(segment
		(start 191.5 137.5)
		(end 192 138)
		(width 0.4)
		(layer "B.Cu")
		(net 25)
	)
	(segment
		(start 191 140)
		(end 190.5 140.5)
		(width 0.4)
		(layer "B.Cu")
		(net 25)
	)
	(segment
		(start 189.006207 144.006207)
		(end 189.5 144.5)
		(width 0.4)
		(layer "B.Cu")
		(net 25)
	)
	(segment
		(start 174.399999 142.736827)
		(end 174.399999 142.799999)
		(width 0.1)
		(layer "B.Cu")
		(net 25)
	)
	(segment
		(start 189.006207 143.993931)
		(end 189.006207 144.006207)
		(width 0.4)
		(layer "B.Cu")
		(net 25)
	)
	(segment
		(start 184.8 142)
		(end 184.6 142.2)
		(width 0.4)
		(layer "B.Cu")
		(net 25)
	)
	(segment
		(start 187.5 141.5)
		(end 188 141)
		(width 0.4)
		(layer "B.Cu")
		(net 25)
	)
	(segment
		(start 183.494975 138.754975)
		(end 183.494975 138.095025)
		(width 0.4)
		(layer "B.Cu")
		(net 25)
	)
	(segment
		(start 185.37 144.999999)
		(end 186 145)
		(width 0.4)
		(layer "B.Cu")
		(net 25)
	)
	(segment
		(start 191.5 143.5)
		(end 192 143)
		(width 0.4)
		(layer "B.Cu")
		(net 25)
	)
	(segment
		(start 185 142)
		(end 184.8 142)
		(width 0.4)
		(layer "B.Cu")
		(net 25)
	)
	(segment
		(start 184.6 142.2)
		(end 183.7 142.2)
		(width 0.4)
		(layer "B.Cu")
		(net 25)
	)
	(segment
		(start 183.494975 138.095025)
		(end 183.79 137.8)
		(width 0.4)
		(layer "B.Cu")
		(net 25)
	)
	(segment
		(start 203.5 135.5)
		(end 204 136)
		(width 0.4)
		(layer "F.Cu")
		(net 26)
	)
	(segment
		(start 222.45 146.7)
		(end 222.65 146.7)
		(width 0.256)
		(layer "F.Cu")
		(net 26)
	)
	(segment
		(start 194.5 133.5)
		(end 194 134)
		(width 0.4)
		(layer "F.Cu")
		(net 26)
	)
	(segment
		(start 195.5 141.5)
		(end 195 142)
		(width 0.4)
		(layer "F.Cu")
		(net 26)
	)
	(segment
		(start 201.5 139.5)
		(end 202 140)
		(width 0.4)
		(layer "F.Cu")
		(net 26)
	)
	(segment
		(start 196.5 133.5)
		(end 196 134)
		(width 0.4)
		(layer "F.Cu")
		(net 26)
	)
	(segment
		(start 197.5 130.5)
		(end 197 131)
		(width 0.4)
		(layer "F.Cu")
		(net 26)
	)
	(segment
		(start 219.975 145.075)
		(end 221.35 145.075)
		(width 0.256)
		(layer "F.Cu")
		(net 26)
	)
	(segment
		(start 222.5 146.7)
		(end 222.65 146.55)
		(width 0.256)
		(layer "F.Cu")
		(net 26)
	)
	(segment
		(start 217.915 147.8)
		(end 217.915 147.135)
		(width 0.256)
		(layer "F.Cu")
		(net 26)
	)
	(segment
		(start 200.5 136.5)
		(end 201 137)
		(width 0.4)
		(layer "F.Cu")
		(net 26)
	)
	(segment
		(start 193.5 135.5)
		(end 193 136)
		(width 0.4)
		(layer "F.Cu")
		(net 26)
	)
	(segment
		(start 196.1745 144.8255)
		(end 196.1745 145.0005)
		(width 0.4)
		(layer "F.Cu")
		(net 26)
	)
	(segment
		(start 197.5 132.5)
		(end 197 133)
		(width 0.4)
		(layer "F.Cu")
		(net 26)
	)
	(segment
		(start 222.65 146.2)
		(end 222.65 145.9)
		(width 0.256)
		(layer "F.Cu")
		(net 26)
	)
	(segment
		(start 222 146.7)
		(end 222.45 146.7)
		(width 0.256)
		(layer "F.Cu")
		(net 26)
	)
	(segment
		(start 234.2 150.9)
		(end 234.2 150.35)
		(width 0.4)
		(layer "F.Cu")
		(net 26)
	)
	(segment
		(start 188.015 148.8)
		(end 188.015 149.384999)
		(width 0.4)
		(layer "F.Cu")
		(net 26)
	)
	(segment
		(start 221.975 145.7)
		(end 221.985 145.7)
		(width 0.256)
		(layer "F.Cu")
		(net 26)
	)
	(segment
		(start 195.5 132.5)
		(end 195 133)
		(width 0.4)
		(layer "F.Cu")
		(net 26)
	)
	(segment
		(start 202.5 142.5)
		(end 202 142)
		(width 0.4)
		(layer "F.Cu")
		(net 26)
	)
	(segment
		(start 222.65 148.3625)
		(end 222.65 147)
		(width 0.256)
		(layer "F.Cu")
		(net 26)
	)
	(segment
		(start 222.65 146.55)
		(end 222.65 146.2)
		(width 0.256)
		(layer "F.Cu")
		(net 26)
	)
	(segment
		(start 217.15 147.8)
		(end 217.915 147.8)
		(width 0.256)
		(layer "F.Cu")
		(net 26)
	)
	(segment
		(start 222.65 146.85)
		(end 222.5 146.7)
		(width 0.256)
		(layer "F.Cu")
		(net 26)
	)
	(segment
		(start 188.015 148.8)
		(end 188.015 148.76)
		(width 0.4)
		(layer "F.Cu")
		(net 26)
	)
	(segment
		(start 196.5 134.5)
		(end 196 135)
		(width 0.4)
		(layer "F.Cu")
		(net 26)
	)
	(segment
		(start 197.5 137.5)
		(end 197 138)
		(width 0.4)
		(layer "F.Cu")
		(net 26)
	)
	(segment
		(start 199.5 143.5)
		(end 199 144)
		(width 0.4)
		(layer "F.Cu")
		(net 26)
	)
	(segment
		(start 210.985 155.24)
		(end 210.91 155.165)
		(width 0.4)
		(layer "F.Cu")
		(net 26)
	)
	(segment
		(start 209.35 156.605)
		(end 209.35235 156.60735)
		(width 0.4)
		(layer "F.Cu")
		(net 26)
	)
	(segment
		(start 222.45 146.7)
		(end 222.5 146.7)
		(width 0.256)
		(layer "F.Cu")
		(net 26)
	)
	(segment
		(start 198.5 140.5)
		(end 198 141)
		(width 0.4)
		(layer "F.Cu")
		(net 26)
	)
	(segment
		(start 209.35235 156.60735)
		(end 210.985 156.60735)
		(width 0.4)
		(layer "F.Cu")
		(net 26)
	)
	(segment
		(start 217.915 147.135)
		(end 219.975 145.075)
		(width 0.256)
		(layer "F.Cu")
		(net 26)
	)
	(segment
		(start 222.65 147)
		(end 222.65 146.85)
		(width 0.256)
		(layer "F.Cu")
		(net 26)
	)
	(segment
		(start 188.015 148.76)
		(end 188.55 148.225)
		(width 0.4)
		(layer "F.Cu")
		(net 26)
	)
	(segment
		(start 233.9 150.05)
		(end 233.9 149.6)
		(width 0.2)
		(layer "F.Cu")
		(net 26)
	)
	(segment
		(start 199.5 132.5)
		(end 199 133)
		(width 0.4)
		(layer "F.Cu")
		(net 26)
	)
	(segment
		(start 221.985 145.7)
		(end 222.45 145.7)
		(width 0.256)
		(layer "F.Cu")
		(net 26)
	)
	(segment
		(start 210.985 156.60735)
		(end 210.985 155.24)
		(width 0.4)
		(layer "F.Cu")
		(net 26)
	)
	(segment
		(start 222.45 145.7)
		(end 222.65 145.9)
		(width 0.256)
		(layer "F.Cu")
		(net 26)
	)
	(segment
		(start 218.4 148.285)
		(end 217.915 147.8)
		(width 0.1)
		(layer "F.Cu")
		(net 26)
	)
	(segment
		(start 233.95 150.1)
		(end 233.9 150.05)
		(width 0.2)
		(layer "F.Cu")
		(net 26)
	)
	(segment
		(start 197.5 128.5)
		(end 197 128)
		(width 0.4)
		(layer "F.Cu")
		(net 26)
	)
	(segment
		(start 196.5 144.5)
		(end 196.1745 144.8255)
		(width 0.4)
		(layer "F.Cu")
		(net 26)
	)
	(segment
		(start 210.9 164.915)
		(end 210.565 164.915)
		(width 0.4)
		(layer "F.Cu")
		(net 26)
	)
	(segment
		(start 188.015 149.384999)
		(end 188.715001 150.085)
		(width 0.4)
		(layer "F.Cu")
		(net 26)
	)
	(segment
		(start 222.65 146.7)
		(end 222.65 146.55)
		(width 0.256)
		(layer "F.Cu")
		(net 26)
	)
	(segment
		(start 234.2 150.35)
		(end 233.95 150.1)
		(width 0.4)
		(layer "F.Cu")
		(net 26)
	)
	(segment
		(start 218.4 149.315)
		(end 218.4 148.285)
		(width 0.1)
		(layer "F.Cu")
		(net 26)
	)
	(segment
		(start 198.5 133.5)
		(end 198 134)
		(width 0.4)
		(layer "F.Cu")
		(net 26)
	)
	(segment
		(start 217.915 149.8)
		(end 218.4 149.315)
		(width 0.1)
		(layer "F.Cu")
		(net 26)
	)
	(segment
		(start 194.5 138.5)
		(end 194 139)
		(width 0.4)
		(layer "F.Cu")
		(net 26)
	)
	(segment
		(start 210.565 164.915)
		(end 210.3 164.65)
		(width 0.4)
		(layer "F.Cu")
		(net 26)
	)
	(segment
		(start 221.35 145.075)
		(end 221.975 145.7)
		(width 0.256)
		(layer "F.Cu")
		(net 26)
	)
	(segment
		(start 222.65 147)
		(end 222.65 146.7)
		(width 0.256)
		(layer "F.Cu")
		(net 26)
	)
	(via
		(at 197 131)
		(size 0.45)
		(drill 0.2)
		(layers "F.Cu" "B.Cu")
		(net 26)
	)
	(via
		(at 211.5 85.5)
		(size 0.45)
		(drill 0.2)
		(layers "F.Cu" "B.Cu")
		(free yes)
		(net 26)
	)
	(via
		(at 196 130)
		(size 0.45)
		(drill 0.2)
		(layers "F.Cu" "B.Cu")
		(net 26)
	)
	(via
		(at 196 134)
		(size 0.45)
		(drill 0.2)
		(layers "F.Cu" "B.Cu")
		(net 26)
	)
	(via
		(at 213.9 165)
		(size 0.45)
		(drill 0.2)
		(layers "F.Cu" "B.Cu")
		(net 26)
	)
	(via
		(at 211.5 87)
		(size 0.45)
		(drill 0.2)
		(layers "F.Cu" "B.Cu")
		(free yes)
		(net 26)
	)
	(via
		(at 212.9 155.25)
		(size 0.45)
		(drill 0.2)
		(layers "F.Cu" "B.Cu")
		(net 26)
	)
	(via
		(at 198 141)
		(size 0.45)
		(drill 0.2)
		(layers "F.Cu" "B.Cu")
		(net 26)
	)
	(via
		(at 266.8 78.2)
		(size 0.45)
		(drill 0.2)
		(layers "F.Cu" "B.Cu")
		(net 26)
	)
	(via
		(at 210.3 164.65)
		(size 0.45)
		(drill 0.2)
		(layers "F.Cu" "B.Cu")
		(net 26)
	)
	(via
		(at 194 134)
		(size 0.45)
		(drill 0.2)
		(layers "F.Cu" "B.Cu")
		(net 26)
	)
	(via
		(at 225 147.2)
		(size 0.45)
		(drill 0.2)
		(layers "F.Cu" "B.Cu")
		(net 26)
	)
	(via
		(at 262.55 72.55)
		(size 0.45)
		(drill 0.2)
		(layers "F.Cu" "B.Cu")
		(net 26)
	)
	(via
		(at 211.5 86.5)
		(size 0.45)
		(drill 0.2)
		(layers "F.Cu" "B.Cu")
		(free yes)
		(net 26)
	)
	(via
		(at 211.5 86)
		(size 0.45)
		(drill 0.2)
		(layers "F.Cu" "B.Cu")
		(free yes)
		(net 26)
	)
	(via
		(at 233.95 150.1)
		(size 0.45)
		(drill 0.2)
		(layers "F.Cu" "B.Cu")
		(net 26)
	)
	(via
		(at 163 159.5)
		(size 0.45)
		(drill 0.2)
		(layers "F.Cu" "B.Cu")
		(free yes)
		(net 26)
	)
	(via
		(at 217.15 147.8)
		(size 0.45)
		(drill 0.2)
		(layers "F.Cu" "B.Cu")
		(net 26)
	)
	(via
		(at 195 133)
		(size 0.45)
		(drill 0.2)
		(layers "F.Cu" "B.Cu")
		(net 26)
	)
	(via
		(at 196 135)
		(size 0.45)
		(drill 0.2)
		(layers "F.Cu" "B.Cu")
		(net 26)
	)
	(via
		(at 196.1745 145.0005)
		(size 0.45)
		(drill 0.2)
		(layers "F.Cu" "B.Cu")
		(net 26)
	)
	(via
		(at 211.5 88)
		(size 0.45)
		(drill 0.2)
		(layers "F.Cu" "B.Cu")
		(free yes)
		(net 26)
	)
	(via
		(at 201 137)
		(size 0.45)
		(drill 0.2)
		(layers "F.Cu" "B.Cu")
		(net 26)
	)
	(via
		(at 200 144)
		(size 0.45)
		(drill 0.2)
		(layers "F.Cu" "B.Cu")
		(net 26)
	)
	(via
		(at 204 136)
		(size 0.45)
		(drill 0.2)
		(layers "F.Cu" "B.Cu")
		(net 26)
	)
	(via
		(at 191.5 132.5)
		(size 0.45)
		(drill 0.2)
		(layers "F.Cu" "B.Cu")
		(net 26)
	)
	(via
		(at 266.8 92)
		(size 0.45)
		(drill 0.2)
		(layers "F.Cu" "B.Cu")
		(net 26)
	)
	(via
		(at 266.8 82.8)
		(size 0.45)
		(drill 0.2)
		(layers "F.Cu" "B.Cu")
		(net 26)
	)
	(via
		(at 194 139)
		(size 0.45)
		(drill 0.2)
		(layers "F.Cu" "B.Cu")
		(net 26)
	)
	(via
		(at 188.55 148.225)
		(size 0.45)
		(drill 0.2)
		(layers "F.Cu" "B.Cu")
		(net 26)
	)
	(via
		(at 202 142)
		(size 0.45)
		(drill 0.2)
		(layers "F.Cu" "B.Cu")
		(net 26)
	)
	(via
		(at 202 140)
		(size 0.45)
		(drill 0.2)
		(layers "F.Cu" "B.Cu")
		(net 26)
	)
	(via
		(at 211.5 87.5)
		(size 0.45)
		(drill 0.2)
		(layers "F.Cu" "B.Cu")
		(free yes)
		(net 26)
	)
	(via
		(at 199 144)
		(size 0.45)
		(drill 0.2)
		(layers "F.Cu" "B.Cu")
		(net 26)
	)
	(via
		(at 195 142)
		(size 0.45)
		(drill 0.2)
		(layers "F.Cu" "B.Cu")
		(net 26)
	)
	(via
		(at 161.5 159)
		(size 0.45)
		(drill 0.2)
		(layers "F.Cu" "B.Cu")
		(free yes)
		(net 26)
	)
	(via
		(at 193.99 145.98)
		(size 0.45)
		(drill 0.2)
		(layers "F.Cu" "B.Cu")
		(net 26)
	)
	(via
		(at 266.8 87.4)
		(size 0.45)
		(drill 0.2)
		(layers "F.Cu" "B.Cu")
		(net 26)
	)
	(via
		(at 191.5 130.5)
		(size 0.45)
		(drill 0.2)
		(layers "F.Cu" "B.Cu")
		(net 26)
	)
	(via
		(at 197 138)
		(size 0.45)
		(drill 0.2)
		(layers "F.Cu" "B.Cu")
		(net 26)
	)
	(via
		(at 198 134)
		(size 0.45)
		(drill 0.2)
		(layers "F.Cu" "B.Cu")
		(net 26)
	)
	(via
		(at 193 132)
		(size 0.45)
		(drill 0.2)
		(layers "F.Cu" "B.Cu")
		(net 26)
	)
	(via
		(at 162.5 159)
		(size 0.45)
		(drill 0.2)
		(layers "F.Cu" "B.Cu")
		(free yes)
		(net 26)
	)
	(via
		(at 210.91 155.165)
		(size 0.45)
		(drill 0.2)
		(layers "F.Cu" "B.Cu")
		(net 26)
	)
	(via
		(at 164 159.5)
		(size 0.45)
		(drill 0.2)
		(layers "F.Cu" "B.Cu")
		(free yes)
		(net 26)
	)
	(via
		(at 222.65 146.2)
		(size 0.45)
		(drill 0.2)
		(layers "F.Cu" "B.Cu")
		(net 26)
	)
	(via
		(at 162 159.5)
		(size 0.45)
		(drill 0.2)
		(layers "F.Cu" "B.Cu")
		(free yes)
		(net 26)
	)
	(via
		(at 200 139)
		(size 0.45)
		(drill 0.2)
		(layers "F.Cu" "B.Cu")
		(net 26)
	)
	(via
		(at 197 133)
		(size 0.45)
		(drill 0.2)
		(layers "F.Cu" "B.Cu")
		(net 26)
	)
	(via
		(at 199 133)
		(size 0.45)
		(drill 0.2)
		(layers "F.Cu" "B.Cu")
		(net 26)
	)
	(via
		(at 163.5 159)
		(size 0.45)
		(drill 0.2)
		(layers "F.Cu" "B.Cu")
		(free yes)
		(net 26)
	)
	(via
		(at 193 136)
		(size 0.45)
		(drill 0.2)
		(layers "F.Cu" "B.Cu")
		(net 26)
	)
	(via
		(at 197 128)
		(size 0.45)
		(drill 0.2)
		(layers "F.Cu" "B.Cu")
		(net 26)
	)
	(segment
		(start 197.5 140.5)
		(end 198 141)
		(width 0.4)
		(layer "B.Cu")
		(net 26)
	)
	(segment
		(start 226.8 148.8)
		(end 226.201 148.201)
		(width 0.1)
		(layer "B.Cu")
		(net 26)
	)
	(segment
		(start 222.6 148.2)
		(end 223.101 148.2)
		(width 0.1)
		(layer "B.Cu")
		(net 26)
	)
	(segment
		(start 266.8 83.515)
		(end 266.8 82.8)
		(width 0.201)
		(layer "B.Cu")
		(net 26)
	)
	(segment
		(start 266.8 88.115)
		(end 266.8 87.4)
		(width 0.201)
		(layer "B.Cu")
		(net 26)
	)
	(segment
		(start 196.99 145.816)
		(end 196.1745 145.0005)
		(width 0.4)
		(layer "B.Cu")
		(net 26)
	)
	(segment
		(start 226.615 153.385)
		(end 227 153)
		(width 0.1)
		(layer "B.Cu")
		(net 26)
	)
	(segment
		(start 202.64 142.64)
		(end 202 142)
		(width 0.4)
		(layer "B.Cu")
		(net 26)
	)
	(segment
		(start 196.99 147.25)
		(end 196.99 145.816)
		(width 0.4)
		(layer "B.Cu")
		(net 26)
	)
	(segment
		(start 262.55 72.55)
		(end 262 73.1)
		(width 0.4)
		(layer "B.Cu")
		(net 26)
	)
	(segment
		(start 226.111 147.711)
		(end 225.6 147.2)
		(width 0.1)
		(layer "B.Cu")
		(net 26)
	)
	(segment
		(start 229.485 154.2)
		(end 229.485 153.685)
		(width 0.1)
		(layer "B.Cu")
		(net 26)
	)
	(segment
		(start 217.15 147.8)
		(end 217.566 148.216)
		(width 0.256)
		(layer "B.Cu")
		(net 26)
	)
	(segment
		(start 193.125 132.43)
		(end 193.125 132.125)
		(width 0.4)
		(layer "B.Cu")
		(net 26)
	)
	(segment
		(start 193.825 134.175)
		(end 193.975 134.175)
		(width 0.4)
		(layer "B.Cu")
		(net 26)
	)
	(segment
		(start 195.825 147.25)
		(end 196.99 147.25)
		(width 0.4)
		(layer "B.Cu")
		(net 26)
	)
	(segment
		(start 229.485 153.685)
		(end 228.4 152.6)
		(width 0.1)
		(layer "B.Cu")
		(net 26)
	)
	(segment
		(start 227 152)
		(end 226.4 151.4)
		(width 0.1)
		(layer "B.Cu")
		(net 26)
	)
	(segment
		(start 262 73.1)
		(end 259.795 73.1)
		(width 0.4)
		(layer "B.Cu")
		(net 26)
	)
	(segment
		(start 201.5 140.5)
		(end 202 140)
		(width 0.4)
		(layer "B.Cu")
		(net 26)
	)
	(segment
		(start 225.6 147.2)
		(end 225 147.2)
		(width 0.1)
		(layer "B.Cu")
		(net 26)
	)
	(segment
		(start 193.5 138.5)
		(end 194 139)
		(width 0.4)
		(layer "B.Cu")
		(net 26)
	)
	(segment
		(start 234.285 147.9)
		(end 234.285 148.9)
		(width 0.182)
		(layer "B.Cu")
		(net 26)
	)
	(segment
		(start 226.111 148.201)
		(end 226.111 147.711)
		(width 0.1)
		(layer "B.Cu")
		(net 26)
	)
	(segment
		(start 227 152.6)
		(end 227 152)
		(width 0.1)
		(layer "B.Cu")
		(net 26)
	)
	(segment
		(start 196 135)
		(end 196.5 135.5)
		(width 0.4)
		(layer "B.Cu")
		(net 26)
	)
	(segment
		(start 201.5 137.5)
		(end 201 137)
		(width 0.4)
		(layer "B.Cu")
		(net 26)
	)
	(segment
		(start 226.201 148.201)
		(end 226.111 148.201)
		(width 0.1)
		(layer "B.Cu")
		(net 26)
	)
	(segment
		(start 198.5 143.5)
		(end 199 144)
		(width 0.4)
		(layer "B.Cu")
		(net 26)
	)
	(segment
		(start 222.65 146.2)
		(end 222.6 146.25)
		(width 0.1)
		(layer "B.Cu")
		(net 26)
	)
	(segment
		(start 193 135)
		(end 193.825 134.175)
		(width 0.4)
		(layer "B.Cu")
		(net 26)
	)
	(segment
		(start 222.6 146.25)
		(end 222.6 148.2)
		(width 0.1)
		(layer "B.Cu")
		(net 26)
	)
	(segment
		(start 196.5 137.5)
		(end 197 138)
		(width 0.4)
		(layer "B.Cu")
		(net 26)
	)
	(segment
		(start 226.615 154.2)
		(end 226.615 153.385)
		(width 0.1)
		(layer "B.Cu")
		(net 26)
	)
	(segment
		(start 227 153)
		(end 227 152.6)
		(width 0.1)
		(layer "B.Cu")
		(net 26)
	)
	(segment
		(start 200 138.5)
		(end 200 139)
		(width 0.4)
		(layer "B.Cu")
		(net 26)
	)
	(segment
		(start 266.8 92.715)
		(end 266.8 92)
		(width 0.201)
		(layer "B.Cu")
		(net 26)
	)
	(segment
		(start 202.5 143.5)
		(end 202.5 143.22)
		(width 0.4)
		(layer "B.Cu")
		(net 26)
	)
	(segment
		(start 193.125 132.125)
		(end 193 132)
		(width 0.4)
		(layer "B.Cu")
		(net 26)
	)
	(segment
		(start 226.4 151.4)
		(end 226.4 150.2)
		(width 0.1)
		(layer "B.Cu")
		(net 26)
	)
	(segment
		(start 193.73 145.72)
		(end 193.99 145.98)
		(width 0.1)
		(layer "B.Cu")
		(net 26)
	)
	(segment
		(start 210.91 155.165)
		(end 210.93 155.185)
		(width 0.4)
		(layer "B.Cu")
		(net 26)
	)
	(segment
		(start 210.93 155.185)
		(end 212.88 155.185)
		(width 0.4)
		(layer "B.Cu")
		(net 26)
	)
	(segment
		(start 226.8 149.8)
		(end 226.8 148.8)
		(width 0.1)
		(layer "B.Cu")
		(net 26)
	)
	(segment
		(start 217.566 148.216)
		(end 219.268 148.216)
		(width 0.256)
		(layer "B.Cu")
		(net 26)
	)
	(segment
		(start 222.2 148.2)
		(end 222.6 148.2)
		(width 0.1)
		(layer "B.Cu")
		(net 26)
	)
	(segment
		(start 202.64 143.08)
		(end 202.64 142.64)
		(width 0.4)
		(layer "B.Cu")
		(net 26)
	)
	(segment
		(start 228.4 152.6)
		(end 227 152.6)
		(width 0.1)
		(layer "B.Cu")
		(net 26)
	)
	(segment
		(start 203.5 135.5)
		(end 204 136)
		(width 0.4)
		(layer "B.Cu")
		(net 26)
	)
	(segment
		(start 233.95 150.1)
		(end 233.95 149.69)
		(width 0.4)
		(layer "B.Cu")
		(net 26)
	)
	(segment
		(start 200 143.7)
		(end 200 144)
		(width 0.4)
		(layer "B.Cu")
		(net 26)
	)
	(segment
		(start 254.6 73.1)
		(end 259.795 73.1)
		(width 0.4)
		(layer "B.Cu")
		(net 26)
	)
	(segment
		(start 266.8 78.915)
		(end 266.8 78.2)
		(width 0.201)
		(layer "B.Cu")
		(net 26)
	)
	(segment
		(start 233.95 149.69)
		(end 234.285 149.355)
		(width 0.4)
		(layer "B.Cu")
		(net 26)
	)
	(segment
		(start 194.5 142.5)
		(end 195 142)
		(width 0.4)
		(layer "B.Cu")
		(net 26)
	)
	(segment
		(start 234.285 149.355)
		(end 234.285 148.9)
		(width 0.4)
		(layer "B.Cu")
		(net 26)
	)
	(segment
		(start 193.717 145.72)
		(end 193.73 145.72)
		(width 0.1)
		(layer "B.Cu")
		(net 26)
	)
	(segment
		(start 226.4 150.2)
		(end 226.8 149.8)
		(width 0.1)
		(layer "B.Cu")
		(net 26)
	)
	(segment
		(start 202.5 143.22)
		(end 202.64 143.08)
		(width 0.4)
		(layer "B.Cu")
		(net 26)
	)
	(segment
		(start 259.35 93.4)
		(end 260.75 93.4)
		(width 0.1)
		(layer "F.Cu")
		(net 27)
	)
	(segment
		(start 240.425 115.275)
		(end 241.81 115.275)
		(width 0.198)
		(layer "B.Cu")
		(net 29)
	)
	(segment
		(start 241.81 115.275)
		(end 242.3 114.785)
		(width 0.198)
		(layer "B.Cu")
		(net 29)
	)
	(segment
		(start 166.6 188.9)
		(end 166.6 188.154)
		(width 0.198)
		(layer "F.Cu")
		(net 37)
	)
	(segment
		(start 158 184.485)
		(end 158 186.125)
		(width 0.1)
		(layer "F.Cu")
		(net 37)
	)
	(segment
		(start 160.9 187.1)
		(end 160.9 188.45)
		(width 0.1)
		(layer "F.Cu")
		(net 37)
	)
	(segment
		(start 160.9 188.95)
		(end 160.9 188.203)
		(width 0.182)
		(layer "F.Cu")
		(net 37)
	)
	(segment
		(start 160.9 188.203)
		(end 160.897 188.2)
		(width 0.182)
		(layer "F.Cu")
		(net 37)
	)
	(segment
		(start 166.6 188.154)
		(end 166.596 188.15)
		(width 0.198)
		(layer "F.Cu")
		(net 37)
	)
	(segment
		(start 158.55 186.675)
		(end 160.475 186.675)
		(width 0.1)
		(layer "F.Cu")
		(net 37)
	)
	(segment
		(start 158 186.125)
		(end 158.55 186.675)
		(width 0.1)
		(layer "F.Cu")
		(net 37)
	)
	(segment
		(start 160.475 186.675)
		(end 160.9 187.1)
		(width 0.1)
		(layer "F.Cu")
		(net 37)
	)
	(segment
		(start 164.85 188.5)
		(end 164.85 189)
		(width 0.182)
		(layer "F.Cu")
		(net 37)
	)
	(via
		(at 164.85 189)
		(size 0.45)
		(drill 0.2)
		(layers "F.Cu" "B.Cu")
		(net 37)
	)
	(via
		(at 166.6 188.9)
		(size 0.45)
		(drill 0.2)
		(layers "F.Cu" "B.Cu")
		(net 37)
	)
	(via
		(at 160.9 188.95)
		(size 0.45)
		(drill 0.2)
		(layers "F.Cu" "B.Cu")
		(net 37)
	)
	(segment
		(start 164.965 188.9)
		(end 164.85 188.785)
		(width 0.256)
		(layer "B.Cu")
		(net 37)
	)
	(segment
		(start 168.55 186.435)
		(end 169.985 187.87)
		(width 0.4)
		(layer "B.Cu")
		(net 37)
	)
	(segment
		(start 166.615 188.885)
		(end 166.6 188.9)
		(width 0.182)
		(layer "B.Cu")
		(net 37)
	)
	(segment
		(start 185.6 187.085)
		(end 185.6 186.15)
		(width 0.4)
		(layer "B.Cu")
		(net 37)
	)
	(segment
		(start 186.015 187.5)
		(end 185.6 187.085)
		(width 0.4)
		(layer "B.Cu")
		(net 37)
	)
	(segment
		(start 166.615 188.6)
		(end 166.615 188.885)
		(width 0.182)
		(layer "B.Cu")
		(net 37)
	)
	(segment
		(start 166.55 186.435)
		(end 166.55 188.85)
		(width 0.256)
		(layer "B.Cu")
		(net 37)
	)
	(segment
		(start 169.985 187.87)
		(end 185.645 187.87)
		(width 0.4)
		(layer "B.Cu")
		(net 37)
	)
	(segment
		(start 185.645 187.87)
		(end 186.015 187.5)
		(width 0.4)
		(layer "B.Cu")
		(net 37)
	)
	(segment
		(start 160.95 189)
		(end 160.9 188.95)
		(width 0.256)
		(layer "B.Cu")
		(net 37)
	)
	(segment
		(start 160.935 188.6)
		(end 160.935 188.915)
		(width 0.182)
		(layer "B.Cu")
		(net 37)
	)
	(segment
		(start 166.55 188.85)
		(end 166.6 188.9)
		(width 0.256)
		(layer "B.Cu")
		(net 37)
	)
	(segment
		(start 164.85 189)
		(end 160.95 189)
		(width 0.256)
		(layer "B.Cu")
		(net 37)
	)
	(segment
		(start 160.935 188.915)
		(end 160.9 188.95)
		(width 0.182)
		(layer "B.Cu")
		(net 37)
	)
	(segment
		(start 166.6 188.9)
		(end 164.965 188.9)
		(width 0.256)
		(layer "B.Cu")
		(net 37)
	)
	(segment
		(start 168.55 186.435)
		(end 166.55 186.435)
		(width 0.256)
		(layer "B.Cu")
		(net 37)
	)
	(segment
		(start 208.5 128.5)
		(end 208.98677 128.01323)
		(width 0.256)
		(layer "F.Cu")
		(net 38)
	)
	(segment
		(start 208.98677 128.01323)
		(end 209.001018 128.01323)
		(width 0.256)
		(layer "F.Cu")
		(net 38)
	)
	(via
		(at 236.4 122.475)
		(size 0.45)
		(drill 0.2)
		(layers "F.Cu" "B.Cu")
		(net 38)
	)
	(via
		(at 209.001018 128.01323)
		(size 0.45)
		(drill 0.2)
		(layers "F.Cu" "B.Cu")
		(net 38)
	)
	(via
		(at 244.4 140.25)
		(size 0.45)
		(drill 0.2)
		(layers "F.Cu" "B.Cu")
		(net 38)
	)
	(via
		(at 250.1 147.725)
		(size 0.45)
		(drill 0.2)
		(layers "F.Cu" "B.Cu")
		(net 38)
	)
	(segment
		(start 250.1 148.273)
		(end 250.1 147.725)
		(width 0.1)
		(layer "B.Cu")
		(net 38)
	)
	(segment
		(start 244.13 127.58)
		(end 244.8 126.91)
		(width 0.1)
		(layer "In3.Cu")
		(net 38)
	)
	(segment
		(start 244.07 120.11)
		(end 238.765 120.11)
		(width 0.1)
		(layer "In3.Cu")
		(net 38)
	)
	(segment
		(start 244.8 128.76)
		(end 244.13 128.09)
		(width 0.1)
		(layer "In3.Cu")
		(net 38)
	)
	(segment
		(start 244.8 139.85)
		(end 244.8 128.76)
		(width 0.1)
		(layer "In3.Cu")
		(net 38)
	)
	(segment
		(start 238.765 120.11)
		(end 236.4 122.475)
		(width 0.1)
		(layer "In3.Cu")
		(net 38)
	)
	(segment
		(start 244.13 128.09)
		(end 244.13 127.58)
		(width 0.1)
		(layer "In3.Cu")
		(net 38)
	)
	(segment
		(start 244.8 120.84)
		(end 244.07 120.11)
		(width 0.1)
		(layer "In3.Cu")
		(net 38)
	)
	(segment
		(start 244.8 126.91)
		(end 244.8 120.84)
		(width 0.1)
		(layer "In3.Cu")
		(net 38)
	)
	(segment
		(start 244.4 140.25)
		(end 244.8 139.85)
		(width 0.1)
		(layer "In3.Cu")
		(net 38)
	)
	(segment
		(start 251.175 143.375)
		(end 248.775 140.975)
		(width 0.1)
		(layer "In5.Cu")
		(net 38)
	)
	(segment
		(start 245.125 140.975)
		(end 244.4 140.25)
		(width 0.1)
		(layer "In5.Cu")
		(net 38)
	)
	(segment
		(start 251.175 146.65)
		(end 251.175 143.375)
		(width 0.1)
		(layer "In5.Cu")
		(net 38)
	)
	(segment
		(start 248.775 140.975)
		(end 245.125 140.975)
		(width 0.1)
		(layer "In5.Cu")
		(net 38)
	)
	(segment
		(start 250.1 147.725)
		(end 251.175 146.65)
		(width 0.1)
		(layer "In5.Cu")
		(net 38)
	)
	(segment
		(start 209.001018 128.01323)
		(end 210.389248 126.625)
		(width 0.1)
		(layer "In7.Cu")
		(net 38)
	)
	(segment
		(start 227.175 122.55)
		(end 236.325 122.55)
		(width 0.1)
		(layer "In7.Cu")
		(net 38)
	)
	(segment
		(start 219.55 123.3)
		(end 226.425 123.3)
		(width 0.1)
		(layer "In7.Cu")
		(net 38)
	)
	(segment
		(start 210.389248 126.625)
		(end 216.225 126.625)
		(width 0.1)
		(layer "In7.Cu")
		(net 38)
	)
	(segment
		(start 236.325 122.55)
		(end 236.4 122.475)
		(width 0.1)
		(layer "In7.Cu")
		(net 38)
	)
	(segment
		(start 216.225 126.625)
		(end 219.55 123.3)
		(width 0.1)
		(layer "In7.Cu")
		(net 38)
	)
	(segment
		(start 226.425 123.3)
		(end 227.175 122.55)
		(width 0.1)
		(layer "In7.Cu")
		(net 38)
	)
	(segment
		(start 224 122.3)
		(end 224 119.6)
		(width 0.1)
		(layer "F.Cu")
		(net 43)
	)
	(segment
		(start 224 119.6)
		(end 224.1 119.5)
		(width 0.1)
		(layer "F.Cu")
		(net 43)
	)
	(segment
		(start 224.1 119.5)
		(end 224.54 119.5)
		(width 0.1)
		(layer "F.Cu")
		(net 43)
	)
	(segment
		(start 252.1 143.373)
		(end 252.1 142.85)
		(width 0.1)
		(layer "F.Cu")
		(net 43)
	)
	(segment
		(start 224.25 124)
		(end 224.25 122.55)
		(width 0.1)
		(layer "F.Cu")
		(net 43)
	)
	(segment
		(start 224.25 122.55)
		(end 224 122.3)
		(width 0.1)
		(layer "F.Cu")
		(net 43)
	)
	(segment
		(start 209.5 129.5)
		(end 210 129)
		(width 0.256)
		(layer "F.Cu")
		(net 43)
	)
	(via
		(at 224.25 124)
		(size 0.45)
		(drill 0.2)
		(layers "F.Cu" "B.Cu")
		(net 43)
	)
	(via
		(at 252.1 142.85)
		(size 0.45)
		(drill 0.2)
		(layers "F.Cu" "B.Cu")
		(net 43)
	)
	(via
		(at 210 129)
		(size 0.45)
		(drill 0.2)
		(layers "F.Cu" "B.Cu")
		(net 43)
	)
	(segment
		(start 216.075 127.625)
		(end 210.844669 127.625)
		(width 0.1)
		(layer "In7.Cu")
		(net 43)
	)
	(segment
		(start 224.25 124)
		(end 228.59 124)
		(width 0.1)
		(layer "In7.Cu")
		(net 43)
	)
	(segment
		(start 240.293173 131.58)
		(end 241.44 132.726827)
		(width 0.1)
		(layer "In7.Cu")
		(net 43)
	)
	(segment
		(start 250.025 142.2)
		(end 251.45 142.2)
		(width 0.1)
		(layer "In7.Cu")
		(net 43)
	)
	(segment
		(start 236.17 131.58)
		(end 240.293173 131.58)
		(width 0.1)
		(layer "In7.Cu")
		(net 43)
	)
	(segment
		(start 210.844669 127.625)
		(end 210.625 127.844669)
		(width 0.1)
		(layer "In7.Cu")
		(net 43)
	)
	(segment
		(start 241.44 133.615)
		(end 250.025 142.2)
		(width 0.1)
		(layer "In7.Cu")
		(net 43)
	)
	(segment
		(start 210.625 127.844669)
		(end 210.625 128.322158)
		(width 0.1)
		(layer "In7.Cu")
		(net 43)
	)
	(segment
		(start 241.44 132.726827)
		(end 241.44 133.615)
		(width 0.1)
		(layer "In7.Cu")
		(net 43)
	)
	(segment
		(start 251.45 142.2)
		(end 252.1 142.85)
		(width 0.1)
		(layer "In7.Cu")
		(net 43)
	)
	(segment
		(start 228.59 124)
		(end 236.17 131.58)
		(width 0.1)
		(layer "In7.Cu")
		(net 43)
	)
	(segment
		(start 210.625 128.322158)
		(end 210 128.947158)
		(width 0.1)
		(layer "In7.Cu")
		(net 43)
	)
	(segment
		(start 219.9 123.8)
		(end 216.075 127.625)
		(width 0.1)
		(layer "In7.Cu")
		(net 43)
	)
	(segment
		(start 224.25 124)
		(end 224.05 123.8)
		(width 0.1)
		(layer "In7.Cu")
		(net 43)
	)
	(segment
		(start 224.05 123.8)
		(end 219.9 123.8)
		(width 0.1)
		(layer "In7.Cu")
		(net 43)
	)
	(segment
		(start 210 128.947158)
		(end 210 129)
		(width 0.1)
		(layer "In7.Cu")
		(net 43)
	)
	(segment
		(start 239.4 125)
		(end 239.4 124.2)
		(width 0.1)
		(layer "F.Cu")
		(net 45)
	)
	(segment
		(start 239.975 128.025)
		(end 239.8 127.85)
		(width 0.1)
		(layer "F.Cu")
		(net 45)
	)
	(segment
		(start 239.8 125.4)
		(end 239.4 125)
		(width 0.1)
		(layer "F.Cu")
		(net 45)
	)
	(segment
		(start 239.8 127.85)
		(end 239.8 125.4)
		(width 0.1)
		(layer "F.Cu")
		(net 45)
	)
	(via
		(at 239.975 128.025)
		(size 0.45)
		(drill 0.2)
		(layers "F.Cu" "B.Cu")
		(net 45)
	)
	(segment
		(start 240.45 139.1)
		(end 242.015 139.1)
		(width 0.1)
		(layer "B.Cu")
		(net 45)
	)
	(segment
		(start 240 128.05)
		(end 240 132)
		(width 0.1)
		(layer "B.Cu")
		(net 45)
	)
	(segment
		(start 238.925 134.875)
		(end 240 135.95)
		(width 0.1)
		(layer "B.Cu")
		(net 45)
	)
	(segment
		(start 240 138.65)
		(end 240.45 139.1)
		(width 0.1)
		(layer "B.Cu")
		(net 45)
	)
	(segment
		(start 240 132)
		(end 238.925 133.075)
		(width 0.1)
		(layer "B.Cu")
		(net 45)
	)
	(segment
		(start 239.975 128.025)
		(end 240 128.05)
		(width 0.1)
		(layer "B.Cu")
		(net 45)
	)
	(segment
		(start 240 135.95)
		(end 240 138.65)
		(width 0.1)
		(layer "B.Cu")
		(net 45)
	)
	(segment
		(start 238.925 133.075)
		(end 238.925 134.875)
		(width 0.1)
		(layer "B.Cu")
		(net 45)
	)
	(segment
		(start 240 124.854)
		(end 240 126.925)
		(width 0.1)
		(layer "F.Cu")
		(net 46)
	)
	(segment
		(start 240.3 127.225)
		(end 240 126.925)
		(width 0.1)
		(layer "F.Cu")
		(net 46)
	)
	(segment
		(start 241.025 127.4)
		(end 240.85 127.225)
		(width 0.1)
		(layer "F.Cu")
		(net 46)
	)
	(segment
		(start 241.025 128.15)
		(end 241.025 127.4)
		(width 0.1)
		(layer "F.Cu")
		(net 46)
	)
	(segment
		(start 240.85 127.225)
		(end 240.3 127.225)
		(width 0.1)
		(layer "F.Cu")
		(net 46)
	)
	(via
		(at 241.025 128.15)
		(size 0.45)
		(drill 0.2)
		(layers "F.Cu" "B.Cu")
		(net 46)
	)
	(segment
		(start 241.95 128.15)
		(end 241.025 128.15)
		(width 0.1)
		(layer "B.Cu")
		(net 46)
	)
	(segment
		(start 242.985 133.9)
		(end 243.425 133.46)
		(width 0.1)
		(layer "B.Cu")
		(net 46)
	)
	(segment
		(start 243.425 133.46)
		(end 243.425 132.825)
		(width 0.1)
		(layer "B.Cu")
		(net 46)
	)
	(segment
		(start 243.425 132.825)
		(end 243.125 132.525)
		(width 0.1)
		(layer "B.Cu")
		(net 46)
	)
	(segment
		(start 243.125 132.525)
		(end 243.125 129.325)
		(width 0.1)
		(layer "B.Cu")
		(net 46)
	)
	(segment
		(start 243.125 129.325)
		(end 241.95 128.15)
		(width 0.1)
		(layer "B.Cu")
		(net 46)
	)
	(segment
		(start 246.6 142.45)
		(end 246.6 142.085)
		(width 0.1)
		(layer "F.Cu")
		(net 54)
	)
	(segment
		(start 246.775 142.625)
		(end 246.6 142.45)
		(width 0.1)
		(layer "F.Cu")
		(net 54)
	)
	(via
		(at 246.775 142.625)
		(size 0.45)
		(drill 0.2)
		(layers "F.Cu" "B.Cu")
		(net 54)
	)
	(via
		(at 235.05 133.6)
		(size 0.45)
		(drill 0.2)
		(layers "F.Cu" "B.Cu")
		(net 54)
	)
	(via
		(at 248.73 126.36)
		(size 0.45)
		(drill 0.2)
		(layers "F.Cu" "B.Cu")
		(net 54)
	)
	(segment
		(start 248.329095 126.360905)
		(end 248.729095 126.360905)
		(width 0.1)
		(layer "B.Cu")
		(net 54)
	)
	(segment
		(start 248.729095 126.360905)
		(end 248.73 126.36)
		(width 0.1)
		(layer "B.Cu")
		(net 54)
	)
	(segment
		(start 243.875 131.355)
		(end 243.875 131.885)
		(width 0.1)
		(layer "In3.Cu")
		(net 54)
	)
	(segment
		(start 238.65 127.75)
		(end 239.08 127.75)
		(width 0.1)
		(layer "In3.Cu")
		(net 54)
	)
	(segment
		(start 244.6 139.519669)
		(end 244.025 140.094669)
		(width 0.1)
		(layer "In3.Cu")
		(net 54)
	)
	(segment
		(start 244.23 140.91)
		(end 245.06 140.91)
		(width 0.1)
		(layer "In3.Cu")
		(net 54)
	)
	(segment
		(start 235.69 132.96)
		(end 235.69 130.71)
		(width 0.1)
		(layer "In3.Cu")
		(net 54)
	)
	(segment
		(start 240.06 128.73)
		(end 241.25 128.73)
		(width 0.1)
		(layer "In3.Cu")
		(net 54)
	)
	(segment
		(start 245.06 140.91)
		(end 246.775 142.625)
		(width 0.1)
		(layer "In3.Cu")
		(net 54)
	)
	(segment
		(start 235.05 133.6)
		(end 235.69 132.96)
		(width 0.1)
		(layer "In3.Cu")
		(net 54)
	)
	(segment
		(start 239.08 127.75)
		(end 240.06 128.73)
		(width 0.1)
		(layer "In3.Cu")
		(net 54)
	)
	(segment
		(start 243.875 131.885)
		(end 244.6 132.61)
		(width 0.1)
		(layer "In3.Cu")
		(net 54)
	)
	(segment
		(start 244.025 140.705)
		(end 244.23 140.91)
		(width 0.1)
		(layer "In3.Cu")
		(net 54)
	)
	(segment
		(start 244.025 140.094669)
		(end 244.025 140.705)
		(width 0.1)
		(layer "In3.Cu")
		(net 54)
	)
	(segment
		(start 235.69 130.71)
		(end 238.65 127.75)
		(width 0.1)
		(layer "In3.Cu")
		(net 54)
	)
	(segment
		(start 241.25 128.73)
		(end 243.875 131.355)
		(width 0.1)
		(layer "In3.Cu")
		(net 54)
	)
	(segment
		(start 244.6 132.61)
		(end 244.6 139.519669)
		(width 0.1)
		(layer "In3.Cu")
		(net 54)
	)
	(segment
		(start 239.35 128.775)
		(end 235.05 133.075)
		(width 0.1)
		(layer "In5.Cu")
		(net 54)
	)
	(segment
		(start 244.275 127.55)
		(end 243.05 128.775)
		(width 0.1)
		(layer "In5.Cu")
		(net 54)
	)
	(segment
		(start 235.05 133.075)
		(end 235.05 133.6)
		(width 0.1)
		(layer "In5.Cu")
		(net 54)
	)
	(segment
		(start 248.445 126.075)
		(end 245.225 126.075)
		(width 0.1)
		(layer "In5.Cu")
		(net 54)
	)
	(segment
		(start 243.05 128.775)
		(end 239.35 128.775)
		(width 0.1)
		(layer "In5.Cu")
		(net 54)
	)
	(segment
		(start 245.225 126.075)
		(end 244.275 127.025)
		(width 0.1)
		(layer "In5.Cu")
		(net 54)
	)
	(segment
		(start 248.73 126.36)
		(end 248.445 126.075)
		(width 0.1)
		(layer "In5.Cu")
		(net 54)
	)
	(segment
		(start 244.275 127.025)
		(end 244.275 127.55)
		(width 0.1)
		(layer "In5.Cu")
		(net 54)
	)
	(segment
		(start 241.62 127.71)
		(end 241.62 128.44)
		(width 0.1)
		(layer "F.Cu")
		(net 55)
	)
	(segment
		(start 241.62 128.44)
		(end 241.27 128.79)
		(width 0.1)
		(layer "F.Cu")
		(net 55)
	)
	(segment
		(start 241.27 128.79)
		(end 240.69 128.79)
		(width 0.1)
		(layer "F.Cu")
		(net 55)
	)
	(segment
		(start 240.69 128.79)
		(end 240.4 128.5)
		(width 0.1)
		(layer "F.Cu")
		(net 55)
	)
	(via
		(at 241.62 127.71)
		(size 0.45)
		(drill 0.2)
		(layers "F.Cu" "B.Cu")
		(net 55)
	)
	(segment
		(start 243.9 134.5)
		(end 244.25 134.15)
		(width 0.1)
		(layer "B.Cu")
		(net 55)
	)
	(segment
		(start 242.07 127.71)
		(end 241.62 127.71)
		(width 0.1)
		(layer "B.Cu")
		(net 55)
	)
	(segment
		(start 243.15 134.9)
		(end 243.55 134.5)
		(width 0.1)
		(layer "B.Cu")
		(net 55)
	)
	(segment
		(start 244.25 133.3)
		(end 243.9 132.95)
		(width 0.1)
		(layer "B.Cu")
		(net 55)
	)
	(segment
		(start 243.55 134.5)
		(end 243.9 134.5)
		(width 0.1)
		(layer "B.Cu")
		(net 55)
	)
	(segment
		(start 243.9 129.54)
		(end 242.07 127.71)
		(width 0.1)
		(layer "B.Cu")
		(net 55)
	)
	(segment
		(start 243.9 132.95)
		(end 243.9 129.54)
		(width 0.1)
		(layer "B.Cu")
		(net 55)
	)
	(segment
		(start 244.25 134.15)
		(end 244.25 133.3)
		(width 0.1)
		(layer "B.Cu")
		(net 55)
	)
	(segment
		(start 242.985 134.9)
		(end 243.15 134.9)
		(width 0.1)
		(layer "B.Cu")
		(net 55)
	)
	(segment
		(start 236.4 120.5)
		(end 236.4 121.5)
		(width 0.1)
		(layer "F.Cu")
		(net 56)
	)
	(segment
		(start 236.375 121.5)
		(end 236.4 121.5)
		(width 0.1)
		(layer "F.Cu")
		(net 56)
	)
	(segment
		(start 236.4 119.5)
		(end 236.4 120.5)
		(width 0.1)
		(layer "F.Cu")
		(net 56)
	)
	(segment
		(start 194 116)
		(end 194.5 116.5)
		(width 0.256)
		(layer "F.Cu")
		(net 56)
	)
	(via
		(at 194 116)
		(size 0.45)
		(drill 0.2)
		(layers "F.Cu" "B.Cu")
		(net 56)
	)
	(via
		(at 251.7 126.7)
		(size 0.45)
		(drill 0.2)
		(layers "F.Cu" "B.Cu")
		(net 56)
	)
	(via
		(at 236.375 121.5)
		(size 0.45)
		(drill 0.2)
		(layers "F.Cu" "B.Cu")
		(net 56)
	)
	(via
		(at 217.9 120.6)
		(size 0.45)
		(drill 0.2)
		(layers "F.Cu" "B.Cu")
		(net 56)
	)
	(segment
		(start 194.495 115.505)
		(end 194.495 114.735)
		(width 0.1)
		(layer "B.Cu")
		(net 56)
	)
	(segment
		(start 195.295 113.935)
		(end 214.045 113.935)
		(width 0.1)
		(layer "B.Cu")
		(net 56)
	)
	(segment
		(start 218 117.89)
		(end 218 120.5)
		(width 0.1)
		(layer "B.Cu")
		(net 56)
	)
	(segment
		(start 218 120.5)
		(end 217.9 120.6)
		(width 0.1)
		(layer "B.Cu")
		(net 56)
	)
	(segment
		(start 194.495 114.735)
		(end 195.295 113.935)
		(width 0.1)
		(layer "B.Cu")
		(net 56)
	)
	(segment
		(start 214.045 113.935)
		(end 218 117.89)
		(width 0.1)
		(layer "B.Cu")
		(net 56)
	)
	(segment
		(start 194 116)
		(end 194.495 115.505)
		(width 0.1)
		(layer "B.Cu")
		(net 56)
	)
	(segment
		(start 251.7 127.073)
		(end 251.7 126.7)
		(width 0.1)
		(layer "B.Cu")
		(net 56)
	)
	(segment
		(start 250.125 126.7)
		(end 251.7 126.7)
		(width 0.1)
		(layer "In7.Cu")
		(net 56)
	)
	(segment
		(start 236.375 121.5)
		(end 236.375 121.55)
		(width 0.1)
		(layer "In7.Cu")
		(net 56)
	)
	(segment
		(start 248.925 125.5)
		(end 250.125 126.7)
		(width 0.1)
		(layer "In7.Cu")
		(net 56)
	)
	(segment
		(start 243.175 125.5)
		(end 248.925 125.5)
		(width 0.1)
		(layer "In7.Cu")
		(net 56)
	)
	(segment
		(start 233.45 127.175)
		(end 241.5 127.175)
		(width 0.1)
		(layer "In7.Cu")
		(net 56)
	)
	(segment
		(start 219.55 122.25)
		(end 217.9 120.6)
		(width 0.1)
		(layer "In7.Cu")
		(net 56)
	)
	(segment
		(start 235.575 123.7)
		(end 235.1 123.225)
		(width 0.1)
		(layer "In7.Cu")
		(net 56)
	)
	(segment
		(start 236.85 122.025)
		(end 236.85 123.275)
		(width 0.1)
		(layer "In7.Cu")
		(net 56)
	)
	(segment
		(start 236.425 123.7)
		(end 235.575 123.7)
		(width 0.1)
		(layer "In7.Cu")
		(net 56)
	)
	(segment
		(start 232.425 124.3)
		(end 232.425 126.15)
		(width 0.1)
		(layer "In7.Cu")
		(net 56)
	)
	(segment
		(start 236.375 121.55)
		(end 236.85 122.025)
		(width 0.1)
		(layer "In7.Cu")
		(net 56)
	)
	(segment
		(start 236.375 121.5)
		(end 235.625 122.25)
		(width 0.1)
		(layer "In7.Cu")
		(net 56)
	)
	(segment
		(start 233.5 123.225)
		(end 232.425 124.3)
		(width 0.1)
		(layer "In7.Cu")
		(net 56)
	)
	(segment
		(start 235.625 122.25)
		(end 219.55 122.25)
		(width 0.1)
		(layer "In7.Cu")
		(net 56)
	)
	(segment
		(start 235.1 123.225)
		(end 233.5 123.225)
		(width 0.1)
		(layer "In7.Cu")
		(net 56)
	)
	(segment
		(start 232.425 126.15)
		(end 233.45 127.175)
		(width 0.1)
		(layer "In7.Cu")
		(net 56)
	)
	(segment
		(start 241.5 127.175)
		(end 243.175 125.5)
		(width 0.1)
		(layer "In7.Cu")
		(net 56)
	)
	(segment
		(start 236.85 123.275)
		(end 236.425 123.7)
		(width 0.1)
		(layer "In7.Cu")
		(net 56)
	)
	(segment
		(start 155.015001 130.765001)
		(end 155 130.75)
		(width 0.4)
		(layer "F.Cu")
		(net 59)
	)
	(segment
		(start 154.45 126.39)
		(end 155.015001 126.955001)
		(width 0.4)
		(layer "F.Cu")
		(net 59)
	)
	(segment
		(start 165.175001 124.319401)
		(end 165.748001 123.746401)
		(width 0.177)
		(layer "F.Cu")
		(net 59)
	)
	(segment
		(start 165.175001 124.415001)
		(end 165.175001 124.319401)
		(width 0.177)
		(layer "F.Cu")
		(net 59)
	)
	(segment
		(start 154.45 126.25)
		(end 154.45 126.39)
		(width 0.4)
		(layer "F.Cu")
		(net 59)
	)
	(segment
		(start 155.015001 125.685001)
		(end 154.45 126.25)
		(width 0.4)
		(layer "F.Cu")
		(net 59)
	)
	(via
		(at 154.45 126.25)
		(size 0.45)
		(drill 0.2)
		(layers "F.Cu" "B.Cu")
		(net 59)
	)
	(via
		(at 155 130.75)
		(size 0.45)
		(drill 0.2)
		(layers "F.Cu" "B.Cu")
		(net 59)
	)
	(via
		(at 165.175001 126.955001)
		(size 0.45)
		(drill 0.2)
		(layers "F.Cu" "B.Cu")
		(net 59)
	)
	(via
		(at 165.748001 123.746401)
		(size 0.45)
		(drill 0.2)
		(layers "F.Cu" "B.Cu")
		(net 59)
	)
	(segment
		(start 165.240001 125.680001)
		(end 165.245001 125.685001)
		(width 0.4)
		(layer "B.Cu")
		(net 59)
	)
	(segment
		(start 165.245001 125.685001)
		(end 165.245001 126.885001)
		(width 0.4)
		(layer "B.Cu")
		(net 59)
	)
	(segment
		(start 165.160401 126.969601)
		(end 165.175001 126.955001)
		(width 0.4)
		(layer "B.Cu")
		(net 59)
	)
	(segment
		(start 165.245001 126.885001)
		(end 165.175001 126.955001)
		(width 0.4)
		(layer "B.Cu")
		(net 59)
	)
	(segment
		(start 165.160401 128.826401)
		(end 165.160401 126.969601)
		(width 0.4)
		(layer "B.Cu")
		(net 59)
	)
	(segment
		(start 165.240001 124.254401)
		(end 165.240001 125.680001)
		(width 0.4)
		(layer "B.Cu")
		(net 59)
	)
	(segment
		(start 165.748001 123.746401)
		(end 165.240001 124.254401)
		(width 0.4)
		(layer "B.Cu")
		(net 59)
	)
	(segment
		(start 165.175001 82.505001)
		(end 165.175001 82.686198)
		(width 0.16)
		(layer "F.Cu")
		(net 60)
	)
	(segment
		(start 165.175001 82.686198)
		(end 165.496804 83.008001)
		(width 0.16)
		(layer "F.Cu")
		(net 60)
	)
	(segment
		(start 165.665002 83.008)
		(end 165.810001 82.863001)
		(width 0.16)
		(layer "F.Cu")
		(net 60)
	)
	(segment
		(start 165.665002 83.008)
		(end 165.496804 83.008001)
		(width 0.16)
		(layer "F.Cu")
		(net 60)
	)
	(via
		(at 165.810001 82.863001)
		(size 0.45)
		(drill 0.2)
		(layers "F.Cu" "B.Cu")
		(net 60)
	)
	(segment
		(start 165.955 83.008)
		(end 166.287001 83.008001)
		(width 0.16)
		(layer "B.Cu")
		(net 60)
	)
	(segment
		(start 166.287001 83.008001)
		(end 166.660001 82.635001)
		(width 0.16)
		(layer "B.Cu")
		(net 60)
	)
	(segment
		(start 165.810001 82.863001)
		(end 165.955 83.008)
		(width 0.16)
		(layer "B.Cu")
		(net 60)
	)
	(via
		(at 188.500001 125.500001)
		(size 0.45)
		(drill 0.2)
		(layers "F.Cu" "B.Cu")
		(net 61)
	)
	(segment
		(start 185.24 124.900001)
		(end 185.139 124.799)
		(width 0.1)
		(layer "B.Cu")
		(net 61)
	)
	(segment
		(start 188.210001 125.500001)
		(end 188.099399 125.389399)
		(width 0.1)
		(layer "B.Cu")
		(net 61)
	)
	(segment
		(start 167.929501 82.934501)
		(end 170.676951 82.934501)
		(width 0.201)
		(layer "B.Cu")
		(net 61)
	)
	(segment
		(start 188.099399 125.389399)
		(end 188.099399 125.137977)
		(width 0.1)
		(layer "B.Cu")
		(net 61)
	)
	(segment
		(start 178.123051 81.199501)
		(end 179.660501 82.736951)
		(width 0.201)
		(layer "B.Cu")
		(net 61)
	)
	(segment
		(start 184.821001 89.837451)
		(end 184.821001 111.772549)
		(width 0.201)
		(layer "B.Cu")
		(net 61)
	)
	(segment
		(start 188.500001 125.500001)
		(end 188.210001 125.500001)
		(width 0.1)
		(layer "B.Cu")
		(net 61)
	)
	(segment
		(start 184.819001 111.774549)
		(end 184.819001 124.613849)
		(width 0.201)
		(layer "B.Cu")
		(net 61)
	)
	(segment
		(start 172.411951 81.199501)
		(end 178.123051 81.199501)
		(width 0.201)
		(layer "B.Cu")
		(net 61)
	)
	(segment
		(start 179.660501 84.676951)
		(end 184.821001 89.837451)
		(width 0.201)
		(layer "B.Cu")
		(net 61)
	)
	(segment
		(start 179.660501 82.736951)
		(end 179.660501 84.676951)
		(width 0.201)
		(layer "B.Cu")
		(net 61)
	)
	(segment
		(start 170.676951 82.934501)
		(end 172.411951 81.199501)
		(width 0.201)
		(layer "B.Cu")
		(net 61)
	)
	(segment
		(start 184.819001 124.613849)
		(end 185.004152 124.799)
		(width 0.201)
		(layer "B.Cu")
		(net 61)
	)
	(segment
		(start 185.004152 124.799)
		(end 185.139 124.799)
		(width 0.201)
		(layer "B.Cu")
		(net 61)
	)
	(segment
		(start 188.099399 125.137977)
		(end 187.861423 124.900001)
		(width 0.1)
		(layer "B.Cu")
		(net 61)
	)
	(segment
		(start 167.630001 82.635001)
		(end 167.929501 82.934501)
		(width 0.201)
		(layer "B.Cu")
		(net 61)
	)
	(segment
		(start 185.24 124.900001)
		(end 187.861423 124.900001)
		(width 0.1)
		(layer "B.Cu")
		(net 61)
	)
	(segment
		(start 184.821001 111.772549)
		(end 184.819001 111.774549)
		(width 0.201)
		(layer "B.Cu")
		(net 61)
	)
	(segment
		(start 165.496804 83.272001)
		(end 165.175001 83.593804)
		(width 0.16)
		(layer "F.Cu")
		(net 62)
	)
	(segment
		(start 165.175001 83.593804)
		(end 165.175001 83.775001)
		(width 0.16)
		(layer "F.Cu")
		(net 62)
	)
	(segment
		(start 165.665002 83.272002)
		(end 165.496804 83.272001)
		(width 0.16)
		(layer "F.Cu")
		(net 62)
	)
	(segment
		(start 165.665002 83.272002)
		(end 165.810001 83.417001)
		(width 0.16)
		(layer "F.Cu")
		(net 62)
	)
	(via
		(at 165.810001 83.417001)
		(size 0.45)
		(drill 0.2)
		(layers "F.Cu" "B.Cu")
		(net 62)
	)
	(segment
		(start 165.810001 83.417001)
		(end 165.955 83.272002)
		(width 0.16)
		(layer "B.Cu")
		(net 62)
	)
	(segment
		(start 166.297001 83.272001)
		(end 166.660001 83.635001)
		(width 0.16)
		(layer "B.Cu")
		(net 62)
	)
	(segment
		(start 165.955 83.272002)
		(end 166.297001 83.272001)
		(width 0.16)
		(layer "B.Cu")
		(net 62)
	)
	(via
		(at 187.500001 125.500001)
		(size 0.45)
		(drill 0.2)
		(layers "F.Cu" "B.Cu")
		(net 63)
	)
	(segment
		(start 179.259501 84.843051)
		(end 184.420001 90.003551)
		(width 0.201)
		(layer "B.Cu")
		(net 63)
	)
	(segment
		(start 187.899399 125.430603)
		(end 187.830001 125.500002)
		(width 0.1)
		(layer "B.Cu")
		(net 63)
	)
	(segment
		(start 187.260001 125.100001)
		(end 187.778579 125.100001)
		(width 0.1)
		(layer "B.Cu")
		(net 63)
	)
	(segment
		(start 187.830001 125.500002)
		(end 187.500001 125.500001)
		(width 0.1)
		(layer "B.Cu")
		(net 63)
	)
	(segment
		(start 184.420001 90.003551)
		(end 184.420001 111.606449)
		(width 0.201)
		(layer "B.Cu")
		(net 63)
	)
	(segment
		(start 185.239 125.1)
		(end 185.804001 125.100001)
		(width 0.1)
		(layer "B.Cu")
		(net 63)
	)
	(segment
		(start 185.904001 125.200001)
		(end 185.904001 125.223544)
		(width 0.1)
		(layer "B.Cu")
		(net 63)
	)
	(segment
		(start 177.956951 81.600501)
		(end 179.259501 82.903051)
		(width 0.201)
		(layer "B.Cu")
		(net 63)
	)
	(segment
		(start 184.838052 125.2)
		(end 185.139 125.2)
		(width 0.201)
		(layer "B.Cu")
		(net 63)
	)
	(segment
		(start 184.420001 111.606449)
		(end 184.418001 111.608449)
		(width 0.201)
		(layer "B.Cu")
		(net 63)
	)
	(segment
		(start 167.630001 83.635001)
		(end 167.929501 83.335501)
		(width 0.201)
		(layer "B.Cu")
		(net 63)
	)
	(segment
		(start 185.139 125.2)
		(end 185.239 125.1)
		(width 0.1)
		(layer "B.Cu")
		(net 63)
	)
	(segment
		(start 184.418001 111.608449)
		(end 184.418001 124.779949)
		(width 0.201)
		(layer "B.Cu")
		(net 63)
	)
	(segment
		(start 184.418001 124.779949)
		(end 184.838052 125.2)
		(width 0.201)
		(layer "B.Cu")
		(net 63)
	)
	(segment
		(start 187.899399 125.220821)
		(end 187.899399 125.430603)
		(width 0.1)
		(layer "B.Cu")
		(net 63)
	)
	(segment
		(start 170.843051 83.335501)
		(end 172.578051 81.600501)
		(width 0.201)
		(layer "B.Cu")
		(net 63)
	)
	(segment
		(start 179.259501 82.903051)
		(end 179.259501 84.843051)
		(width 0.201)
		(layer "B.Cu")
		(net 63)
	)
	(segment
		(start 187.778579 125.100001)
		(end 187.899399 125.220821)
		(width 0.1)
		(layer "B.Cu")
		(net 63)
	)
	(segment
		(start 172.578051 81.600501)
		(end 177.956951 81.600501)
		(width 0.201)
		(layer "B.Cu")
		(net 63)
	)
	(segment
		(start 186.104001 125.223544)
		(end 186.104001 125.200001)
		(width 0.1)
		(layer "B.Cu")
		(net 63)
	)
	(segment
		(start 167.929501 83.335501)
		(end 170.843051 83.335501)
		(width 0.201)
		(layer "B.Cu")
		(net 63)
	)
	(segment
		(start 186.204001 125.100001)
		(end 186.660001 125.100001)
		(width 0.1)
		(layer "B.Cu")
		(net 63)
	)
	(arc
		(start 185.904001 125.223544)
		(mid 185.93329 125.294255)
		(end 186.004001 125.323544)
		(width 0.1)
		(layer "B.Cu")
		(net 63)
	)
	(arc
		(start 186.960001 125.400001)
		(mid 187.066067 125.356067)
		(end 187.110001 125.250001)
		(width 0.1)
		(layer "B.Cu")
		(net 63)
	)
	(arc
		(start 186.104001 125.200001)
		(mid 186.13329 125.12929)
		(end 186.204001 125.100001)
		(width 0.1)
		(layer "B.Cu")
		(net 63)
	)
	(arc
		(start 185.804001 125.100001)
		(mid 185.874712 125.12929)
		(end 185.904001 125.200001)
		(width 0.1)
		(layer "B.Cu")
		(net 63)
	)
	(arc
		(start 186.810001 125.250001)
		(mid 186.853935 125.356067)
		(end 186.960001 125.400001)
		(width 0.1)
		(layer "B.Cu")
		(net 63)
	)
	(arc
		(start 187.110001 125.250001)
		(mid 187.153935 125.143935)
		(end 187.260001 125.100001)
		(width 0.1)
		(layer "B.Cu")
		(net 63)
	)
	(arc
		(start 186.004001 125.323544)
		(mid 186.074712 125.294255)
		(end 186.104001 125.223544)
		(width 0.1)
		(layer "B.Cu")
		(net 63)
	)
	(arc
		(start 186.660001 125.100001)
		(mid 186.766067 125.143935)
		(end 186.810001 125.250001)
		(width 0.1)
		(layer "B.Cu")
		(net 63)
	)
	(segment
		(start 172.809251 108.339501)
		(end 170.572501 108.339501)
		(width 0.201)
		(layer "F.Cu")
		(net 64)
	)
	(segment
		(start 173.085001 108.063751)
		(end 172.809251 108.339501)
		(width 0.201)
		(layer "F.Cu")
		(net 64)
	)
	(segment
		(start 168.218 108.408)
		(end 170.504001 108.408001)
		(width 0.16)
		(layer "F.Cu")
		(net 64)
	)
	(segment
		(start 170.504001 108.408001)
		(end 170.572501 108.339501)
		(width 0.16)
		(layer "F.Cu")
		(net 64)
	)
	(segment
		(start 167.715001 107.905001)
		(end 168.218 108.408)
		(width 0.16)
		(layer "F.Cu")
		(net 64)
	)
	(segment
		(start 186.099399 126.137978)
		(end 185.861423 125.900001)
		(width 0.1)
		(layer "F.Cu")
		(net 65)
	)
	(segment
		(start 174.330751 108.339501)
		(end 182.253051 108.339501)
		(width 0.201)
		(layer "F.Cu")
		(net 65)
	)
	(segment
		(start 186.099399 126.389399)
		(end 186.099399 126.137978)
		(width 0.1)
		(layer "F.Cu")
		(net 65)
	)
	(segment
		(start 183.5205 125.45695)
		(end 183.86255 125.799)
		(width 0.201)
		(layer "F.Cu")
		(net 65)
	)
	(segment
		(start 184.51 125.9)
		(end 185.861423 125.900001)
		(width 0.1)
		(layer "F.Cu")
		(net 65)
	)
	(segment
		(start 184.51 125.9)
		(end 184.409 125.799)
		(width 0.1)
		(layer "F.Cu")
		(net 65)
	)
	(segment
		(start 174.055001 108.063751)
		(end 174.330751 108.339501)
		(width 0.201)
		(layer "F.Cu")
		(net 65)
	)
	(segment
		(start 186.210001 126.500001)
		(end 186.099399 126.389399)
		(width 0.1)
		(layer "F.Cu")
		(net 65)
	)
	(segment
		(start 183.86255 125.799)
		(end 184.409 125.799)
		(width 0.201)
		(layer "F.Cu")
		(net 65)
	)
	(segment
		(start 182.253051 108.339501)
		(end 183.5205 109.60695)
		(width 0.201)
		(layer "F.Cu")
		(net 65)
	)
	(segment
		(start 186.500001 126.500001)
		(end 186.210001 126.500001)
		(width 0.1)
		(layer "F.Cu")
		(net 65)
	)
	(segment
		(start 183.5205 109.60695)
		(end 183.5205 125.45695)
		(width 0.201)
		(layer "F.Cu")
		(net 65)
	)
	(segment
		(start 167.715001 109.175001)
		(end 168.218 108.672002)
		(width 0.16)
		(layer "F.Cu")
		(net 67)
	)
	(segment
		(start 170.504001 108.672001)
		(end 170.572501 108.740501)
		(width 0.16)
		(layer "F.Cu")
		(net 67)
	)
	(segment
		(start 172.809251 108.740501)
		(end 170.572501 108.740501)
		(width 0.201)
		(layer "F.Cu")
		(net 67)
	)
	(segment
		(start 173.085001 109.016251)
		(end 172.809251 108.740501)
		(width 0.201)
		(layer "F.Cu")
		(net 67)
	)
	(segment
		(start 168.218 108.672002)
		(end 170.504001 108.672001)
		(width 0.16)
		(layer "F.Cu")
		(net 67)
	)
	(segment
		(start 185.8994 126.220821)
		(end 185.77858 126.100001)
		(width 0.1)
		(layer "F.Cu")
		(net 69)
	)
	(segment
		(start 183.1195 125.62305)
		(end 183.69645 126.2)
		(width 0.201)
		(layer "F.Cu")
		(net 69)
	)
	(segment
		(start 185.069001 126.250001)
		(end 185.069001 126.373202)
		(width 0.1)
		(layer "F.Cu")
		(net 69)
	)
	(segment
		(start 183.69645 126.2)
		(end 184.41 126.2)
		(width 0.201)
		(layer "F.Cu")
		(net 69)
	)
	(segment
		(start 185.77858 126.100001)
		(end 185.219001 126.100001)
		(width 0.1)
		(layer "F.Cu")
		(net 69)
	)
	(segment
		(start 184.769001 126.373202)
		(end 184.769001 126.250001)
		(width 0.1)
		(layer "F.Cu")
		(net 69)
	)
	(segment
		(start 185.500001 126.500001)
		(end 185.830002 126.500001)
		(width 0.1)
		(layer "F.Cu")
		(net 69)
	)
	(segment
		(start 184.51 126.099999)
		(end 184.41 126.2)
		(width 0.1)
		(layer "F.Cu")
		(net 69)
	)
	(segment
		(start 183.1195 109.77305)
		(end 183.1195 125.62305)
		(width 0.201)
		(layer "F.Cu")
		(net 69)
	)
	(segment
		(start 174.330751 108.740501)
		(end 182.086951 108.740501)
		(width 0.201)
		(layer "F.Cu")
		(net 69)
	)
	(segment
		(start 185.8994 126.430604)
		(end 185.8994 126.220821)
		(width 0.1)
		(layer "F.Cu")
		(net 69)
	)
	(segment
		(start 174.055001 109.016251)
		(end 174.330751 108.740501)
		(width 0.201)
		(layer "F.Cu")
		(net 69)
	)
	(segment
		(start 184.510002 126.100001)
		(end 184.619001 126.100001)
		(width 0.1)
		(layer "F.Cu")
		(net 69)
	)
	(segment
		(start 182.086951 108.740501)
		(end 183.1195 109.77305)
		(width 0.201)
		(layer "F.Cu")
		(net 69)
	)
	(segment
		(start 185.830002 126.500001)
		(end 185.8994 126.430604)
		(width 0.1)
		(layer "F.Cu")
		(net 69)
	)
	(arc
		(start 184.919001 126.523202)
		(mid 184.812935 126.479268)
		(end 184.769001 126.373202)
		(width 0.1)
		(layer "F.Cu")
		(net 69)
	)
	(arc
		(start 184.769001 126.250001)
		(mid 184.725067 126.143935)
		(end 184.619001 126.100001)
		(width 0.1)
		(layer "F.Cu")
		(net 69)
	)
	(arc
		(start 185.219001 126.100001)
		(mid 185.112935 126.143935)
		(end 185.069001 126.250001)
		(width 0.1)
		(layer "F.Cu")
		(net 69)
	)
	(arc
		(start 185.069001 126.373202)
		(mid 185.025067 126.479268)
		(end 184.919001 126.523202)
		(width 0.1)
		(layer "F.Cu")
		(net 69)
	)
	(segment
		(start 172.809251 113.419501)
		(end 170.572501 113.419501)
		(width 0.201)
		(layer "F.Cu")
		(net 71)
	)
	(segment
		(start 173.085001 113.143751)
		(end 172.809251 113.419501)
		(width 0.201)
		(layer "F.Cu")
		(net 71)
	)
	(segment
		(start 170.504001 113.488001)
		(end 170.572501 113.419501)
		(width 0.16)
		(layer "F.Cu")
		(net 71)
	)
	(segment
		(start 167.715001 112.985001)
		(end 168.218 113.488)
		(width 0.16)
		(layer "F.Cu")
		(net 71)
	)
	(segment
		(start 168.218 113.488)
		(end 170.504001 113.488001)
		(width 0.16)
		(layer "F.Cu")
		(net 71)
	)
	(segment
		(start 188.210001 127.500001)
		(end 188.099399 127.389399)
		(width 0.1)
		(layer "F.Cu")
		(net 73)
	)
	(segment
		(start 188.500001 127.500001)
		(end 188.210001 127.500001)
		(width 0.1)
		(layer "F.Cu")
		(net 73)
	)
	(segment
		(start 183.446376 126.900001)
		(end 183.345376 126.799001)
		(width 0.1)
		(layer "F.Cu")
		(net 73)
	)
	(segment
		(start 174.055001 113.143751)
		(end 174.330751 113.419501)
		(width 0.201)
		(layer "F.Cu")
		(net 73)
	)
	(segment
		(start 182.826732 126.799001)
		(end 183.345376 126.799001)
		(width 0.201)
		(layer "F.Cu")
		(net 73)
	)
	(segment
		(start 182.220501 114.536951)
		(end 182.220501 126.19277)
		(width 0.201)
		(layer "F.Cu")
		(net 73)
	)
	(segment
		(start 188.099399 127.389399)
		(end 188.099399 127.137977)
		(width 0.1)
		(layer "F.Cu")
		(net 73)
	)
	(segment
		(start 188.099399 127.137977)
		(end 187.861423 126.900001)
		(width 0.1)
		(layer "F.Cu")
		(net 73)
	)
	(segment
		(start 181.103051 113.419501)
		(end 182.220501 114.536951)
		(width 0.201)
		(layer "F.Cu")
		(net 73)
	)
	(segment
		(start 182.220501 126.19277)
		(end 182.826732 126.799001)
		(width 0.201)
		(layer "F.Cu")
		(net 73)
	)
	(segment
		(start 174.330751 113.419501)
		(end 181.103051 113.419501)
		(width 0.201)
		(layer "F.Cu")
		(net 73)
	)
	(segment
		(start 187.861423 126.900001)
		(end 183.446376 126.900001)
		(width 0.1)
		(layer "F.Cu")
		(net 73)
	)
	(segment
		(start 263.025 129.275)
		(end 263.575 129.825)
		(width 0.184)
		(layer "B.Cu")
		(net 74)
	)
	(segment
		(start 252.125 129.9)
		(end 255.45 129.9)
		(width 0.184)
		(layer "B.Cu")
		(net 74)
	)
	(segment
		(start 255.45 129.9)
		(end 256.4 128.95)
		(width 0.184)
		(layer "B.Cu")
		(net 74)
	)
	(segment
		(start 258.35 129.275)
		(end 263.025 129.275)
		(width 0.184)
		(layer "B.Cu")
		(net 74)
	)
	(segment
		(start 251.485 129.7)
		(end 251.925 129.7)
		(width 0.184)
		(layer "B.Cu")
		(net 74)
	)
	(segment
		(start 251.925 129.7)
		(end 252.125 129.9)
		(width 0.184)
		(layer "B.Cu")
		(net 74)
	)
	(segment
		(start 258.025 128.95)
		(end 258.35 129.275)
		(width 0.184)
		(layer "B.Cu")
		(net 74)
	)
	(segment
		(start 256.4 128.95)
		(end 258.025 128.95)
		(width 0.184)
		(layer "B.Cu")
		(net 74)
	)
	(segment
		(start 203.5 131.5)
		(end 204 132)
		(width 0.256)
		(layer "F.Cu")
		(net 75)
	)
	(segment
		(start 223.65 124.2)
		(end 223.65 122.9)
		(width 0.1)
		(layer "F.Cu")
		(net 75)
	)
	(segment
		(start 223.65 122.9)
		(end 223.65 118.95)
		(width 0.1)
		(layer "F.Cu")
		(net 75)
	)
	(segment
		(start 249.7 143.473)
		(end 249.7 143.25)
		(width 0.1)
		(layer "F.Cu")
		(net 75)
	)
	(segment
		(start 223.65 118.95)
		(end 224.1 118.5)
		(width 0.1)
		(layer "F.Cu")
		(net 75)
	)
	(segment
		(start 224.1 118.5)
		(end 224.54 118.5)
		(width 0.1)
		(layer "F.Cu")
		(net 75)
	)
	(segment
		(start 224.54 118.5)
		(end 224.54 117.5)
		(width 0.1)
		(layer "F.Cu")
		(net 75)
	)
	(segment
		(start 223.675 124.225)
		(end 223.65 124.2)
		(width 0.1)
		(layer "F.Cu")
		(net 75)
	)
	(via
		(at 249.7 143.25)
		(size 0.45)
		(drill 0.2)
		(layers "F.Cu" "B.Cu")
		(net 75)
	)
	(via
		(at 223.65 122.9)
		(size 0.45)
		(drill 0.2)
		(layers "F.Cu" "B.Cu")
		(net 75)
	)
	(via
		(at 204 132)
		(size 0.45)
		(drill 0.2)
		(layers "F.Cu" "B.Cu")
		(net 75)
	)
	(via
		(at 223.675 124.225)
		(size 0.45)
		(drill 0.2)
		(layers "F.Cu" "B.Cu")
		(net 75)
	)
	(segment
		(start 219.7 122.75)
		(end 216.025 126.425)
		(width 0.1)
		(layer "In7.Cu")
		(net 75)
	)
	(segment
		(start 207.6 132.3)
		(end 207.3 132.6)
		(width 0.1)
		(layer "In7.Cu")
		(net 75)
	)
	(segment
		(start 208.2 131.5)
		(end 207.9 131.5)
		(width 0.1)
		(layer "In7.Cu")
		(net 75)
	)
	(segment
		(start 228.7 124.45)
		(end 236.03 131.78)
		(width 0.1)
		(layer "In7.Cu")
		(net 75)
	)
	(segment
		(start 207.6 131.8)
		(end 207.6 132.3)
		(width 0.1)
		(layer "In7.Cu")
		(net 75)
	)
	(segment
		(start 223.65 122.9)
		(end 223.5 122.75)
		(width 0.1)
		(layer "In7.Cu")
		(net 75)
	)
	(segment
		(start 208.4 128.069669)
		(end 208.4 131.3)
		(width 0.1)
		(layer "In7.Cu")
		(net 75)
	)
	(segment
		(start 216.025 126.425)
		(end 210.044669 126.425)
		(width 0.1)
		(layer "In7.Cu")
		(net 75)
	)
	(segment
		(start 204.6 132.6)
		(end 204 132)
		(width 0.1)
		(layer "In7.Cu")
		(net 75)
	)
	(segment
		(start 223.5 122.75)
		(end 219.7 122.75)
		(width 0.1)
		(layer "In7.Cu")
		(net 75)
	)
	(segment
		(start 241.24 132.809669)
		(end 241.24 133.697842)
		(width 0.1)
		(layer "In7.Cu")
		(net 75)
	)
	(segment
		(start 249.7 142.157842)
		(end 249.7 143.25)
		(width 0.1)
		(layer "In7.Cu")
		(net 75)
	)
	(segment
		(start 223.9 124.45)
		(end 228.7 124.45)
		(width 0.1)
		(layer "In7.Cu")
		(net 75)
	)
	(segment
		(start 240.210331 131.78)
		(end 241.24 132.809669)
		(width 0.1)
		(layer "In7.Cu")
		(net 75)
	)
	(segment
		(start 208.4 131.3)
		(end 208.2 131.5)
		(width 0.1)
		(layer "In7.Cu")
		(net 75)
	)
	(segment
		(start 207.3 132.6)
		(end 204.6 132.6)
		(width 0.1)
		(layer "In7.Cu")
		(net 75)
	)
	(segment
		(start 223.675 124.225)
		(end 223.9 124.45)
		(width 0.1)
		(layer "In7.Cu")
		(net 75)
	)
	(segment
		(start 236.03 131.78)
		(end 240.210331 131.78)
		(width 0.1)
		(layer "In7.Cu")
		(net 75)
	)
	(segment
		(start 207.9 131.5)
		(end 207.6 131.8)
		(width 0.1)
		(layer "In7.Cu")
		(net 75)
	)
	(segment
		(start 210.044669 126.425)
		(end 208.4 128.069669)
		(width 0.1)
		(layer "In7.Cu")
		(net 75)
	)
	(segment
		(start 241.24 133.697842)
		(end 249.7 142.157842)
		(width 0.1)
		(layer "In7.Cu")
		(net 75)
	)
	(segment
		(start 170.504001 113.752001)
		(end 170.572501 113.820501)
		(width 0.16)
		(layer "F.Cu")
		(net 76)
	)
	(segment
		(start 172.809251 113.820501)
		(end 170.572501 113.820501)
		(width 0.201)
		(layer "F.Cu")
		(net 76)
	)
	(segment
		(start 168.218 113.752002)
		(end 170.504001 113.752001)
		(width 0.16)
		(layer "F.Cu")
		(net 76)
	)
	(segment
		(start 173.085001 114.096251)
		(end 172.809251 113.820501)
		(width 0.201)
		(layer "F.Cu")
		(net 76)
	)
	(segment
		(start 167.715001 114.255001)
		(end 168.218 113.752002)
		(width 0.16)
		(layer "F.Cu")
		(net 76)
	)
	(segment
		(start 187.899399 127.220821)
		(end 187.778579 127.100001)
		(width 0.1)
		(layer "F.Cu")
		(net 78)
	)
	(segment
		(start 186.903001 127.206769)
		(end 186.903001 127.200001)
		(width 0.1)
		(layer "F.Cu")
		(net 78)
	)
	(segment
		(start 181.819501 114.703051)
		(end 181.819501 126.35887)
		(width 0.201)
		(layer "F.Cu")
		(net 78)
	)
	(segment
		(start 183.446376 127.100001)
		(end 183.346376 127.200001)
		(width 0.1)
		(layer "F.Cu")
		(net 78)
	)
	(segment
		(start 186.803001 127.100001)
		(end 186.753001 127.100001)
		(width 0.1)
		(layer "F.Cu")
		(net 78)
	)
	(segment
		(start 180.936951 113.820501)
		(end 181.819501 114.703051)
		(width 0.201)
		(layer "F.Cu")
		(net 78)
	)
	(segment
		(start 174.330751 113.820501)
		(end 180.936951 113.820501)
		(width 0.201)
		(layer "F.Cu")
		(net 78)
	)
	(segment
		(start 181.819501 126.35887)
		(end 182.660632 127.200001)
		(width 0.201)
		(layer "F.Cu")
		(net 78)
	)
	(segment
		(start 174.055001 114.096251)
		(end 174.330751 113.820501)
		(width 0.201)
		(layer "F.Cu")
		(net 78)
	)
	(segment
		(start 187.899399 127.430603)
		(end 187.899399 127.220821)
		(width 0.1)
		(layer "F.Cu")
		(net 78)
	)
	(segment
		(start 187.103001 127.200001)
		(end 187.103001 127.206769)
		(width 0.1)
		(layer "F.Cu")
		(net 78)
	)
	(segment
		(start 187.500001 127.500001)
		(end 187.830001 127.500002)
		(width 0.1)
		(layer "F.Cu")
		(net 78)
	)
	(segment
		(start 182.660632 127.200001)
		(end 183.346376 127.200001)
		(width 0.201)
		(layer "F.Cu")
		(net 78)
	)
	(segment
		(start 186.753001 127.100001)
		(end 183.446376 127.100001)
		(width 0.1)
		(layer "F.Cu")
		(net 78)
	)
	(segment
		(start 187.830001 127.500002)
		(end 187.899399 127.430603)
		(width 0.1)
		(layer "F.Cu")
		(net 78)
	)
	(segment
		(start 187.778579 127.100001)
		(end 187.203001 127.100001)
		(width 0.1)
		(layer "F.Cu")
		(net 78)
	)
	(arc
		(start 187.003001 127.306769)
		(mid 186.93229 127.27748)
		(end 186.903001 127.206769)
		(width 0.1)
		(layer "F.Cu")
		(net 78)
	)
	(arc
		(start 186.903001 127.200001)
		(mid 186.873712 127.12929)
		(end 186.803001 127.100001)
		(width 0.1)
		(layer "F.Cu")
		(net 78)
	)
	(arc
		(start 187.103001 127.206769)
		(mid 187.073712 127.27748)
		(end 187.003001 127.306769)
		(width 0.1)
		(layer "F.Cu")
		(net 78)
	)
	(arc
		(start 187.203001 127.100001)
		(mid 187.13229 127.12929)
		(end 187.103001 127.200001)
		(width 0.1)
		(layer "F.Cu")
		(net 78)
	)
	(segment
		(start 171.843199 117.833251)
		(end 171.176949 118.499501)
		(width 0.201)
		(layer "F.Cu")
		(net 79)
	)
	(segment
		(start 173.085001 117.557501)
		(end 172.809251 117.833251)
		(width 0.201)
		(layer "F.Cu")
		(net 79)
	)
	(segment
		(start 168.218 118.568)
		(end 170.504001 118.568001)
		(width 0.16)
		(layer "F.Cu")
		(net 79)
	)
	(segment
		(start 170.504001 118.568001)
		(end 170.572501 118.499501)
		(width 0.16)
		(layer "F.Cu")
		(net 79)
	)
	(segment
		(start 167.715001 118.065001)
		(end 168.218 118.568)
		(width 0.16)
		(layer "F.Cu")
		(net 79)
	)
	(segment
		(start 171.176949 118.499501)
		(end 170.572501 118.499501)
		(width 0.201)
		(layer "F.Cu")
		(net 79)
	)
	(segment
		(start 172.809251 117.833251)
		(end 171.843199 117.833251)
		(width 0.201)
		(layer "F.Cu")
		(net 79)
	)
	(segment
		(start 186.210001 128.500001)
		(end 186.099399 128.389399)
		(width 0.1)
		(layer "F.Cu")
		(net 80)
	)
	(segment
		(start 180.920501 119.306951)
		(end 180.920501 126.766951)
		(width 0.201)
		(layer "F.Cu")
		(net 80)
	)
	(segment
		(start 186.099399 128.389399)
		(end 186.099399 128.137978)
		(width 0.1)
		(layer "F.Cu")
		(net 80)
	)
	(segment
		(start 180.920501 126.766951)
		(end 181.952551 127.799001)
		(width 0.201)
		(layer "F.Cu")
		(net 80)
	)
	(segment
		(start 186.099399 128.137978)
		(end 185.861423 127.900001)
		(width 0.1)
		(layer "F.Cu")
		(net 80)
	)
	(segment
		(start 185.861423 127.900001)
		(end 183.446376 127.900001)
		(width 0.1)
		(layer "F.Cu")
		(net 80)
	)
	(segment
		(start 183.446376 127.900001)
		(end 183.345376 127.799001)
		(width 0.1)
		(layer "F.Cu")
		(net 80)
	)
	(segment
		(start 174.055001 117.557501)
		(end 174.330751 117.833251)
		(width 0.201)
		(layer "F.Cu")
		(net 80)
	)
	(segment
		(start 181.952551 127.799001)
		(end 183.345376 127.799001)
		(width 0.201)
		(layer "F.Cu")
		(net 80)
	)
	(segment
		(start 179.446801 117.833251)
		(end 180.920501 119.306951)
		(width 0.201)
		(layer "F.Cu")
		(net 80)
	)
	(segment
		(start 174.330751 117.833251)
		(end 179.446801 117.833251)
		(width 0.201)
		(layer "F.Cu")
		(net 80)
	)
	(segment
		(start 186.500001 128.500001)
		(end 186.210001 128.500001)
		(width 0.1)
		(layer "F.Cu")
		(net 80)
	)
	(segment
		(start 168.218 118.832002)
		(end 170.504001 118.832001)
		(width 0.16)
		(layer "F.Cu")
		(net 81)
	)
	(segment
		(start 167.715001 119.335001)
		(end 168.218 118.832002)
		(width 0.16)
		(layer "F.Cu")
		(net 81)
	)
	(segment
		(start 172.809251 118.234251)
		(end 172.009299 118.234251)
		(width 0.201)
		(layer "F.Cu")
		(net 81)
	)
	(segment
		(start 172.009299 118.234251)
		(end 171.343049 118.900501)
		(width 0.201)
		(layer "F.Cu")
		(net 81)
	)
	(segment
		(start 171.343049 118.900501)
		(end 170.572501 118.900501)
		(width 0.201)
		(layer "F.Cu")
		(net 81)
	)
	(segment
		(start 170.504001 118.832001)
		(end 170.572501 118.900501)
		(width 0.16)
		(layer "F.Cu")
		(net 81)
	)
	(segment
		(start 173.085001 118.510001)
		(end 172.809251 118.234251)
		(width 0.201)
		(layer "F.Cu")
		(net 81)
	)
	(segment
		(start 184.482001 128.100001)
		(end 184.432001 128.100001)
		(width 0.1)
		(layer "F.Cu")
		(net 82)
	)
	(segment
		(start 174.330751 118.234251)
		(end 179.280701 118.234251)
		(width 0.201)
		(layer "F.Cu")
		(net 82)
	)
	(segment
		(start 185.8994 128.220821)
		(end 185.77858 128.100001)
		(width 0.1)
		(layer "F.Cu")
		(net 82)
	)
	(segment
		(start 179.280701 118.234251)
		(end 180.519501 119.473051)
		(width 0.201)
		(layer "F.Cu")
		(net 82)
	)
	(segment
		(start 185.77858 128.100001)
		(end 185.182001 128.100001)
		(width 0.1)
		(layer "F.Cu")
		(net 82)
	)
	(segment
		(start 184.657001 128.285649)
		(end 184.657001 128.275001)
		(width 0.1)
		(layer "F.Cu")
		(net 82)
	)
	(segment
		(start 174.055001 118.510001)
		(end 174.330751 118.234251)
		(width 0.201)
		(layer "F.Cu")
		(net 82)
	)
	(segment
		(start 181.786451 128.200001)
		(end 183.346376 128.200001)
		(width 0.201)
		(layer "F.Cu")
		(net 82)
	)
	(segment
		(start 185.830002 128.500001)
		(end 185.8994 128.430604)
		(width 0.1)
		(layer "F.Cu")
		(net 82)
	)
	(segment
		(start 184.432001 128.100001)
		(end 183.446376 128.100001)
		(width 0.1)
		(layer "F.Cu")
		(net 82)
	)
	(segment
		(start 185.007001 128.275001)
		(end 185.007001 128.285649)
		(width 0.1)
		(layer "F.Cu")
		(net 82)
	)
	(segment
		(start 183.446376 128.100001)
		(end 183.346376 128.200001)
		(width 0.1)
		(layer "F.Cu")
		(net 82)
	)
	(segment
		(start 180.519501 126.933051)
		(end 181.786451 128.200001)
		(width 0.201)
		(layer "F.Cu")
		(net 82)
	)
	(segment
		(start 180.519501 119.473051)
		(end 180.519501 126.933051)
		(width 0.201)
		(layer "F.Cu")
		(net 82)
	)
	(segment
		(start 185.8994 128.430604)
		(end 185.8994 128.220821)
		(width 0.1)
		(layer "F.Cu")
		(net 82)
	)
	(segment
		(start 185.500001 128.500001)
		(end 185.830002 128.500001)
		(width 0.1)
		(layer "F.Cu")
		(net 82)
	)
	(arc
		(start 184.657001 128.275001)
		(mid 184.605745 128.151257)
		(end 184.482001 128.100001)
		(width 0.1)
		(layer "F.Cu")
		(net 82)
	)
	(arc
		(start 184.832001 128.460649)
		(mid 184.708257 128.409393)
		(end 184.657001 128.285649)
		(width 0.1)
		(layer "F.Cu")
		(net 82)
	)
	(arc
		(start 185.007001 128.285649)
		(mid 184.955745 128.409393)
		(end 184.832001 128.460649)
		(width 0.1)
		(layer "F.Cu")
		(net 82)
	)
	(arc
		(start 185.182001 128.100001)
		(mid 185.058257 128.151257)
		(end 185.007001 128.275001)
		(width 0.1)
		(layer "F.Cu")
		(net 82)
	)
	(segment
		(start 173.085001 123.970001)
		(end 172.809251 124.245751)
		(width 0.201)
		(layer "F.Cu")
		(net 83)
	)
	(segment
		(start 172.809251 124.245751)
		(end 172.029301 124.245751)
		(width 0.201)
		(layer "F.Cu")
		(net 83)
	)
	(segment
		(start 170.504001 123.648001)
		(end 170.572501 123.579501)
		(width 0.16)
		(layer "F.Cu")
		(net 83)
	)
	(segment
		(start 172.029301 124.245751)
		(end 171.363051 123.579501)
		(width 0.201)
		(layer "F.Cu")
		(net 83)
	)
	(segment
		(start 171.363051 123.579501)
		(end 170.572501 123.579501)
		(width 0.201)
		(layer "F.Cu")
		(net 83)
	)
	(segment
		(start 167.715001 123.145001)
		(end 168.218 123.648)
		(width 0.16)
		(layer "F.Cu")
		(net 83)
	)
	(segment
		(start 168.218 123.648)
		(end 170.504001 123.648001)
		(width 0.16)
		(layer "F.Cu")
		(net 83)
	)
	(segment
		(start 177.025501 125.001951)
		(end 177.025501 128.581951)
		(width 0.201)
		(layer "F.Cu")
		(net 87)
	)
	(segment
		(start 188.099398 131.137976)
		(end 187.861422 130.9)
		(width 0.1)
		(layer "F.Cu")
		(net 87)
	)
	(segment
		(start 188.099398 131.389398)
		(end 188.099398 131.137976)
		(width 0.1)
		(layer "F.Cu")
		(net 87)
	)
	(segment
		(start 179.242551 130.799001)
		(end 183.345376 130.799001)
		(width 0.201)
		(layer "F.Cu")
		(net 87)
	)
	(segment
		(start 174.330751 124.245751)
		(end 176.269301 124.245751)
		(width 0.201)
		(layer "F.Cu")
		(net 87)
	)
	(segment
		(start 183.446375 130.9)
		(end 183.345376 130.799001)
		(width 0.1)
		(layer "F.Cu")
		(net 87)
	)
	(segment
		(start 187.861422 130.9)
		(end 183.446375 130.9)
		(width 0.1)
		(layer "F.Cu")
		(net 87)
	)
	(segment
		(start 174.055001 123.970001)
		(end 174.330751 124.245751)
		(width 0.201)
		(layer "F.Cu")
		(net 87)
	)
	(segment
		(start 188.21 131.5)
		(end 188.099398 131.389398)
		(width 0.1)
		(layer "F.Cu")
		(net 87)
	)
	(segment
		(start 177.025501 128.581951)
		(end 179.242551 130.799001)
		(width 0.201)
		(layer "F.Cu")
		(net 87)
	)
	(segment
		(start 188.5 131.5)
		(end 188.21 131.5)
		(width 0.1)
		(layer "F.Cu")
		(net 87)
	)
	(segment
		(start 176.269301 124.245751)
		(end 177.025501 125.001951)
		(width 0.201)
		(layer "F.Cu")
		(net 87)
	)
	(segment
		(start 171.196951 123.980501)
		(end 170.572501 123.980501)
		(width 0.201)
		(layer "F.Cu")
		(net 88)
	)
	(segment
		(start 171.863201 124.646751)
		(end 171.196951 123.980501)
		(width 0.201)
		(layer "F.Cu")
		(net 88)
	)
	(segment
		(start 167.715001 124.415001)
		(end 168.218 123.912002)
		(width 0.16)
		(layer "F.Cu")
		(net 88)
	)
	(segment
		(start 172.809251 124.646751)
		(end 171.863201 124.646751)
		(width 0.201)
		(layer "F.Cu")
		(net 88)
	)
	(segment
		(start 168.218 123.912002)
		(end 170.504001 123.912001)
		(width 0.16)
		(layer "F.Cu")
		(net 88)
	)
	(segment
		(start 173.085001 124.922501)
		(end 172.809251 124.646751)
		(width 0.201)
		(layer "F.Cu")
		(net 88)
	)
	(segment
		(start 170.504001 123.912001)
		(end 170.572501 123.980501)
		(width 0.16)
		(layer "F.Cu")
		(net 88)
	)
	(segment
		(start 187.899398 131.22082)
		(end 187.778578 131.1)
		(width 0.1)
		(layer "F.Cu")
		(net 89)
	)
	(segment
		(start 187.5 131.5)
		(end 187.83 131.500001)
		(width 0.1)
		(layer "F.Cu")
		(net 89)
	)
	(segment
		(start 187.83 131.500001)
		(end 187.899398 131.430602)
		(width 0.1)
		(layer "F.Cu")
		(net 89)
	)
	(segment
		(start 176.103201 124.646751)
		(end 176.624501 125.168051)
		(width 0.201)
		(layer "F.Cu")
		(net 89)
	)
	(segment
		(start 186.736 131.1)
		(end 186.686 131.1)
		(width 0.1)
		(layer "F.Cu")
		(net 89)
	)
	(segment
		(start 179.076451 131.200001)
		(end 183.346376 131.200001)
		(width 0.201)
		(layer "F.Cu")
		(net 89)
	)
	(segment
		(start 174.330751 124.646751)
		(end 176.103201 124.646751)
		(width 0.201)
		(layer "F.Cu")
		(net 89)
	)
	(segment
		(start 183.446375 131.1)
		(end 183.346375 131.2)
		(width 0.1)
		(layer "F.Cu")
		(net 89)
	)
	(segment
		(start 176.624501 125.168051)
		(end 176.624501 128.748051)
		(width 0.201)
		(layer "F.Cu")
		(net 89)
	)
	(segment
		(start 186.861 131.272149)
		(end 186.861 131.225)
		(width 0.1)
		(layer "F.Cu")
		(net 89)
	)
	(segment
		(start 187.111 131.225)
		(end 187.111 131.272149)
		(width 0.1)
		(layer "F.Cu")
		(net 89)
	)
	(segment
		(start 187.778578 131.1)
		(end 187.236 131.1)
		(width 0.1)
		(layer "F.Cu")
		(net 89)
	)
	(segment
		(start 187.899398 131.430602)
		(end 187.899398 131.22082)
		(width 0.1)
		(layer "F.Cu")
		(net 89)
	)
	(segment
		(start 186.686 131.1)
		(end 183.446375 131.1)
		(width 0.1)
		(layer "F.Cu")
		(net 89)
	)
	(segment
		(start 176.624501 128.748051)
		(end 179.076451 131.200001)
		(width 0.201)
		(layer "F.Cu")
		(net 89)
	)
	(segment
		(start 174.055001 124.922501)
		(end 174.330751 124.646751)
		(width 0.201)
		(layer "F.Cu")
		(net 89)
	)
	(arc
		(start 186.861 131.225)
		(mid 186.824388 131.136612)
		(end 186.736 131.1)
		(width 0.1)
		(layer "F.Cu")
		(net 89)
	)
	(arc
		(start 187.111 131.272149)
		(mid 187.074388 131.360537)
		(end 186.986 131.397149)
		(width 0.1)
		(layer "F.Cu")
		(net 89)
	)
	(arc
		(start 186.986 131.397149)
		(mid 186.897612 131.360537)
		(end 186.861 131.272149)
		(width 0.1)
		(layer "F.Cu")
		(net 89)
	)
	(arc
		(start 187.236 131.1)
		(mid 187.147612 131.136612)
		(end 187.111 131.225)
		(width 0.1)
		(layer "F.Cu")
		(net 89)
	)
	(segment
		(start 172.778051 128.659501)
		(end 170.572501 128.659501)
		(width 0.201)
		(layer "F.Cu")
		(net 96)
	)
	(segment
		(start 170.504001 128.728001)
		(end 170.572501 128.659501)
		(width 0.16)
		(layer "F.Cu")
		(net 96)
	)
	(segment
		(start 174.030001 130.515001)
		(end 173.754251 130.239251)
		(width 0.201)
		(layer "F.Cu")
		(net 96)
	)
	(segment
		(start 168.218 128.728)
		(end 170.504001 128.728001)
		(width 0.16)
		(layer "F.Cu")
		(net 96)
	)
	(segment
		(start 173.754251 130.239251)
		(end 173.754251 129.635701)
		(width 0.201)
		(layer "F.Cu")
		(net 96)
	)
	(segment
		(start 173.754251 129.635701)
		(end 172.778051 128.659501)
		(width 0.201)
		(layer "F.Cu")
		(net 96)
	)
	(segment
		(start 167.715001 128.225001)
		(end 168.218 128.728)
		(width 0.16)
		(layer "F.Cu")
		(net 96)
	)
	(segment
		(start 186.500001 134.500001)
		(end 186.210001 134.500001)
		(width 0.1)
		(layer "F.Cu")
		(net 97)
	)
	(segment
		(start 185.063001 133.800001)
		(end 185.063001 133.785384)
		(width 0.1)
		(layer "F.Cu")
		(net 97)
	)
	(segment
		(start 183.446376 133.900001)
		(end 183.345376 133.799001)
		(width 0.1)
		(layer "F.Cu")
		(net 97)
	)
	(segment
		(start 184.863001 133.785384)
		(end 184.863001 133.800001)
		(width 0.1)
		(layer "F.Cu")
		(net 97)
	)
	(segment
		(start 186.210001 134.500001)
		(end 186.099399 134.389399)
		(width 0.1)
		(layer "F.Cu")
		(net 97)
	)
	(segment
		(start 185.861422 133.900001)
		(end 185.163001 133.900001)
		(width 0.1)
		(layer "F.Cu")
		(net 97)
	)
	(segment
		(start 184.763001 133.900001)
		(end 184.713001 133.900001)
		(width 0.1)
		(layer "F.Cu")
		(net 97)
	)
	(segment
		(start 186.099399 134.137978)
		(end 185.861422 133.900001)
		(width 0.1)
		(layer "F.Cu")
		(net 97)
	)
	(segment
		(start 173.754251 133.215701)
		(end 174.337551 133.799001)
		(width 0.201)
		(layer "F.Cu")
		(net 97)
	)
	(segment
		(start 174.337551 133.799001)
		(end 183.345376 133.799001)
		(width 0.201)
		(layer "F.Cu")
		(net 97)
	)
	(segment
		(start 173.754251 131.760751)
		(end 173.754251 133.215701)
		(width 0.201)
		(layer "F.Cu")
		(net 97)
	)
	(segment
		(start 174.030001 131.485001)
		(end 173.754251 131.760751)
		(width 0.201)
		(layer "F.Cu")
		(net 97)
	)
	(segment
		(start 184.713001 133.900001)
		(end 183.446376 133.900001)
		(width 0.1)
		(layer "F.Cu")
		(net 97)
	)
	(segment
		(start 186.099399 134.389399)
		(end 186.099399 134.137978)
		(width 0.1)
		(layer "F.Cu")
		(net 97)
	)
	(arc
		(start 184.863001 133.800001)
		(mid 184.833712 133.870712)
		(end 184.763001 133.900001)
		(width 0.1)
		(layer "F.Cu")
		(net 97)
	)
	(arc
		(start 185.063001 133.785384)
		(mid 185.033712 133.714673)
		(end 184.963001 133.685384)
		(width 0.1)
		(layer "F.Cu")
		(net 97)
	)
	(arc
		(start 185.163001 133.900001)
		(mid 185.09229 133.870712)
		(end 185.063001 133.800001)
		(width 0.1)
		(layer "F.Cu")
		(net 97)
	)
	(arc
		(start 184.963001 133.685384)
		(mid 184.89229 133.714673)
		(end 184.863001 133.785384)
		(width 0.1)
		(layer "F.Cu")
		(net 97)
	)
	(segment
		(start 173.353251 130.239251)
		(end 173.353251 129.801801)
		(width 0.201)
		(layer "F.Cu")
		(net 98)
	)
	(segment
		(start 173.353251 129.801801)
		(end 172.611951 129.060501)
		(width 0.201)
		(layer "F.Cu")
		(net 98)
	)
	(segment
		(start 170.504001 128.992001)
		(end 170.572501 129.060501)
		(width 0.16)
		(layer "F.Cu")
		(net 98)
	)
	(segment
		(start 172.611951 129.060501)
		(end 170.572501 129.060501)
		(width 0.201)
		(layer "F.Cu")
		(net 98)
	)
	(segment
		(start 168.218 128.992002)
		(end 170.504001 128.992001)
		(width 0.16)
		(layer "F.Cu")
		(net 98)
	)
	(segment
		(start 167.715001 129.495001)
		(end 168.218 128.992002)
		(width 0.16)
		(layer "F.Cu")
		(net 98)
	)
	(segment
		(start 173.077501 130.515001)
		(end 173.353251 130.239251)
		(width 0.201)
		(layer "F.Cu")
		(net 98)
	)
	(segment
		(start 163.905001 81.235001)
		(end 163.905001 80.305001)
		(width 0.1)
		(layer "F.Cu")
		(net 99)
	)
	(segment
		(start 163.905001 80.305001)
		(end 163.9 80.3)
		(width 0.1)
		(layer "F.Cu")
		(net 99)
	)
	(via
		(at 163.9 80.3)
		(size 0.45)
		(drill 0.2)
		(layers "F.Cu" "B.Cu")
		(net 99)
	)
	(segment
		(start 185.8994 134.430604)
		(end 185.8994 134.220821)
		(width 0.1)
		(layer "F.Cu")
		(net 101)
	)
	(segment
		(start 185.500001 134.500001)
		(end 185.830002 134.500001)
		(width 0.1)
		(layer "F.Cu")
		(net 101)
	)
	(segment
		(start 173.077501 131.485001)
		(end 173.353251 131.760751)
		(width 0.201)
		(layer "F.Cu")
		(net 101)
	)
	(segment
		(start 174.171451 134.200001)
		(end 183.346376 134.200001)
		(width 0.201)
		(layer "F.Cu")
		(net 101)
	)
	(segment
		(start 185.830002 134.500001)
		(end 185.8994 134.430604)
		(width 0.1)
		(layer "F.Cu")
		(net 101)
	)
	(segment
		(start 185.8994 134.220821)
		(end 185.77858 134.100001)
		(width 0.1)
		(layer "F.Cu")
		(net 101)
	)
	(segment
		(start 183.446376 134.100001)
		(end 183.346376 134.200001)
		(width 0.1)
		(layer "F.Cu")
		(net 101)
	)
	(segment
		(start 173.353251 133.381801)
		(end 174.171451 134.200001)
		(width 0.201)
		(layer "F.Cu")
		(net 101)
	)
	(segment
		(start 185.77858 134.100001)
		(end 183.446376 134.100001)
		(width 0.1)
		(layer "F.Cu")
		(net 101)
	)
	(segment
		(start 173.353251 131.760751)
		(end 173.353251 133.381801)
		(width 0.201)
		(layer "F.Cu")
		(net 101)
	)
	(segment
		(start 172.019301 126.785751)
		(end 171.353051 126.119501)
		(width 0.201)
		(layer "F.Cu")
		(net 105)
	)
	(segment
		(start 172.809251 126.785751)
		(end 172.019301 126.785751)
		(width 0.201)
		(layer "F.Cu")
		(net 105)
	)
	(segment
		(start 166.445001 125.685001)
		(end 166.948 126.188)
		(width 0.16)
		(layer "F.Cu")
		(net 105)
	)
	(segment
		(start 166.948 126.188)
		(end 170.572501 126.188001)
		(width 0.16)
		(layer "F.Cu")
		(net 105)
	)
	(segment
		(start 173.085001 126.510001)
		(end 172.809251 126.785751)
		(width 0.201)
		(layer "F.Cu")
		(net 105)
	)
	(segment
		(start 171.353051 126.119501)
		(end 170.641001 126.119501)
		(width 0.201)
		(layer "F.Cu")
		(net 105)
	)
	(segment
		(start 170.572501 126.188001)
		(end 170.641001 126.119501)
		(width 0.16)
		(layer "F.Cu")
		(net 105)
	)
	(segment
		(start 174.055001 126.510001)
		(end 174.330751 126.785751)
		(width 0.201)
		(layer "F.Cu")
		(net 107)
	)
	(segment
		(start 178.322551 131.799001)
		(end 183.345376 131.799001)
		(width 0.201)
		(layer "F.Cu")
		(net 107)
	)
	(segment
		(start 175.720501 129.196951)
		(end 178.322551 131.799001)
		(width 0.201)
		(layer "F.Cu")
		(net 107)
	)
	(segment
		(start 186.099399 132.137977)
		(end 185.861423 131.900001)
		(width 0.1)
		(layer "F.Cu")
		(net 107)
	)
	(segment
		(start 186.210001 132.500001)
		(end 186.099399 132.389398)
		(width 0.1)
		(layer "F.Cu")
		(net 107)
	)
	(segment
		(start 174.330751 126.785751)
		(end 174.914301 126.785751)
		(width 0.201)
		(layer "F.Cu")
		(net 107)
	)
	(segment
		(start 186.210001 132.500001)
		(end 186.500001 132.500001)
		(width 0.1)
		(layer "F.Cu")
		(net 107)
	)
	(segment
		(start 183.446375 131.9)
		(end 183.345376 131.799001)
		(width 0.1)
		(layer "F.Cu")
		(net 107)
	)
	(segment
		(start 186.099399 132.389398)
		(end 186.099399 132.137977)
		(width 0.1)
		(layer "F.Cu")
		(net 107)
	)
	(segment
		(start 175.720501 127.591951)
		(end 175.720501 129.196951)
		(width 0.201)
		(layer "F.Cu")
		(net 107)
	)
	(segment
		(start 185.861423 131.900001)
		(end 183.446375 131.9)
		(width 0.1)
		(layer "F.Cu")
		(net 107)
	)
	(segment
		(start 174.914301 126.785751)
		(end 175.720501 127.591951)
		(width 0.201)
		(layer "F.Cu")
		(net 107)
	)
	(segment
		(start 166.948 126.452002)
		(end 170.572501 126.452001)
		(width 0.16)
		(layer "F.Cu")
		(net 109)
	)
	(segment
		(start 173.085001 127.462501)
		(end 172.809251 127.186751)
		(width 0.201)
		(layer "F.Cu")
		(net 109)
	)
	(segment
		(start 166.445001 126.955001)
		(end 166.948 126.452002)
		(width 0.16)
		(layer "F.Cu")
		(net 109)
	)
	(segment
		(start 170.572501 126.452001)
		(end 170.641001 126.520501)
		(width 0.16)
		(layer "F.Cu")
		(net 109)
	)
	(segment
		(start 171.853201 127.186751)
		(end 171.186951 126.520501)
		(width 0.201)
		(layer "F.Cu")
		(net 109)
	)
	(segment
		(start 171.186951 126.520501)
		(end 170.641001 126.520501)
		(width 0.201)
		(layer "F.Cu")
		(net 109)
	)
	(segment
		(start 172.809251 127.186751)
		(end 171.853201 127.186751)
		(width 0.201)
		(layer "F.Cu")
		(net 109)
	)
	(segment
		(start 248.65 122.45)
		(end 248.8 122.3)
		(width 0.177)
		(layer "F.Cu")
		(net 111)
	)
	(segment
		(start 248.65 123.825)
		(end 248.65 122.45)
		(width 0.177)
		(layer "F.Cu")
		(net 111)
	)
	(via
		(at 251.65 128.6)
		(size 0.45)
		(drill 0.2)
		(layers "F.Cu" "B.Cu")
		(net 112)
	)
	(segment
		(start 251.65 128.6)
		(end 251.65 128.25)
		(width 0.177)
		(layer "B.Cu")
		(net 112)
	)
	(segment
		(start 251.65 128.25)
		(end 251.7 128.2)
		(width 0.177)
		(layer "B.Cu")
		(net 112)
	)
	(segment
		(start 218.315 158.7595)
		(end 218.55 158.5245)
		(width 0.1)
		(layer "F.Cu")
		(net 113)
	)
	(segment
		(start 247.3 142.9)
		(end 247.275 142.875)
		(width 0.1)
		(layer "F.Cu")
		(net 113)
	)
	(segment
		(start 217.1457 161.3475)
		(end 218.0525 161.3475)
		(width 0.1)
		(layer "F.Cu")
		(net 113)
	)
	(segment
		(start 218.315 158.95)
		(end 218.315 158.7595)
		(width 0.1)
		(layer "F.Cu")
		(net 113)
	)
	(segment
		(start 218.315 161.085)
		(end 218.315 158.95)
		(width 0.1)
		(layer "F.Cu")
		(net 113)
	)
	(segment
		(start 247.3 143.473)
		(end 247.3 142.9)
		(width 0.1)
		(layer "F.Cu")
		(net 113)
	)
	(segment
		(start 218.0525 161.3475)
		(end 218.315 161.085)
		(width 0.1)
		(layer "F.Cu")
		(net 113)
	)
	(via
		(at 247.275 142.875)
		(size 0.45)
		(drill 0.2)
		(layers "F.Cu" "B.Cu")
		(net 113)
	)
	(via
		(at 255.314812 142.985188)
		(size 0.45)
		(drill 0.2)
		(layers "F.Cu" "B.Cu")
		(net 113)
	)
	(via
		(at 218.55 158.5245)
		(size 0.45)
		(drill 0.2)
		(layers "F.Cu" "B.Cu")
		(net 113)
	)
	(segment
		(start 249 143.45)
		(end 248.8 143.65)
		(width 0.1)
		(layer "B.Cu")
		(net 113)
	)
	(segment
		(start 255.314812 142.985188)
		(end 254.754624 142.425)
		(width 0.1)
		(layer "B.Cu")
		(net 113)
	)
	(segment
		(start 248.8 143.65)
		(end 247.525 143.65)
		(width 0.1)
		(layer "B.Cu")
		(net 113)
	)
	(segment
		(start 248.775 142.95)
		(end 249 143.175)
		(width 0.1)
		(layer "B.Cu")
		(net 113)
	)
	(segment
		(start 254.754624 142.425)
		(end 248.9 142.425)
		(width 0.1)
		(layer "B.Cu")
		(net 113)
	)
	(segment
		(start 248.775 142.55)
		(end 248.775 142.95)
		(width 0.1)
		(layer "B.Cu")
		(net 113)
	)
	(segment
		(start 249 143.175)
		(end 249 143.45)
		(width 0.1)
		(layer "B.Cu")
		(net 113)
	)
	(segment
		(start 248.9 142.425)
		(end 248.775 142.55)
		(width 0.1)
		(layer "B.Cu")
		(net 113)
	)
	(segment
		(start 247.275 143.4)
		(end 247.275 142.875)
		(width 0.1)
		(layer "B.Cu")
		(net 113)
	)
	(segment
		(start 247.525 143.65)
		(end 247.275 143.4)
		(width 0.1)
		(layer "B.Cu")
		(net 113)
	)
	(segment
		(start 235.658632 158.65)
		(end 234.45 158.65)
		(width 0.1)
		(layer "In3.Cu")
		(net 113)
	)
	(segment
		(start 249.001474 150.8)
		(end 245.111474 154.69)
		(width 0.1)
		(layer "In3.Cu")
		(net 113)
	)
	(segment
		(start 239.618631 154.69)
		(end 235.658632 158.65)
		(width 0.1)
		(layer "In3.Cu")
		(net 113)
	)
	(segment
		(start 258.5 150.4)
		(end 258.1 150.8)
		(width 0.1)
		(layer "In3.Cu")
		(net 113)
	)
	(segment
		(start 218.05 163.75)
		(end 217.75 163.45)
		(width 0.1)
		(layer "In3.Cu")
		(net 113)
	)
	(segment
		(start 217.75 163.45)
		(end 217.75 159.3245)
		(width 0.1)
		(layer "In3.Cu")
		(net 113)
	)
	(segment
		(start 245.111474 154.69)
		(end 239.618631 154.69)
		(width 0.1)
		(layer "In3.Cu")
		(net 113)
	)
	(segment
		(start 255.314812 142.985188)
		(end 255.314812 143.014812)
		(width 0.1)
		(layer "In3.Cu")
		(net 113)
	)
	(segment
		(start 234.45 158.65)
		(end 229.35 163.75)
		(width 0.1)
		(layer "In3.Cu")
		(net 113)
	)
	(segment
		(start 255.314812 143.014812)
		(end 258.5 146.2)
		(width 0.1)
		(layer "In3.Cu")
		(net 113)
	)
	(segment
		(start 229.35 163.75)
		(end 218.05 163.75)
		(width 0.1)
		(layer "In3.Cu")
		(net 113)
	)
	(segment
		(start 217.75 159.3245)
		(end 218.55 158.5245)
		(width 0.1)
		(layer "In3.Cu")
		(net 113)
	)
	(segment
		(start 258.1 150.8)
		(end 249.001474 150.8)
		(width 0.1)
		(layer "In3.Cu")
		(net 113)
	)
	(segment
		(start 258.5 146.2)
		(end 258.5 150.4)
		(width 0.1)
		(layer "In3.Cu")
		(net 113)
	)
	(segment
		(start 174.330751 127.186751)
		(end 174.748201 127.186751)
		(width 0.201)
		(layer "F.Cu")
		(net 115)
	)
	(segment
		(start 184.588 132.1)
		(end 184.538 132.1)
		(width 0.1)
		(layer "F.Cu")
		(net 115)
	)
	(segment
		(start 178.156451 132.200001)
		(end 183.346376 132.200001)
		(width 0.201)
		(layer "F.Cu")
		(net 115)
	)
	(segment
		(start 185.500001 132.500001)
		(end 185.830002 132.500001)
		(width 0.1)
		(layer "F.Cu")
		(net 115)
	)
	(segment
		(start 174.748201 127.186751)
		(end 175.319501 127.758051)
		(width 0.201)
		(layer "F.Cu")
		(net 115)
	)
	(segment
		(start 184.538 132.1)
		(end 183.446377 132.1)
		(width 0.1)
		(layer "F.Cu")
		(net 115)
	)
	(segment
		(start 175.319501 129.363051)
		(end 178.156451 132.200001)
		(width 0.201)
		(layer "F.Cu")
		(net 115)
	)
	(segment
		(start 183.446377 132.1)
		(end 183.346376 132.200001)
		(width 0.1)
		(layer "F.Cu")
		(net 115)
	)
	(segment
		(start 185.038 132.25)
		(end 185.038 132.265688)
		(width 0.1)
		(layer "F.Cu")
		(net 115)
	)
	(segment
		(start 185.8994 132.430603)
		(end 185.8994 132.22082)
		(width 0.1)
		(layer "F.Cu")
		(net 115)
	)
	(segment
		(start 185.77858 132.1)
		(end 185.188 132.1)
		(width 0.1)
		(layer "F.Cu")
		(net 115)
	)
	(segment
		(start 174.055001 127.462501)
		(end 174.330751 127.186751)
		(width 0.201)
		(layer "F.Cu")
		(net 115)
	)
	(segment
		(start 184.738 132.265688)
		(end 184.738 132.25)
		(width 0.1)
		(layer "F.Cu")
		(net 115)
	)
	(segment
		(start 175.319501 127.758051)
		(end 175.319501 129.363051)
		(width 0.201)
		(layer "F.Cu")
		(net 115)
	)
	(segment
		(start 185.8994 132.22082)
		(end 185.77858 132.1)
		(width 0.1)
		(layer "F.Cu")
		(net 115)
	)
	(segment
		(start 185.830002 132.500001)
		(end 185.8994 132.430603)
		(width 0.1)
		(layer "F.Cu")
		(net 115)
	)
	(arc
		(start 185.038 132.265688)
		(mid 184.994066 132.371754)
		(end 184.888 132.415688)
		(width 0.1)
		(layer "F.Cu")
		(net 115)
	)
	(arc
		(start 184.738 132.25)
		(mid 184.694066 132.143934)
		(end 184.588 132.1)
		(width 0.1)
		(layer "F.Cu")
		(net 115)
	)
	(arc
		(start 184.888 132.415688)
		(mid 184.781934 132.371754)
		(end 184.738 132.265688)
		(width 0.1)
		(layer "F.Cu")
		(net 115)
	)
	(arc
		(start 185.188 132.1)
		(mid 185.081934 132.143934)
		(end 185.038 132.25)
		(width 0.1)
		(layer "F.Cu")
		(net 115)
	)
	(segment
		(start 171.378932 121.039501)
		(end 170.641001 121.039501)
		(width 0.201)
		(layer "F.Cu")
		(net 119)
	)
	(segment
		(start 170.572501 121.108001)
		(end 170.641001 121.039501)
		(width 0.16)
		(layer "F.Cu")
		(net 119)
	)
	(segment
		(start 172.045182 121.705751)
		(end 171.378932 121.039501)
		(width 0.201)
		(layer "F.Cu")
		(net 119)
	)
	(segment
		(start 173.085001 121.430001)
		(end 172.809251 121.705751)
		(width 0.201)
		(layer "F.Cu")
		(net 119)
	)
	(segment
		(start 172.809251 121.705751)
		(end 172.045182 121.705751)
		(width 0.201)
		(layer "F.Cu")
		(net 119)
	)
	(segment
		(start 166.948 121.108)
		(end 170.572501 121.108001)
		(width 0.16)
		(layer "F.Cu")
		(net 119)
	)
	(segment
		(start 166.445001 120.605001)
		(end 166.948 121.108)
		(width 0.16)
		(layer "F.Cu")
		(net 119)
	)
	(segment
		(start 180.142551 129.799001)
		(end 183.345376 129.799001)
		(width 0.201)
		(layer "F.Cu")
		(net 122)
	)
	(segment
		(start 186.500001 130.500001)
		(end 186.210001 130.500001)
		(width 0.1)
		(layer "F.Cu")
		(net 122)
	)
	(segment
		(start 174.055001 121.430001)
		(end 174.330751 121.705751)
		(width 0.201)
		(layer "F.Cu")
		(net 122)
	)
	(segment
		(start 186.210001 130.500001)
		(end 186.099399 130.389399)
		(width 0.1)
		(layer "F.Cu")
		(net 122)
	)
	(segment
		(start 178.325501 122.841951)
		(end 178.325501 127.981951)
		(width 0.201)
		(layer "F.Cu")
		(net 122)
	)
	(segment
		(start 186.099399 130.389399)
		(end 186.099399 130.137978)
		(width 0.1)
		(layer "F.Cu")
		(net 122)
	)
	(segment
		(start 183.446376 129.900001)
		(end 183.345376 129.799001)
		(width 0.1)
		(layer "F.Cu")
		(net 122)
	)
	(segment
		(start 186.099399 130.137978)
		(end 185.861423 129.900001)
		(width 0.1)
		(layer "F.Cu")
		(net 122)
	)
	(segment
		(start 174.330751 121.705751)
		(end 177.189301 121.705751)
		(width 0.201)
		(layer "F.Cu")
		(net 122)
	)
	(segment
		(start 185.861423 129.900001)
		(end 183.446376 129.900001)
		(width 0.1)
		(layer "F.Cu")
		(net 122)
	)
	(segment
		(start 177.189301 121.705751)
		(end 178.325501 122.841951)
		(width 0.201)
		(layer "F.Cu")
		(net 122)
	)
	(segment
		(start 178.325501 127.981951)
		(end 180.142551 129.799001)
		(width 0.201)
		(layer "F.Cu")
		(net 122)
	)
	(segment
		(start 172.809251 122.106751)
		(end 171.879082 122.106751)
		(width 0.201)
		(layer "F.Cu")
		(net 123)
	)
	(segment
		(start 170.572501 121.372001)
		(end 170.641001 121.440501)
		(width 0.16)
		(layer "F.Cu")
		(net 123)
	)
	(segment
		(start 171.212832 121.440501)
		(end 170.641001 121.440501)
		(width 0.201)
		(layer "F.Cu")
		(net 123)
	)
	(segment
		(start 173.085001 122.382501)
		(end 172.809251 122.106751)
		(width 0.201)
		(layer "F.Cu")
		(net 123)
	)
	(segment
		(start 166.445001 121.875001)
		(end 166.948 121.372002)
		(width 0.16)
		(layer "F.Cu")
		(net 123)
	)
	(segment
		(start 171.879082 122.106751)
		(end 171.212832 121.440501)
		(width 0.201)
		(layer "F.Cu")
		(net 123)
	)
	(segment
		(start 166.948 121.372002)
		(end 170.572501 121.372001)
		(width 0.16)
		(layer "F.Cu")
		(net 123)
	)
	(segment
		(start 174.330751 122.106751)
		(end 177.023201 122.106751)
		(width 0.201)
		(layer "F.Cu")
		(net 124)
	)
	(segment
		(start 185.500001 130.500001)
		(end 185.830002 130.500001)
		(width 0.1)
		(layer "F.Cu")
		(net 124)
	)
	(segment
		(start 179.976451 130.200001)
		(end 183.346376 130.200001)
		(width 0.201)
		(layer "F.Cu")
		(net 124)
	)
	(segment
		(start 185.77858 130.100001)
		(end 185.202001 130.100001)
		(width 0.1)
		(layer "F.Cu")
		(net 124)
	)
	(segment
		(start 185.8994 130.430604)
		(end 185.8994 130.220821)
		(width 0.1)
		(layer "F.Cu")
		(net 124)
	)
	(segment
		(start 177.023201 122.106751)
		(end 177.924501 123.008051)
		(width 0.201)
		(layer "F.Cu")
		(net 124)
	)
	(segment
		(start 185.102001 130.200001)
		(end 185.102001 130.225768)
		(width 0.1)
		(layer "F.Cu")
		(net 124)
	)
	(segment
		(start 174.055001 122.382501)
		(end 174.330751 122.106751)
		(width 0.201)
		(layer "F.Cu")
		(net 124)
	)
	(segment
		(start 185.830002 130.500001)
		(end 185.8994 130.430604)
		(width 0.1)
		(layer "F.Cu")
		(net 124)
	)
	(segment
		(start 183.446376 130.100001)
		(end 183.346376 130.200001)
		(width 0.1)
		(layer "F.Cu")
		(net 124)
	)
	(segment
		(start 185.8994 130.220821)
		(end 185.77858 130.100001)
		(width 0.1)
		(layer "F.Cu")
		(net 124)
	)
	(segment
		(start 183.446376 130.100001)
		(end 184.802001 130.100001)
		(width 0.1)
		(layer "F.Cu")
		(net 124)
	)
	(segment
		(start 184.902001 130.225768)
		(end 184.902001 130.200001)
		(width 0.1)
		(layer "F.Cu")
		(net 124)
	)
	(segment
		(start 177.924501 123.008051)
		(end 177.924501 128.148051)
		(width 0.201)
		(layer "F.Cu")
		(net 124)
	)
	(segment
		(start 177.924501 128.148051)
		(end 179.976451 130.200001)
		(width 0.201)
		(layer "F.Cu")
		(net 124)
	)
	(arc
		(start 185.202001 130.100001)
		(mid 185.13129 130.12929)
		(end 185.102001 130.200001)
		(width 0.1)
		(layer "F.Cu")
		(net 124)
	)
	(arc
		(start 185.002001 130.325768)
		(mid 184.93129 130.296479)
		(end 184.902001 130.225768)
		(width 0.1)
		(layer "F.Cu")
		(net 124)
	)
	(arc
		(start 184.902001 130.200001)
		(mid 184.872712 130.12929)
		(end 184.802001 130.100001)
		(width 0.1)
		(layer "F.Cu")
		(net 124)
	)
	(arc
		(start 185.102001 130.225768)
		(mid 185.072712 130.296479)
		(end 185.002001 130.325768)
		(width 0.1)
		(layer "F.Cu")
		(net 124)
	)
	(segment
		(start 228.15 166.25)
		(end 228.1 166.3)
		(width 0.1)
		(layer "F.Cu")
		(net 143)
	)
	(segment
		(start 228.15 165.36)
		(end 228.15 166.25)
		(width 0.1)
		(layer "F.Cu")
		(net 143)
	)
	(via
		(at 228.1 166.3)
		(size 0.45)
		(drill 0.2)
		(layers "F.Cu" "B.Cu")
		(net 143)
	)
	(segment
		(start 228.1 165.885)
		(end 228.1 166.3)
		(width 0.1)
		(layer "B.Cu")
		(net 143)
	)
	(segment
		(start 158.825001 130.765001)
		(end 159.56 131.5)
		(width 0.256)
		(layer "F.Cu")
		(net 152)
	)
	(segment
		(start 160.630002 131.5)
		(end 161.365001 130.765001)
		(width 0.256)
		(layer "F.Cu")
		(net 152)
	)
	(segment
		(start 161.365001 130.765001)
		(end 162.635001 129.495001)
		(width 0.256)
		(layer "F.Cu")
		(net 152)
	)
	(segment
		(start 158.825001 130.765001)
		(end 160.095001 129.495001)
		(width 0.256)
		(layer "F.Cu")
		(net 152)
	)
	(segment
		(start 159.56 131.5)
		(end 160.630002 131.5)
		(width 0.256)
		(layer "F.Cu")
		(net 152)
	)
	(segment
		(start 171.429201 79.900001)
		(end 172.66 81.1308)
		(width 0.1)
		(layer "F.Cu")
		(net 153)
	)
	(segment
		(start 161.365001 81.235001)
		(end 162.700001 79.900001)
		(width 0.1)
		(layer "F.Cu")
		(net 153)
	)
	(segment
		(start 162.700001 79.900001)
		(end 171.429201 79.900001)
		(width 0.1)
		(layer "F.Cu")
		(net 153)
	)
	(segment
		(start 151.25 78.975)
		(end 151.25 121.75)
		(width 0.1)
		(layer "F.Cu")
		(net 161)
	)
	(segment
		(start 151.35 78.875)
		(end 151.25 78.975)
		(width 0.1)
		(layer "F.Cu")
		(net 161)
	)
	(segment
		(start 163.3 123.4)
		(end 163.3 122.480002)
		(width 0.1)
		(layer "F.Cu")
		(net 161)
	)
	(segment
		(start 163.3 122.480002)
		(end 163.905001 121.875001)
		(width 0.1)
		(layer "F.Cu")
		(net 161)
	)
	(segment
		(start 234.375 125.225)
		(end 234.7 125.55)
		(width 0.1)
		(layer "F.Cu")
		(net 161)
	)
	(segment
		(start 234.7 130.535)
		(end 235.715 131.55)
		(width 0.1)
		(layer "F.Cu")
		(net 161)
	)
	(segment
		(start 162.8 123.9)
		(end 163.3 123.4)
		(width 0.1)
		(layer "F.Cu")
		(net 161)
	)
	(segment
		(start 234.7 125.55)
		(end 234.7 130.535)
		(width 0.1)
		(layer "F.Cu")
		(net 161)
	)
	(segment
		(start 194.5 120.5)
		(end 194 120)
		(width 0.256)
		(layer "F.Cu")
		(net 161)
	)
	(segment
		(start 151.25 121.75)
		(end 153.4 123.9)
		(width 0.1)
		(layer "F.Cu")
		(net 161)
	)
	(segment
		(start 153.4 123.9)
		(end 162.8 123.9)
		(width 0.1)
		(layer "F.Cu")
		(net 161)
	)
	(via
		(at 151.35 78.875)
		(size 0.45)
		(drill 0.2)
		(layers "F.Cu" "B.Cu")
		(net 161)
	)
	(via
		(at 234.375 125.225)
		(size 0.45)
		(drill 0.2)
		(layers "F.Cu" "B.Cu")
		(net 161)
	)
	(via
		(at 192.9 76)
		(size 0.45)
		(drill 0.2)
		(layers "F.Cu" "B.Cu")
		(net 161)
	)
	(via
		(at 194 120)
		(size 0.45)
		(drill 0.2)
		(layers "F.Cu" "B.Cu")
		(net 161)
	)
	(segment
		(start 192 76)
		(end 191 75)
		(width 0.1)
		(layer "B.Cu")
		(net 161)
	)
	(segment
		(start 192.9 76)
		(end 192 76)
		(width 0.1)
		(layer "B.Cu")
		(net 161)
	)
	(segment
		(start 191 75)
		(end 191 74.385)
		(width 0.1)
		(layer "B.Cu")
		(net 161)
	)
	(segment
		(start 191 73.615)
		(end 191 74.385)
		(width 0.1)
		(layer "B.Cu")
		(net 161)
	)
	(segment
		(start 194.2 85.665684)
		(end 194.2 77.3)
		(width 0.1)
		(layer "In3.Cu")
		(net 161)
	)
	(segment
		(start 193.8 119.8)
		(end 193.8 119.4)
		(width 0.1)
		(layer "In3.Cu")
		(net 161)
	)
	(segment
		(start 193.4 119)
		(end 193.4 86.465684)
		(width 0.1)
		(layer "In3.Cu")
		(net 161)
	)
	(segment
		(start 194.2 77.3)
		(end 192.9 76)
		(width 0.1)
		(layer "In3.Cu")
		(net 161)
	)
	(segment
		(start 193.8 119.4)
		(end 193.4 119)
		(width 0.1)
		(layer "In3.Cu")
		(net 161)
	)
	(segment
		(start 193.4 86.465684)
		(end 194.2 85.665684)
		(width 0.1)
		(layer "In3.Cu")
		(net 161)
	)
	(segment
		(start 194 120)
		(end 193.8 119.8)
		(width 0.1)
		(layer "In3.Cu")
		(net 161)
	)
	(segment
		(start 209.3 89.6)
		(end 205.2 85.5)
		(width 0.1)
		(layer "In7.Cu")
		(net 161)
	)
	(segment
		(start 200.5 80.8)
		(end 196.8 77.1)
		(width 0.1)
		(layer "In7.Cu")
		(net 161)
	)
	(segment
		(start 187 75.3)
		(end 185.4 76.9)
		(width 0.1)
		(layer "In7.Cu")
		(net 161)
	)
	(segment
		(start 191.6 76)
		(end 191.3 76.3)
		(width 0.1)
		(layer "In7.Cu")
		(net 161)
	)
	(segment
		(start 211.4 93.9)
		(end 209.3 91.8)
		(width 0.1)
		(layer "In7.Cu")
		(net 161)
	)
	(segment
		(start 192.9 76)
		(end 191.6 76)
		(width 0.1)
		(layer "In7.Cu")
		(net 161)
	)
	(segment
		(start 201.8 85.5)
		(end 200.5 84.2)
		(width 0.1)
		(layer "In7.Cu")
		(net 161)
	)
	(segment
		(start 163.025 80.7)
		(end 161.2 78.875)
		(width 0.1)
		(layer "In7.Cu")
		(net 161)
	)
	(segment
		(start 217 107.3)
		(end 211.4 101.7)
		(width 0.1)
		(layer "In7.Cu")
		(net 161)
	)
	(segment
		(start 237.8 123.9)
		(end 237.8 111.7)
		(width 0.1)
		(layer "In7.Cu")
		(net 161)
	)
	(segment
		(start 211.4 101.7)
		(end 211.4 93.9)
		(width 0.1)
		(layer "In7.Cu")
		(net 161)
	)
	(segment
		(start 170.175 76.1)
		(end 165.575 80.7)
		(width 0.1)
		(layer "In7.Cu")
		(net 161)
	)
	(segment
		(start 194 77.1)
		(end 192.9 76)
		(width 0.1)
		(layer "In7.Cu")
		(net 161)
	)
	(segment
		(start 185.4 76.9)
		(end 184.6 76.9)
		(width 0.1)
		(layer "In7.Cu")
		(net 161)
	)
	(segment
		(start 233.4 107.3)
		(end 217 107.3)
		(width 0.1)
		(layer "In7.Cu")
		(net 161)
	)
	(segment
		(start 189.8 75.3)
		(end 187 75.3)
		(width 0.1)
		(layer "In7.Cu")
		(net 161)
	)
	(segment
		(start 191.3 76.3)
		(end 190.8 76.3)
		(width 0.1)
		(layer "In7.Cu")
		(net 161)
	)
	(segment
		(start 196.8 77.1)
		(end 194 77.1)
		(width 0.1)
		(layer "In7.Cu")
		(net 161)
	)
	(segment
		(start 161.2 78.875)
		(end 151.35 78.875)
		(width 0.1)
		(layer "In7.Cu")
		(net 161)
	)
	(segment
		(start 209.3 91.8)
		(end 209.3 89.6)
		(width 0.1)
		(layer "In7.Cu")
		(net 161)
	)
	(segment
		(start 237.8 111.7)
		(end 233.4 107.3)
		(width 0.1)
		(layer "In7.Cu")
		(net 161)
	)
	(segment
		(start 236.475 125.225)
		(end 237.8 123.9)
		(width 0.1)
		(layer "In7.Cu")
		(net 161)
	)
	(segment
		(start 234.375 125.225)
		(end 236.475 125.225)
		(width 0.1)
		(layer "In7.Cu")
		(net 161)
	)
	(segment
		(start 184.6 76.9)
		(end 183.8 76.1)
		(width 0.1)
		(layer "In7.Cu")
		(net 161)
	)
	(segment
		(start 165.575 80.7)
		(end 163.025 80.7)
		(width 0.1)
		(layer "In7.Cu")
		(net 161)
	)
	(segment
		(start 200.5 84.2)
		(end 200.5 80.8)
		(width 0.1)
		(layer "In7.Cu")
		(net 161)
	)
	(segment
		(start 183.8 76.1)
		(end 170.175 76.1)
		(width 0.1)
		(layer "In7.Cu")
		(net 161)
	)
	(segment
		(start 190.8 76.3)
		(end 189.8 75.3)
		(width 0.1)
		(layer "In7.Cu")
		(net 161)
	)
	(segment
		(start 205.2 85.5)
		(end 201.8 85.5)
		(width 0.1)
		(layer "In7.Cu")
		(net 161)
	)
	(segment
		(start 194.5 119.5)
		(end 194 119)
		(width 0.256)
		(layer "F.Cu")
		(net 165)
	)
	(segment
		(start 163.4 113.8)
		(end 163.1 113.5)
		(width 0.1)
		(layer "F.Cu")
		(net 165)
	)
	(segment
		(start 234.375 124.425)
		(end 233.9 124.9)
		(width 0.1)
		(layer "F.Cu")
		(net 165)
	)
	(segment
		(start 163.1 113.5)
		(end 153.45 113.5)
		(width 0.1)
		(layer "F.Cu")
		(net 165)
	)
	(segment
		(start 234.4 126)
		(end 234.4 131.235)
		(width 0.1)
		(layer "F.Cu")
		(net 165)
	)
	(segment
		(start 234.4 131.235)
		(end 235.715 132.55)
		(width 0.1)
		(layer "F.Cu")
		(net 165)
	)
	(segment
		(start 233.9 124.9)
		(end 233.9 125.5)
		(width 0.1)
		(layer "F.Cu")
		(net 165)
	)
	(segment
		(start 153.45 113.5)
		(end 152.85 112.9)
		(width 0.1)
		(layer "F.Cu")
		(net 165)
	)
	(segment
		(start 163.905001 116.795001)
		(end 163.4 116.29)
		(width 0.1)
		(layer "F.Cu")
		(net 165)
	)
	(segment
		(start 233.9 125.5)
		(end 234.4 126)
		(width 0.1)
		(layer "F.Cu")
		(net 165)
	)
	(segment
		(start 152.85 112.9)
		(end 152.85 78.45)
		(width 0.1)
		(layer "F.Cu")
		(net 165)
	)
	(segment
		(start 163.4 116.29)
		(end 163.4 113.8)
		(width 0.1)
		(layer "F.Cu")
		(net 165)
	)
	(via
		(at 152.85 78.45)
		(size 0.45)
		(drill 0.2)
		(layers "F.Cu" "B.Cu")
		(net 165)
	)
	(via
		(at 191 75.9)
		(size 0.45)
		(drill 0.2)
		(layers "F.Cu" "B.Cu")
		(net 165)
	)
	(via
		(at 194 119)
		(size 0.45)
		(drill 0.2)
		(layers "F.Cu" "B.Cu")
		(net 165)
	)
	(via
		(at 234.375 124.425)
		(size 0.45)
		(drill 0.2)
		(layers "F.Cu" "B.Cu")
		(net 165)
	)
	(segment
		(start 190.5 74.385)
		(end 190.5 75.4)
		(width 0.1)
		(layer "B.Cu")
		(net 165)
	)
	(segment
		(start 190.5 73.615)
		(end 190.5 74.385)
		(width 0.1)
		(layer "B.Cu")
		(net 165)
	)
	(segment
		(start 190.5 75.4)
		(end 191 75.9)
		(width 0.1)
		(layer "B.Cu")
		(net 165)
	)
	(segment
		(start 194.4 76.7)
		(end 193.2 75.5)
		(width 0.1)
		(layer "In3.Cu")
		(net 165)
	)
	(segment
		(start 193.6 86.548526)
		(end 194.4 85.748526)
		(width 0.1)
		(layer "In3.Cu")
		(net 165)
	)
	(segment
		(start 193.2 75.5)
		(end 191.4 75.5)
		(width 0.1)
		(layer "In3.Cu")
		(net 165)
	)
	(segment
		(start 193.6 118.6)
		(end 193.6 86.548526)
		(width 0.1)
		(layer "In3.Cu")
		(net 165)
	)
	(segment
		(start 191.4 75.5)
		(end 191 75.9)
		(width 0.1)
		(layer "In3.Cu")
		(net 165)
	)
	(segment
		(start 194 119)
		(end 193.6 118.6)
		(width 0.1)
		(layer "In3.Cu")
		(net 165)
	)
	(segment
		(start 194.4 85.748526)
		(end 194.4 76.7)
		(width 0.1)
		(layer "In3.Cu")
		(net 165)
	)
	(segment
		(start 184.8 76.6)
		(end 184 75.8)
		(width 0.1)
		(layer "In7.Cu")
		(net 165)
	)
	(segment
		(start 233.8 125)
		(end 233.8 125.5)
		(width 0.1)
		(layer "In7.Cu")
		(net 165)
	)
	(segment
		(start 169.925 75.8)
		(end 165.925 79.8)
		(width 0.1)
		(layer "In7.Cu")
		(net 165)
	)
	(segment
		(start 209.5 91.6)
		(end 209.5 89.4)
		(width 0.1)
		(layer "In7.Cu")
		(net 165)
	)
	(segment
		(start 193.8 76.3)
		(end 193.8 75.7)
		(width 0.1)
		(layer "In7.Cu")
		(net 165)
	)
	(segment
		(start 238 124.1)
		(end 238 111.3)
		(width 0.1)
		(layer "In7.Cu")
		(net 165)
	)
	(segment
		(start 202 85.3)
		(end 200.7 84)
		(width 0.1)
		(layer "In7.Cu")
		(net 165)
	)
	(segment
		(start 162.925 79.8)
		(end 161.575 78.45)
		(width 0.1)
		(layer "In7.Cu")
		(net 165)
	)
	(segment
		(start 196.9 76.8)
		(end 194.3 76.8)
		(width 0.1)
		(layer "In7.Cu")
		(net 165)
	)
	(segment
		(start 234.375 124.425)
		(end 233.8 125)
		(width 0.1)
		(layer "In7.Cu")
		(net 165)
	)
	(segment
		(start 186.9 74.9)
		(end 185.2 76.6)
		(width 0.1)
		(layer "In7.Cu")
		(net 165)
	)
	(segment
		(start 200.7 80.6)
		(end 196.9 76.8)
		(width 0.1)
		(layer "In7.Cu")
		(net 165)
	)
	(segment
		(start 205.4 85.3)
		(end 202 85.3)
		(width 0.1)
		(layer "In7.Cu")
		(net 165)
	)
	(segment
		(start 190 74.9)
		(end 186.9 74.9)
		(width 0.1)
		(layer "In7.Cu")
		(net 165)
	)
	(segment
		(start 185.2 76.6)
		(end 184.8 76.6)
		(width 0.1)
		(layer "In7.Cu")
		(net 165)
	)
	(segment
		(start 191.6 75.3)
		(end 191 75.9)
		(width 0.1)
		(layer "In7.Cu")
		(net 165)
	)
	(segment
		(start 209.5 89.4)
		(end 205.4 85.3)
		(width 0.1)
		(layer "In7.Cu")
		(net 165)
	)
	(segment
		(start 184 75.8)
		(end 169.925 75.8)
		(width 0.1)
		(layer "In7.Cu")
		(net 165)
	)
	(segment
		(start 165.925 79.8)
		(end 162.925 79.8)
		(width 0.1)
		(layer "In7.Cu")
		(net 165)
	)
	(segment
		(start 211.6 93.7)
		(end 209.5 91.6)
		(width 0.1)
		(layer "In7.Cu")
		(net 165)
	)
	(segment
		(start 200.7 84)
		(end 200.7 80.6)
		(width 0.1)
		(layer "In7.Cu")
		(net 165)
	)
	(segment
		(start 234 125.7)
		(end 236.4 125.7)
		(width 0.1)
		(layer "In7.Cu")
		(net 165)
	)
	(segment
		(start 233.6 106.9)
		(end 217 106.9)
		(width 0.1)
		(layer "In7.Cu")
		(net 165)
	)
	(segment
		(start 238 111.3)
		(end 233.6 106.9)
		(width 0.1)
		(layer "In7.Cu")
		(net 165)
	)
	(segment
		(start 161.575 78.45)
		(end 152.85 78.45)
		(width 0.1)
		(layer "In7.Cu")
		(net 165)
	)
	(segment
		(start 193.8 75.7)
		(end 193.4 75.3)
		(width 0.1)
		(layer "In7.Cu")
		(net 165)
	)
	(segment
		(start 191 75.9)
		(end 190 74.9)
		(width 0.1)
		(layer "In7.Cu")
		(net 165)
	)
	(segment
		(start 193.4 75.3)
		(end 191.6 75.3)
		(width 0.1)
		(layer "In7.Cu")
		(net 165)
	)
	(segment
		(start 217 106.9)
		(end 211.6 101.5)
		(width 0.1)
		(layer "In7.Cu")
		(net 165)
	)
	(segment
		(start 233.8 125.5)
		(end 234 125.7)
		(width 0.1)
		(layer "In7.Cu")
		(net 165)
	)
	(segment
		(start 211.6 101.5)
		(end 211.6 93.7)
		(width 0.1)
		(layer "In7.Cu")
		(net 165)
	)
	(segment
		(start 236.4 125.7)
		(end 238 124.1)
		(width 0.1)
		(layer "In7.Cu")
		(net 165)
	)
	(segment
		(start 194.3 76.8)
		(end 193.8 76.3)
		(width 0.1)
		(layer "In7.Cu")
		(net 165)
	)
	(segment
		(start 153.5 123.7)
		(end 161.5 123.7)
		(width 0.1)
		(layer "F.Cu")
		(net 190)
	)
	(segment
		(start 151.775 121.975)
		(end 153.5 123.7)
		(width 0.1)
		(layer "F.Cu")
		(net 190)
	)
	(segment
		(start 151.775 121.975)
		(end 151.775 79.975)
		(width 0.1)
		(layer "F.Cu")
		(net 190)
	)
	(segment
		(start 161.9 123.3)
		(end 161.5 123.7)
		(width 0.1)
		(layer "F.Cu")
		(net 190)
	)
	(segment
		(start 162.2 121.1)
		(end 161.9 121.4)
		(width 0.1)
		(layer "F.Cu")
		(net 190)
	)
	(segment
		(start 235.3 124.65)
		(end 235.3 129.135)
		(width 0.1)
		(layer "F.Cu")
		(net 190)
	)
	(segment
		(start 234.925 124.275)
		(end 235.3 124.65)
		(width 0.1)
		(layer "F.Cu")
		(net 190)
	)
	(segment
		(start 164.2 121.1)
		(end 162.2 121.1)
		(width 0.1)
		(layer "F.Cu")
		(net 190)
	)
	(segment
		(start 194.5 121.5)
		(end 194 121)
		(width 0.256)
		(layer "F.Cu")
		(net 190)
	)
	(segment
		(start 164.5 120.8)
		(end 164.2 121.1)
		(width 0.1)
		(layer "F.Cu")
		(net 190)
	)
	(segment
		(start 161.9 121.4)
		(end 161.9 123.3)
		(width 0.1)
		(layer "F.Cu")
		(net 190)
	)
	(segment
		(start 235.3 129.135)
		(end 235.715 129.55)
		(width 0.1)
		(layer "F.Cu")
		(net 190)
	)
	(segment
		(start 164.5 119.93)
		(end 164.5 120.8)
		(width 0.1)
		(layer "F.Cu")
		(net 190)
	)
	(segment
		(start 163.905001 119.335001)
		(end 164.5 119.93)
		(width 0.1)
		(layer "F.Cu")
		(net 190)
	)
	(segment
		(start 151.775 79.975)
		(end 152 79.75)
		(width 0.1)
		(layer "F.Cu")
		(net 190)
	)
	(via
		(at 194 121)
		(size 0.45)
		(drill 0.2)
		(layers "F.Cu" "B.Cu")
		(net 190)
	)
	(via
		(at 152 79.75)
		(size 0.45)
		(drill 0.2)
		(layers "F.Cu" "B.Cu")
		(net 190)
	)
	(via
		(at 189.000001 76.400001)
		(size 0.45)
		(drill 0.2)
		(layers "F.Cu" "B.Cu")
		(net 190)
	)
	(via
		(at 234.925 124.275)
		(size 0.45)
		(drill 0.2)
		(layers "F.Cu" "B.Cu")
		(net 190)
	)
	(segment
		(start 189.5 75.9)
		(end 189 76.4)
		(width 0.1)
		(layer "B.Cu")
		(net 190)
	)
	(segment
		(start 189.5 74.385)
		(end 189.5 75.9)
		(width 0.1)
		(layer "B.Cu")
		(net 190)
	)
	(segment
		(start 189.5 73.615)
		(end 189.5 74.385)
		(width 0.1)
		(layer "B.Cu")
		(net 190)
	)
	(segment
		(start 193.2 86.382842)
		(end 194 85.582842)
		(width 0.1)
		(layer "In3.Cu")
		(net 190)
	)
	(segment
		(start 193.2 119.1)
		(end 193.2 86.382842)
		(width 0.1)
		(layer "In3.Cu")
		(net 190)
	)
	(segment
		(start 193.017158 76.4)
		(end 189 76.4)
		(width 0.1)
		(layer "In3.Cu")
		(net 190)
	)
	(segment
		(start 193.6 119.5)
		(end 193.2 119.1)
		(width 0.1)
		(layer "In3.Cu")
		(net 190)
	)
	(segment
		(start 194 77.382842)
		(end 193.017158 76.4)
		(width 0.1)
		(layer "In3.Cu")
		(net 190)
	)
	(segment
		(start 194 121)
		(end 193.6 120.6)
		(width 0.1)
		(layer "In3.Cu")
		(net 190)
	)
	(segment
		(start 193.6 120.6)
		(end 193.6 119.5)
		(width 0.1)
		(layer "In3.Cu")
		(net 190)
	)
	(segment
		(start 194 85.582842)
		(end 194 77.382842)
		(width 0.1)
		(layer "In3.Cu")
		(net 190)
	)
	(segment
		(start 200 84.5)
		(end 200 81.1)
		(width 0.1)
		(layer "In7.Cu")
		(net 190)
	)
	(segment
		(start 184.2 77.5)
		(end 187.4 77.5)
		(width 0.1)
		(layer "In7.Cu")
		(net 190)
	)
	(segment
		(start 165.875 81.225)
		(end 162.125 81.225)
		(width 0.1)
		(layer "In7.Cu")
		(net 190)
	)
	(segment
		(start 189 76.9)
		(end 189 76.4)
		(width 0.1)
		(layer "In7.Cu")
		(net 190)
	)
	(segment
		(start 162.125 81.225)
		(end 160.65 79.75)
		(width 0.1)
		(layer "In7.Cu")
		(net 190)
	)
	(segment
		(start 208.9 90)
		(end 204.8 85.9)
		(width 0.1)
		(layer "In7.Cu")
		(net 190)
	)
	(segment
		(start 236.625 124.275)
		(end 237.4 123.5)
		(width 0.1)
		(layer "In7.Cu")
		(net 190)
	)
	(segment
		(start 211 94.3)
		(end 208.9 92.2)
		(width 0.1)
		(layer "In7.Cu")
		(net 190)
	)
	(segment
		(start 237.4 123.5)
		(end 237.4 112.3)
		(width 0.1)
		(layer "In7.Cu")
		(net 190)
	)
	(segment
		(start 201.4 85.9)
		(end 200 84.5)
		(width 0.1)
		(layer "In7.Cu")
		(net 190)
	)
	(segment
		(start 200 81.1)
		(end 196.6 77.7)
		(width 0.1)
		(layer "In7.Cu")
		(net 190)
	)
	(segment
		(start 189.8 77.7)
		(end 189 76.9)
		(width 0.1)
		(layer "In7.Cu")
		(net 190)
	)
	(segment
		(start 183.4 76.7)
		(end 184.2 77.5)
		(width 0.1)
		(layer "In7.Cu")
		(net 190)
	)
	(segment
		(start 187.4 77.5)
		(end 188.499999 76.400001)
		(width 0.1)
		(layer "In7.Cu")
		(net 190)
	)
	(segment
		(start 208.9 92.2)
		(end 208.9 90)
		(width 0.1)
		(layer "In7.Cu")
		(net 190)
	)
	(segment
		(start 234.925 124.275)
		(end 236.625 124.275)
		(width 0.1)
		(layer "In7.Cu")
		(net 190)
	)
	(segment
		(start 160.65 79.75)
		(end 152 79.75)
		(width 0.1)
		(layer "In7.Cu")
		(net 190)
	)
	(segment
		(start 170.4 76.7)
		(end 183.4 76.7)
		(width 0.1)
		(layer "In7.Cu")
		(net 190)
	)
	(segment
		(start 217 108.1)
		(end 211 102.1)
		(width 0.1)
		(layer "In7.Cu")
		(net 190)
	)
	(segment
		(start 233.2 108.1)
		(end 217 108.1)
		(width 0.1)
		(layer "In7.Cu")
		(net 190)
	)
	(segment
		(start 196.6 77.7)
		(end 189.8 77.7)
		(width 0.1)
		(layer "In7.Cu")
		(net 190)
	)
	(segment
		(start 211 102.1)
		(end 211 94.3)
		(width 0.1)
		(layer "In7.Cu")
		(net 190)
	)
	(segment
		(start 237.4 112.3)
		(end 233.2 108.1)
		(width 0.1)
		(layer "In7.Cu")
		(net 190)
	)
	(segment
		(start 204.8 85.9)
		(end 201.4 85.9)
		(width 0.1)
		(layer "In7.Cu")
		(net 190)
	)
	(segment
		(start 189.000001 76.400001)
		(end 188.499999 76.400001)
		(width 0.1)
		(layer "In7.Cu")
		(net 190)
	)
	(segment
		(start 170.4 76.7)
		(end 165.875 81.225)
		(width 0.1)
		(layer "In7.Cu")
		(net 190)
	)
	(segment
		(start 172.3592 79.33)
		(end 174.16 81.1308)
		(width 0.1)
		(layer "F.Cu")
		(net 194)
	)
	(segment
		(start 162.809999 78.500001)
		(end 164.06 77.25)
		(width 0.1)
		(layer "F.Cu")
		(net 194)
	)
	(segment
		(start 158.000001 80.300001)
		(end 158.000001 79.700001)
		(width 0.1)
		(layer "F.Cu")
		(net 194)
	)
	(segment
		(start 159.200001 78.500001)
		(end 162.809999 78.500001)
		(width 0.1)
		(layer "F.Cu")
		(net 194)
	)
	(segment
		(start 158.825001 81.235001)
		(end 158.825001 81.125001)
		(width 0.1)
		(layer "F.Cu")
		(net 194)
	)
	(segment
		(start 158.000001 79.700001)
		(end 159.200001 78.500001)
		(width 0.1)
		(layer "F.Cu")
		(net 194)
	)
	(segment
		(start 168.88 79.33)
		(end 172.3592 79.33)
		(width 0.1)
		(layer "F.Cu")
		(net 194)
	)
	(segment
		(start 164.06 77.25)
		(end 166.8 77.25)
		(width 0.1)
		(layer "F.Cu")
		(net 194)
	)
	(segment
		(start 166.8 77.25)
		(end 168.88 79.33)
		(width 0.1)
		(layer "F.Cu")
		(net 194)
	)
	(segment
		(start 158.825001 81.125001)
		(end 158.000001 80.300001)
		(width 0.1)
		(layer "F.Cu")
		(net 194)
	)
	(segment
		(start 156.285001 130.765001)
		(end 157.555001 129.495001)
		(width 0.256)
		(layer "F.Cu")
		(net 215)
	)
	(segment
		(start 167.155 76.53)
		(end 169.325001 78.700001)
		(width 0.1)
		(layer "F.Cu")
		(net 216)
	)
	(segment
		(start 169.325001 78.700001)
		(end 173.229201 78.700001)
		(width 0.1)
		(layer "F.Cu")
		(net 216)
	)
	(segment
		(start 162.419999 78.100001)
		(end 163.99 76.53)
		(width 0.1)
		(layer "F.Cu")
		(net 216)
	)
	(segment
		(start 163.99 76.53)
		(end 167.155 76.53)
		(width 0.1)
		(layer "F.Cu")
		(net 216)
	)
	(segment
		(start 156.285001 80.615001)
		(end 158.800001 78.100001)
		(width 0.1)
		(layer "F.Cu")
		(net 216)
	)
	(segment
		(start 156.285001 81.235001)
		(end 156.285001 80.615001)
		(width 0.1)
		(layer "F.Cu")
		(net 216)
	)
	(segment
		(start 173.229201 78.700001)
		(end 175.66 81.1308)
		(width 0.1)
		(layer "F.Cu")
		(net 216)
	)
	(segment
		(start 158.800001 78.100001)
		(end 162.419999 78.100001)
		(width 0.1)
		(layer "F.Cu")
		(net 216)
	)
	(segment
		(start 235 125.05)
		(end 235 129.835)
		(width 0.1)
		(layer "F.Cu")
		(net 220)
	)
	(segment
		(start 152.475 79.975)
		(end 152.475 79.35)
		(width 0.1)
		(layer "F.Cu")
		(net 220)
	)
	(segment
		(start 163.905001 118.065001)
		(end 163.2 117.36)
		(width 0.1)
		(layer "F.Cu")
		(net 220)
	)
	(segment
		(start 235 129.835)
		(end 235.715 130.55)
		(width 0.1)
		(layer "F.Cu")
		(net 220)
	)
	(segment
		(start 163.2 113.9)
		(end 163 113.7)
		(width 0.1)
		(layer "F.Cu")
		(net 220)
	)
	(segment
		(start 163 113.7)
		(end 152.825 113.7)
		(width 0.1)
		(layer "F.Cu")
		(net 220)
	)
	(segment
		(start 152.825 113.7)
		(end 152.35 113.225)
		(width 0.1)
		(layer "F.Cu")
		(net 220)
	)
	(segment
		(start 194.5 122.5)
		(end 194.000001 122.000001)
		(width 0.256)
		(layer "F.Cu")
		(net 220)
	)
	(segment
		(start 152.35 113.225)
		(end 152.35 80.1)
		(width 0.1)
		(layer "F.Cu")
		(net 220)
	)
	(segment
		(start 234.775 124.825)
		(end 235 125.05)
		(width 0.1)
		(layer "F.Cu")
		(net 220)
	)
	(segment
		(start 194.000001 122.000001)
		(end 193.98408 122.000001)
		(width 0.256)
		(layer "F.Cu")
		(net 220)
	)
	(segment
		(start 163.2 117.36)
		(end 163.2 113.9)
		(width 0.1)
		(layer "F.Cu")
		(net 220)
	)
	(segment
		(start 152.475 79.35)
		(end 152.4 79.275)
		(width 0.1)
		(layer "F.Cu")
		(net 220)
	)
	(segment
		(start 152.35 80.1)
		(end 152.475 79.975)
		(width 0.1)
		(layer "F.Cu")
		(net 220)
	)
	(via
		(at 193.98408 122.000001)
		(size 0.45)
		(drill 0.2)
		(layers "F.Cu" "B.Cu")
		(net 220)
	)
	(via
		(at 234.775 124.825)
		(size 0.45)
		(drill 0.2)
		(layers "F.Cu" "B.Cu")
		(net 220)
	)
	(via
		(at 152.4 79.275)
		(size 0.45)
		(drill 0.2)
		(layers "F.Cu" "B.Cu")
		(net 220)
	)
	(via
		(at 187.000001 77.000001)
		(size 0.45)
		(drill 0.2)
		(layers "F.Cu" "B.Cu")
		(net 220)
	)
	(segment
		(start 189.000001 74.385001)
		(end 189.000001 75.000001)
		(width 0.1)
		(layer "B.Cu")
		(net 220)
	)
	(segment
		(start 189.000001 75.000001)
		(end 187.000001 77.000001)
		(width 0.1)
		(layer "B.Cu")
		(net 220)
	)
	(segment
		(start 189 73.615)
		(end 189 74.385)
		(width 0.1)
		(layer "B.Cu")
		(net 220)
	)
	(segment
		(start 193.000001 119.200001)
		(end 193.000001 86.300001)
		(width 0.1)
		(layer "In3.Cu")
		(net 220)
	)
	(segment
		(start 193.500001 120.900001)
		(end 193.400001 120.800001)
		(width 0.1)
		(layer "In3.Cu")
		(net 220)
	)
	(segment
		(start 193.500001 121.500001)
		(end 193.500001 120.900001)
		(width 0.1)
		(layer "In3.Cu")
		(net 220)
	)
	(segment
		(start 193.000001 86.300001)
		(end 193.800001 85.500001)
		(width 0.1)
		(layer "In3.Cu")
		(net 220)
	)
	(segment
		(start 193.400001 119.600001)
		(end 193.000001 119.200001)
		(width 0.1)
		(layer "In3.Cu")
		(net 220)
	)
	(segment
		(start 193.800001 85.500001)
		(end 193.800001 77.465685)
		(width 0.1)
		(layer "In3.Cu")
		(net 220)
	)
	(segment
		(start 193.400001 120.800001)
		(end 193.400001 119.600001)
		(width 0.1)
		(layer "In3.Cu")
		(net 220)
	)
	(segment
		(start 193.334317 77.000001)
		(end 187.000001 77.000001)
		(width 0.1)
		(layer "In3.Cu")
		(net 220)
	)
	(segment
		(start 194.000001 122.000001)
		(end 193.500001 121.500001)
		(width 0.1)
		(layer "In3.Cu")
		(net 220)
	)
	(segment
		(start 193.800001 77.465685)
		(end 193.334317 77.000001)
		(width 0.1)
		(layer "In3.Cu")
		(net 220)
	)
	(segment
		(start 190 77.4)
		(end 189.600001 77.000001)
		(width 0.1)
		(layer "In7.Cu")
		(net 220)
	)
	(segment
		(start 170.275 76.4)
		(end 165.725 80.95)
		(width 0.1)
		(layer "In7.Cu")
		(net 220)
	)
	(segment
		(start 205.000001 85.700001)
		(end 201.600001 85.700001)
		(width 0.1)
		(layer "In7.Cu")
		(net 220)
	)
	(segment
		(start 185.5 77.2)
		(end 184.4 77.2)
		(width 0.1)
		(layer "In7.Cu")
		(net 220)
	)
	(segment
		(start 217.000001 107.700001)
		(end 211.200001 101.900001)
		(width 0.1)
		(layer "In7.Cu")
		(net 220)
	)
	(segment
		(start 160.975 79.35)
		(end 152.475 79.35)
		(width 0.1)
		(layer "In7.Cu")
		(net 220)
	)
	(segment
		(start 152.475 79.35)
		(end 152.4 79.275)
		(width 0.1)
		(layer "In7.Cu")
		(net 220)
	)
	(segment
		(start 209.1 92)
		(end 209.1 89.8)
		(width 0.1)
		(layer "In7.Cu")
		(net 220)
	)
	(segment
		(start 184.4 77.2)
		(end 183.6 76.4)
		(width 0.1)
		(layer "In7.Cu")
		(net 220)
	)
	(segment
		(start 188.100001 75.900001)
		(end 187.000001 77.000001)
		(width 0.1)
		(layer "In7.Cu")
		(net 220)
	)
	(segment
		(start 162.575 80.95)
		(end 160.975 79.35)
		(width 0.1)
		(layer "In7.Cu")
		(net 220)
	)
	(segment
		(start 189.600001 76.300001)
		(end 189.200001 75.900001)
		(width 0.1)
		(layer "In7.Cu")
		(net 220)
	)
	(segment
		(start 237.600001 112.100001)
		(end 233.200001 107.700001)
		(width 0.1)
		(layer "In7.Cu")
		(net 220)
	)
	(segment
		(start 211.200001 101.900001)
		(end 211.200001 94.100001)
		(width 0.1)
		(layer "In7.Cu")
		(net 220)
	)
	(segment
		(start 209.1 89.8)
		(end 205.000001 85.700001)
		(width 0.1)
		(layer "In7.Cu")
		(net 220)
	)
	(segment
		(start 165.725 80.95)
		(end 162.575 80.95)
		(width 0.1)
		(layer "In7.Cu")
		(net 220)
	)
	(segment
		(start 234.775001 124.825001)
		(end 236.475001 124.825001)
		(width 0.1)
		(layer "In7.Cu")
		(net 220)
	)
	(segment
		(start 237.600001 123.700001)
		(end 237.600001 112.100001)
		(width 0.1)
		(layer "In7.Cu")
		(net 220)
	)
	(segment
		(start 201.600001 85.700001)
		(end 200.200001 84.300001)
		(width 0.1)
		(layer "In7.Cu")
		(net 220)
	)
	(segment
		(start 196.7 77.4)
		(end 190 77.4)
		(width 0.1)
		(layer "In7.Cu")
		(net 220)
	)
	(segment
		(start 189.200001 75.900001)
		(end 188.100001 75.900001)
		(width 0.1)
		(layer "In7.Cu")
		(net 220)
	)
	(segment
		(start 189.600001 77.000001)
		(end 189.600001 76.300001)
		(width 0.1)
		(layer "In7.Cu")
		(net 220)
	)
	(segment
		(start 170.275 76.4)
		(end 183.6 76.4)
		(width 0.1)
		(layer "In7.Cu")
		(net 220)
	)
	(segment
		(start 185.699999 77.000001)
		(end 185.5 77.2)
		(width 0.1)
		(layer "In7.Cu")
		(net 220)
	)
	(segment
		(start 200.200001 84.300001)
		(end 200.200001 80.900001)
		(width 0.1)
		(layer "In7.Cu")
		(net 220)
	)
	(segment
		(start 200.200001 80.900001)
		(end 196.7 77.4)
		(width 0.1)
		(layer "In7.Cu")
		(net 220)
	)
	(segment
		(start 187.000001 77.000001)
		(end 185.699999 77.000001)
		(width 0.1)
		(layer "In7.Cu")
		(net 220)
	)
	(segment
		(start 211.200001 94.100001)
		(end 209.1 92)
		(width 0.1)
		(layer "In7.Cu")
		(net 220)
	)
	(segment
		(start 236.475001 124.825001)
		(end 237.600001 123.700001)
		(width 0.1)
		(layer "In7.Cu")
		(net 220)
	)
	(segment
		(start 233.200001 107.700001)
		(end 217.000001 107.700001)
		(width 0.1)
		(layer "In7.Cu")
		(net 220)
	)
	(segment
		(start 198.5 118.5)
		(end 198.024377 118.024377)
		(width 0.256)
		(layer "F.Cu")
		(net 239)
	)
	(segment
		(start 156.775002 93.168)
		(end 156.920001 93.023001)
		(width 0.16)
		(layer "F.Cu")
		(net 239)
	)
	(segment
		(start 156.285001 92.846198)
		(end 156.606804 93.168001)
		(width 0.16)
		(layer "F.Cu")
		(net 239)
	)
	(segment
		(start 156.775002 93.168)
		(end 156.606804 93.168001)
		(width 0.16)
		(layer "F.Cu")
		(net 239)
	)
	(segment
		(start 156.285001 92.665001)
		(end 156.285001 92.846198)
		(width 0.16)
		(layer "F.Cu")
		(net 239)
	)
	(segment
		(start 198.024377 118.024377)
		(end 198.01323 118.024377)
		(width 0.256)
		(layer "F.Cu")
		(net 239)
	)
	(via
		(at 156.920001 93.023001)
		(size 0.45)
		(drill 0.2)
		(layers "F.Cu" "B.Cu")
		(net 239)
	)
	(via
		(at 198.01323 118.024377)
		(size 0.45)
		(drill 0.2)
		(layers "F.Cu" "B.Cu")
		(net 239)
	)
	(segment
		(start 183.103501 93.084364)
		(end 183.103502 93.084363)
		(width 0.114)
		(layer "In5.Cu")
		(net 239)
	)
	(segment
		(start 157.053501 93.156501)
		(end 158.840561 93.156501)
		(width 0.114)
		(layer "In5.Cu")
		(net 239)
	)
	(segment
		(start 180.559441 91.256501)
		(end 181.901469 92.59853)
		(width 0.114)
		(layer "In5.Cu")
		(net 239)
	)
	(segment
		(start 200.396423 117.600001)
		(end 200.650001 117.346423)
		(width 0.1)
		(layer "In5.Cu")
		(net 239)
	)
	(segment
		(start 184.093451 94.074312)
		(end 183.881367 94.286393)
		(width 0.114)
		(layer "In5.Cu")
		(net 239)
	)
	(segment
		(start 167.680561 92.516501)
		(end 168.940561 91.256501)
		(width 0.114)
		(layer "In5.Cu")
		(net 239)
	)
	(segment
		(start 182.193505 92.598531)
		(end 182.405588 92.386449)
		(width 0.114)
		(layer "In5.Cu")
		(net 239)
	)
	(segment
		(start 183.881367 94.578429)
		(end 183.881368 94.578429)
		(width 0.114)
		(layer "In5.Cu")
		(net 239)
	)
	(segment
		(start 156.920001 93.023001)
		(end 157.053501 93.156501)
		(width 0.114)
		(layer "In5.Cu")
		(net 239)
	)
	(segment
		(start 158.840561 93.156501)
		(end 159.480561 92.516501)
		(width 0.114)
		(layer "In5.Cu")
		(net 239)
	)
	(segment
		(start 182.193507 92.598532)
		(end 182.193505 92.598531)
		(width 0.114)
		(layer "In5.Cu")
		(net 239)
	)
	(segment
		(start 184.09345 94.074313)
		(end 184.093451 94.074312)
		(width 0.114)
		(layer "In5.Cu")
		(net 239)
	)
	(segment
		(start 200.693501 111.390561)
		(end 200.693501 113.405001)
		(width 0.114)
		(layer "In5.Cu")
		(net 239)
	)
	(segment
		(start 198.400001 117.600001)
		(end 200.396423 117.600001)
		(width 0.1)
		(layer "In5.Cu")
		(net 239)
	)
	(segment
		(start 182.891418 93.58848)
		(end 182.891419 93.58848)
		(width 0.114)
		(layer "In5.Cu")
		(net 239)
	)
	(segment
		(start 168.940561 91.256501)
		(end 180.559441 91.256501)
		(width 0.114)
		(layer "In5.Cu")
		(net 239)
	)
	(segment
		(start 200.650001 117.346423)
		(end 200.650001 113.448501)
		(width 0.1)
		(layer "In5.Cu")
		(net 239)
	)
	(segment
		(start 183.881368 94.578429)
		(end 200.693501 111.390561)
		(width 0.114)
		(layer "In5.Cu")
		(net 239)
	)
	(segment
		(start 159.480561 92.516501)
		(end 167.680561 92.516501)
		(width 0.114)
		(layer "In5.Cu")
		(net 239)
	)
	(segment
		(start 183.183454 93.58848)
		(end 183.395537 93.376398)
		(width 0.114)
		(layer "In5.Cu")
		(net 239)
	)
	(segment
		(start 200.650001 113.448501)
		(end 200.693501 113.405001)
		(width 0.1)
		(layer "In5.Cu")
		(net 239)
	)
	(segment
		(start 183.183456 93.588481)
		(end 183.183454 93.58848)
		(width 0.114)
		(layer "In5.Cu")
		(net 239)
	)
	(segment
		(start 183.103502 93.084363)
		(end 182.891418 93.296444)
		(width 0.114)
		(layer "In5.Cu")
		(net 239)
	)
	(segment
		(start 198.000001 118.000001)
		(end 198.400001 117.600001)
		(width 0.1)
		(layer "In5.Cu")
		(net 239)
	)
	(arc
		(start 183.395537 93.376398)
		(mid 183.744494 93.231855)
		(end 184.093451 93.376398)
		(width 0.114)
		(layer "In5.Cu")
		(net 239)
	)
	(arc
		(start 183.881367 94.286393)
		(mid 183.820885 94.432412)
		(end 183.881367 94.578429)
		(width 0.114)
		(layer "In5.Cu")
		(net 239)
	)
	(arc
		(start 181.901469 92.59853)
		(mid 182.047488 92.659014)
		(end 182.193507 92.598532)
		(width 0.114)
		(layer "In5.Cu")
		(net 239)
	)
	(arc
		(start 184.093451 93.376398)
		(mid 184.237993 93.725356)
		(end 184.09345 94.074313)
		(width 0.114)
		(layer "In5.Cu")
		(net 239)
	)
	(arc
		(start 182.891418 93.296444)
		(mid 182.830936 93.442463)
		(end 182.891418 93.58848)
		(width 0.114)
		(layer "In5.Cu")
		(net 239)
	)
	(arc
		(start 183.103502 92.386449)
		(mid 183.248044 92.735407)
		(end 183.103501 93.084364)
		(width 0.114)
		(layer "In5.Cu")
		(net 239)
	)
	(arc
		(start 182.405588 92.386449)
		(mid 182.754545 92.241906)
		(end 183.103502 92.386449)
		(width 0.114)
		(layer "In5.Cu")
		(net 239)
	)
	(arc
		(start 182.891418 93.588479)
		(mid 183.037437 93.648963)
		(end 183.183456 93.588481)
		(width 0.114)
		(layer "In5.Cu")
		(net 239)
	)
	(segment
		(start 195.025955 117.025955)
		(end 195.025955 116.984935)
		(width 0.256)
		(layer "F.Cu")
		(net 241)
	)
	(segment
		(start 195.5 117.5)
		(end 195.025955 117.025955)
		(width 0.256)
		(layer "F.Cu")
		(net 241)
	)
	(segment
		(start 158.045002 92.162002)
		(end 158.190001 92.307001)
		(width 0.16)
		(layer "F.Cu")
		(net 241)
	)
	(segment
		(start 157.555001 92.483804)
		(end 157.555001 92.665001)
		(width 0.16)
		(layer "F.Cu")
		(net 241)
	)
	(segment
		(start 157.876804 92.162001)
		(end 157.555001 92.483804)
		(width 0.16)
		(layer "F.Cu")
		(net 241)
	)
	(segment
		(start 158.045002 92.162002)
		(end 157.876804 92.162001)
		(width 0.16)
		(layer "F.Cu")
		(net 241)
	)
	(via
		(at 195.025955 116.984935)
		(size 0.45)
		(drill 0.2)
		(layers "F.Cu" "B.Cu")
		(net 241)
	)
	(via
		(at 158.190001 92.307001)
		(size 0.45)
		(drill 0.2)
		(layers "F.Cu" "B.Cu")
		(net 241)
	)
	(segment
		(start 160.962501 92.516501)
		(end 169.770561 92.516501)
		(width 0.114)
		(layer "In7.Cu")
		(net 241)
	)
	(segment
		(start 179.659397 98.121459)
		(end 179.659397 98.121458)
		(width 0.114)
		(layer "In7.Cu")
		(net 241)
	)
	(segment
		(start 175.063208 94.187828)
		(end 174.773753 94.477282)
		(width 0.114)
		(layer "In7.Cu")
		(net 241)
	)
	(segment
		(start 157.952156 92.876501)
		(end 158.699013 92.876501)
		(width 0.114)
		(layer "In7.Cu")
		(net 241)
	)
	(segment
		(start 176.868908 96.572437)
		(end 177.158362 96.282982)
		(width 0.114)
		(layer "In7.Cu")
		(net 241)
	)
	(segment
		(start 177.788146 97.491675)
		(end 178.0776 97.20222)
		(width 0.114)
		(layer "In7.Cu")
		(net 241)
	)
	(segment
		(start 178.74016 97.86478)
		(end 178.450705 98.154234)
		(width 0.114)
		(layer "In7.Cu")
		(net 241)
	)
	(segment
		(start 174.111194 93.814723)
		(end 174.400648 93.525268)
		(width 0.114)
		(layer "In7.Cu")
		(net 241)
	)
	(segment
		(start 160.062501 92.216501)
		(end 160.062501 92.187032)
		(width 0.114)
		(layer "In7.Cu")
		(net 241)
	)
	(segment
		(start 176.612229 96.572438)
		(end 176.612229 96.572437)
		(width 0.114)
		(layer "In7.Cu")
		(net 241)
	)
	(segment
		(start 160.662501 92.187032)
		(end 160.662501 92.216501)
		(width 0.114)
		(layer "In7.Cu")
		(net 241)
	)
	(segment
		(start 158.190001 92.307001)
		(end 158.056501 92.173501)
		(width 0.114)
		(layer "In7.Cu")
		(net 241)
	)
	(segment
		(start 173.854515 93.814724)
		(end 173.854515 93.814723)
		(width 0.114)
		(layer "In7.Cu")
		(net 241)
	)
	(segment
		(start 178.707384 98.410912)
		(end 178.707384 98.410913)
		(width 0.114)
		(layer "In7.Cu")
		(net 241)
	)
	(segment
		(start 159.059013 92.516501)
		(end 159.762501 92.516501)
		(width 0.114)
		(layer "In7.Cu")
		(net 241)
	)
	(segment
		(start 176.901684 96.026303)
		(end 176.901684 96.026304)
		(width 0.114)
		(layer "In7.Cu")
		(net 241)
	)
	(segment
		(start 177.788146 97.491674)
		(end 177.788146 97.491675)
		(width 0.114)
		(layer "In7.Cu")
		(net 241)
	)
	(segment
		(start 176.901683 95.363745)
		(end 176.901683 95.363744)
		(width 0.114)
		(layer "In7.Cu")
		(net 241)
	)
	(segment
		(start 176.901684 96.026304)
		(end 176.612229 96.315758)
		(width 0.114)
		(layer "In7.Cu")
		(net 241)
	)
	(segment
		(start 175.030432 94.73396)
		(end 175.030432 94.733961)
		(width 0.114)
		(layer "In7.Cu")
		(net 241)
	)
	(segment
		(start 175.94967 95.653198)
		(end 175.94967 95.653199)
		(width 0.114)
		(layer "In7.Cu")
		(net 241)
	)
	(segment
		(start 169.770561 92.516501)
		(end 170.450561 91.836501)
		(width 0.114)
		(layer "In7.Cu")
		(net 241)
	)
	(segment
		(start 178.707384 98.410913)
		(end 178.996838 98.121458)
		(width 0.114)
		(layer "In7.Cu")
		(net 241)
	)
	(segment
		(start 193.841423 117.400001)
		(end 193.600001 117.158579)
		(width 0.1)
		(layer "In7.Cu")
		(net 241)
	)
	(segment
		(start 175.94967 95.653199)
		(end 176.239124 95.363744)
		(width 0.114)
		(layer "In7.Cu")
		(net 241)
	)
	(segment
		(start 175.982445 94.444507)
		(end 175.982445 94.444506)
		(width 0.114)
		(layer "In7.Cu")
		(net 241)
	)
	(segment
		(start 178.450705 98.410914)
		(end 178.450705 98.410913)
		(width 0.114)
		(layer "In7.Cu")
		(net 241)
	)
	(segment
		(start 174.773753 94.733962)
		(end 174.773753 94.733961)
		(width 0.114)
		(layer "In7.Cu")
		(net 241)
	)
	(segment
		(start 193.600001 113.448501)
		(end 193.643501 113.405001)
		(width 0.1)
		(layer "In7.Cu")
		(net 241)
	)
	(segment
		(start 177.531467 97.491676)
		(end 177.531467 97.491675)
		(width 0.114)
		(layer "In7.Cu")
		(net 241)
	)
	(segment
		(start 178.74016 97.864779)
		(end 178.74016 97.86478)
		(width 0.114)
		(layer "In7.Cu")
		(net 241)
	)
	(segment
		(start 195.000001 117.000001)
		(end 194.600001 117.400001)
		(width 0.1)
		(layer "In7.Cu")
		(net 241)
	)
	(segment
		(start 174.14397 93.26859)
		(end 173.854515 93.558044)
		(width 0.114)
		(layer "In7.Cu")
		(net 241)
	)
	(segment
		(start 178.740159 97.202221)
		(end 178.740159 97.20222)
		(width 0.114)
		(layer "In7.Cu")
		(net 241)
	)
	(segment
		(start 175.030432 94.733961)
		(end 175.319886 94.444506)
		(width 0.114)
		(layer "In7.Cu")
		(net 241)
	)
	(segment
		(start 177.820922 96.945541)
		(end 177.820922 96.945542)
		(width 0.114)
		(layer "In7.Cu")
		(net 241)
	)
	(segment
		(start 174.111194 93.814722)
		(end 174.111194 93.814723)
		(width 0.114)
		(layer "In7.Cu")
		(net 241)
	)
	(segment
		(start 194.600001 117.400001)
		(end 193.841423 117.400001)
		(width 0.1)
		(layer "In7.Cu")
		(net 241)
	)
	(segment
		(start 175.692991 95.6532)
		(end 175.692991 95.653199)
		(width 0.114)
		(layer "In7.Cu")
		(net 241)
	)
	(segment
		(start 175.982446 95.107065)
		(end 175.982446 95.107066)
		(width 0.114)
		(layer "In7.Cu")
		(net 241)
	)
	(segment
		(start 177.820922 96.945542)
		(end 177.531467 97.234996)
		(width 0.114)
		(layer "In7.Cu")
		(net 241)
	)
	(segment
		(start 170.450561 91.836501)
		(end 173.374441 91.836501)
		(width 0.114)
		(layer "In7.Cu")
		(net 241)
	)
	(segment
		(start 157.743501 92.289441)
		(end 157.743501 92.667846)
		(width 0.114)
		(layer "In7.Cu")
		(net 241)
	)
	(segment
		(start 177.820921 96.282983)
		(end 177.820921 96.282982)
		(width 0.114)
		(layer "In7.Cu")
		(net 241)
	)
	(segment
		(start 193.600001 117.158579)
		(end 193.600001 113.448501)
		(width 0.1)
		(layer "In7.Cu")
		(net 241)
	)
	(segment
		(start 175.063208 94.187827)
		(end 175.063208 94.187828)
		(width 0.114)
		(layer "In7.Cu")
		(net 241)
	)
	(segment
		(start 175.982446 95.107066)
		(end 175.692991 95.39652)
		(width 0.114)
		(layer "In7.Cu")
		(net 241)
	)
	(segment
		(start 157.859441 92.173501)
		(end 157.743501 92.289441)
		(width 0.114)
		(layer "In7.Cu")
		(net 241)
	)
	(segment
		(start 173.374441 91.836501)
		(end 174.14397 92.606031)
		(width 0.114)
		(layer "In7.Cu")
		(net 241)
	)
	(segment
		(start 176.868908 96.572436)
		(end 176.868908 96.572437)
		(width 0.114)
		(layer "In7.Cu")
		(net 241)
	)
	(segment
		(start 179.659397 98.121458)
		(end 193.643501 112.105561)
		(width 0.114)
		(layer "In7.Cu")
		(net 241)
	)
	(segment
		(start 158.056501 92.173501)
		(end 157.859441 92.173501)
		(width 0.114)
		(layer "In7.Cu")
		(net 241)
	)
	(segment
		(start 193.643501 112.105561)
		(end 193.643501 113.405001)
		(width 0.114)
		(layer "In7.Cu")
		(net 241)
	)
	(segment
		(start 175.063207 93.525269)
		(end 175.063207 93.525268)
		(width 0.114)
		(layer "In7.Cu")
		(net 241)
	)
	(segment
		(start 157.743501 92.667846)
		(end 157.952156 92.876501)
		(width 0.114)
		(layer "In7.Cu")
		(net 241)
	)
	(segment
		(start 174.14397 93.268589)
		(end 174.14397 93.26859)
		(width 0.114)
		(layer "In7.Cu")
		(net 241)
	)
	(segment
		(start 158.699013 92.876501)
		(end 159.059013 92.516501)
		(width 0.114)
		(layer "In7.Cu")
		(net 241)
	)
	(arc
		(start 174.773753 94.733961)
		(mid 174.902093 94.78712)
		(end 175.030432 94.73396)
		(width 0.114)
		(layer "In7.Cu")
		(net 241)
	)
	(arc
		(start 174.14397 92.606031)
		(mid 174.28119 92.93731)
		(end 174.14397 93.268589)
		(width 0.114)
		(layer "In7.Cu")
		(net 241)
	)
	(arc
		(start 175.982446 94.444507)
		(mid 176.119666 94.775786)
		(end 175.982446 95.107065)
		(width 0.114)
		(layer "In7.Cu")
		(net 241)
	)
	(arc
		(start 176.901684 95.363745)
		(mid 177.038904 95.695024)
		(end 176.901684 96.026303)
		(width 0.114)
		(layer "In7.Cu")
		(net 241)
	)
	(arc
		(start 178.450705 98.154234)
		(mid 178.397545 98.282574)
		(end 178.450705 98.410914)
		(width 0.114)
		(layer "In7.Cu")
		(net 241)
	)
	(arc
		(start 175.692991 95.653199)
		(mid 175.821331 95.706358)
		(end 175.94967 95.653198)
		(width 0.114)
		(layer "In7.Cu")
		(net 241)
	)
	(arc
		(start 177.531467 97.491675)
		(mid 177.659807 97.544834)
		(end 177.788146 97.491674)
		(width 0.114)
		(layer "In7.Cu")
		(net 241)
	)
	(arc
		(start 177.820922 96.282983)
		(mid 177.958142 96.614262)
		(end 177.820922 96.945541)
		(width 0.114)
		(layer "In7.Cu")
		(net 241)
	)
	(arc
		(start 176.612229 96.572437)
		(mid 176.740569 96.625596)
		(end 176.868908 96.572436)
		(width 0.114)
		(layer "In7.Cu")
		(net 241)
	)
	(arc
		(start 177.158362 96.282982)
		(mid 177.489642 96.145762)
		(end 177.820921 96.282983)
		(width 0.114)
		(layer "In7.Cu")
		(net 241)
	)
	(arc
		(start 178.74016 97.202221)
		(mid 178.87738 97.5335)
		(end 178.74016 97.864779)
		(width 0.114)
		(layer "In7.Cu")
		(net 241)
	)
	(arc
		(start 178.450705 98.410913)
		(mid 178.579045 98.464072)
		(end 178.707384 98.410912)
		(width 0.114)
		(layer "In7.Cu")
		(net 241)
	)
	(arc
		(start 173.854515 93.814723)
		(mid 173.982855 93.867882)
		(end 174.111194 93.814722)
		(width 0.114)
		(layer "In7.Cu")
		(net 241)
	)
	(arc
		(start 176.612229 96.315758)
		(mid 176.559069 96.444098)
		(end 176.612229 96.572438)
		(width 0.114)
		(layer "In7.Cu")
		(net 241)
	)
	(arc
		(start 177.531467 97.234996)
		(mid 177.478307 97.363336)
		(end 177.531467 97.491676)
		(width 0.114)
		(layer "In7.Cu")
		(net 241)
	)
	(arc
		(start 173.854515 93.558044)
		(mid 173.801355 93.686384)
		(end 173.854515 93.814724)
		(width 0.114)
		(layer "In7.Cu")
		(net 241)
	)
	(arc
		(start 174.400648 93.525268)
		(mid 174.731928 93.388048)
		(end 175.063207 93.525269)
		(width 0.114)
		(layer "In7.Cu")
		(net 241)
	)
	(arc
		(start 160.662501 92.216501)
		(mid 160.750369 92.428633)
		(end 160.962501 92.516501)
		(width 0.114)
		(layer "In7.Cu")
		(net 241)
	)
	(arc
		(start 175.063208 93.525269)
		(mid 175.200428 93.856548)
		(end 175.063208 94.187827)
		(width 0.114)
		(layer "In7.Cu")
		(net 241)
	)
	(arc
		(start 160.062501 92.187032)
		(mid 160.150369 91.9749)
		(end 160.362501 91.887032)
		(width 0.114)
		(layer "In7.Cu")
		(net 241)
	)
	(arc
		(start 160.362501 91.887032)
		(mid 160.574633 91.9749)
		(end 160.662501 92.187032)
		(width 0.114)
		(layer "In7.Cu")
		(net 241)
	)
	(arc
		(start 175.319886 94.444506)
		(mid 175.651166 94.307286)
		(end 175.982445 94.444507)
		(width 0.114)
		(layer "In7.Cu")
		(net 241)
	)
	(arc
		(start 174.773753 94.477282)
		(mid 174.720593 94.605622)
		(end 174.773753 94.733962)
		(width 0.114)
		(layer "In7.Cu")
		(net 241)
	)
	(arc
		(start 175.692991 95.39652)
		(mid 175.639831 95.52486)
		(end 175.692991 95.6532)
		(width 0.114)
		(layer "In7.Cu")
		(net 241)
	)
	(arc
		(start 178.0776 97.20222)
		(mid 178.40888 97.065)
		(end 178.740159 97.202221)
		(width 0.114)
		(layer "In7.Cu")
		(net 241)
	)
	(arc
		(start 178.996838 98.121458)
		(mid 179.328118 97.984238)
		(end 179.659397 98.121459)
		(width 0.114)
		(layer "In7.Cu")
		(net 241)
	)
	(arc
		(start 176.239124 95.363744)
		(mid 176.570404 95.226524)
		(end 176.901683 95.363745)
		(width 0.114)
		(layer "In7.Cu")
		(net 241)
	)
	(arc
		(start 159.762501 92.516501)
		(mid 159.974633 92.428633)
		(end 160.062501 92.216501)
		(width 0.114)
		(layer "In7.Cu")
		(net 241)
	)
	(segment
		(start 194.5 126.5)
		(end 194 126)
		(width 0.256)
		(layer "F.Cu")
		(net 246)
	)
	(segment
		(start 206.75 81.335)
		(end 206.75 79.74)
		(width 0.182)
		(layer "F.Cu")
		(net 246)
	)
	(segment
		(start 207.155 81.74)
		(end 206.75 81.335)
		(width 0.182)
		(layer "F.Cu")
		(net 246)
	)
	(via
		(at 247.275 141.975)
		(size 0.45)
		(drill 0.2)
		(layers "F.Cu" "B.Cu")
		(net 246)
	)
	(via
		(at 206.75 79.74)
		(size 0.45)
		(drill 0.2)
		(layers "F.Cu" "B.Cu")
		(net 246)
	)
	(via
		(at 194 126)
		(size 0.45)
		(drill 0.2)
		(layers "F.Cu" "B.Cu")
		(net 246)
	)
	(segment
		(start 245.9 142.475)
		(end 243.725 142.475)
		(width 0.1)
		(layer "B.Cu")
		(net 246)
	)
	(segment
		(start 243.525 143.925)
		(end 244 144.4)
		(width 0.1)
		(layer "B.Cu")
		(net 246)
	)
	(segment
		(start 247.7 144.4)
		(end 249.3 146)
		(width 0.1)
		(layer "B.Cu")
		(net 246)
	)
	(segment
		(start 243.725 142.475)
		(end 243.525 142.675)
		(width 0.1)
		(layer "B.Cu")
		(net 246)
	)
	(segment
		(start 244 144.4)
		(end 247.7 144.4)
		(width 0.1)
		(layer "B.Cu")
		(net 246)
	)
	(segment
		(start 249.3 146)
		(end 249.3 148.273)
		(width 0.1)
		(layer "B.Cu")
		(net 246)
	)
	(segment
		(start 247.275 141.975)
		(end 246.4 141.975)
		(width 0.1)
		(layer "B.Cu")
		(net 246)
	)
	(segment
		(start 246.4 141.975)
		(end 245.9 142.475)
		(width 0.1)
		(layer "B.Cu")
		(net 246)
	)
	(segment
		(start 243.525 142.675)
		(end 243.525 143.925)
		(width 0.1)
		(layer "B.Cu")
		(net 246)
	)
	(segment
		(start 195 81.87)
		(end 195 85.997053)
		(width 0.1)
		(layer "In3.Cu")
		(net 246)
	)
	(segment
		(start 260.1 72.8)
		(end 262 74.7)
		(width 0.1)
		(layer "In3.Cu")
		(net 246)
	)
	(segment
		(start 194.6 125.4)
		(end 194 126)
		(width 0.1)
		(layer "In3.Cu")
		(net 246)
	)
	(segment
		(start 245 138.8)
		(end 247.25 141.05)
		(width 0.1)
		(layer "In3.Cu")
		(net 246)
	)
	(segment
		(start 206.75 79.74)
		(end 207.188 79.302)
		(width 0.1)
		(layer "In3.Cu")
		(net 246)
	)
	(segment
		(start 262 74.7)
		(end 262 94.2)
		(width 0.1)
		(layer "In3.Cu")
		(net 246)
	)
	(segment
		(start 207.188 79.302)
		(end 207.188 76.211999)
		(width 0.1)
		(layer "In3.Cu")
		(net 246)
	)
	(segment
		(start 194.6 114.4)
		(end 194.6 125.4)
		(width 0.1)
		(layer "In3.Cu")
		(net 246)
	)
	(segment
		(start 194.2 86.797052)
		(end 194.2 114)
		(width 0.1)
		(layer "In3.Cu")
		(net 246)
	)
	(segment
		(start 247.25 141.95)
		(end 247.275 141.975)
		(width 0.1)
		(layer "In3.Cu")
		(net 246)
	)
	(segment
		(start 205.73 80.76)
		(end 196.11 80.76)
		(width 0.1)
		(layer "In3.Cu")
		(net 246)
	)
	(segment
		(start 196.11 80.76)
		(end 195 81.87)
		(width 0.1)
		(layer "In3.Cu")
		(net 246)
	)
	(segment
		(start 245 111.2)
		(end 245 138.8)
		(width 0.1)
		(layer "In3.Cu")
		(net 246)
	)
	(segment
		(start 195 85.997053)
		(end 194.2 86.797052)
		(width 0.1)
		(layer "In3.Cu")
		(net 246)
	)
	(segment
		(start 247.25 141.05)
		(end 247.25 141.95)
		(width 0.1)
		(layer "In3.Cu")
		(net 246)
	)
	(segment
		(start 207.188 76.211999)
		(end 210.6 72.8)
		(width 0.1)
		(layer "In3.Cu")
		(net 246)
	)
	(segment
		(start 206.75 79.74)
		(end 205.73 80.76)
		(width 0.1)
		(layer "In3.Cu")
		(net 246)
	)
	(segment
		(start 194.2 114)
		(end 194.6 114.4)
		(width 0.1)
		(layer "In3.Cu")
		(net 246)
	)
	(segment
		(start 210.6 72.8)
		(end 260.1 72.8)
		(width 0.1)
		(layer "In3.Cu")
		(net 246)
	)
	(segment
		(start 262 94.2)
		(end 245 111.2)
		(width 0.1)
		(layer "In3.Cu")
		(net 246)
	)
	(segment
		(start 167.715001 92.665001)
		(end 168.218 93.168)
		(width 0.16)
		(layer "F.Cu")
		(net 249)
	)
	(segment
		(start 171.599501 92.975)
		(end 171.475 93.099501)
		(width 0.201)
		(layer "F.Cu")
		(net 249)
	)
	(segment
		(start 171.475 93.099501)
		(end 170.572501 93.099501)
		(width 0.201)
		(layer "F.Cu")
		(net 249)
	)
	(segment
		(start 170.504001 93.168001)
		(end 170.572501 93.099501)
		(width 0.16)
		(layer "F.Cu")
		(net 249)
	)
	(segment
		(start 170.504001 93.168001)
		(end 168.218 93.168)
		(width 0.16)
		(layer "F.Cu")
		(net 249)
	)
	(via
		(at 171.599501 92.975)
		(size 0.45)
		(drill 0.2)
		(layers "F.Cu" "B.Cu")
		(net 249)
	)
	(via
		(at 190.5 130.5)
		(size 0.45)
		(drill 0.2)
		(layers "F.Cu" "B.Cu")
		(net 249)
	)
	(segment
		(start 178.320501 95.376951)
		(end 178.320501 127.976951)
		(width 0.201)
		(layer "B.Cu")
		(net 249)
	)
	(segment
		(start 190.210001 130.500001)
		(end 190.099399 130.389399)
		(width 0.1)
		(layer "B.Cu")
		(net 249)
	)
	(segment
		(start 183.447376 129.900001)
		(end 183.346376 129.799001)
		(width 0.1)
		(layer "B.Cu")
		(net 249)
	)
	(segment
		(start 178.320501 127.976951)
		(end 180.142551 129.799001)
		(width 0.201)
		(layer "B.Cu")
		(net 249)
	)
	(segment
		(start 171.599501 92.975)
		(end 171.724002 93.099501)
		(width 0.201)
		(layer "B.Cu")
		(net 249)
	)
	(segment
		(start 190.099399 130.389399)
		(end 190.0994 130.137977)
		(width 0.1)
		(layer "B.Cu")
		(net 249)
	)
	(segment
		(start 190.210001 130.500001)
		(end 190.500001 130.500001)
		(width 0.1)
		(layer "B.Cu")
		(net 249)
	)
	(segment
		(start 176.043051 93.099501)
		(end 178.320501 95.376951)
		(width 0.201)
		(layer "B.Cu")
		(net 249)
	)
	(segment
		(start 190.0994 130.137977)
		(end 189.861424 129.900001)
		(width 0.1)
		(layer "B.Cu")
		(net 249)
	)
	(segment
		(start 180.142551 129.799001)
		(end 183.346376 129.799001)
		(width 0.201)
		(layer "B.Cu")
		(net 249)
	)
	(segment
		(start 189.861424 129.900001)
		(end 183.447376 129.900001)
		(width 0.1)
		(layer "B.Cu")
		(net 249)
	)
	(segment
		(start 171.724002 93.099501)
		(end 176.043051 93.099501)
		(width 0.201)
		(layer "B.Cu")
		(net 249)
	)
	(via
		(at 249.15 149.9)
		(size 0.45)
		(drill 0.2)
		(layers "F.Cu" "B.Cu")
		(net 250)
	)
	(segment
		(start 249.15 149.9)
		(end 249.15 149.6)
		(width 0.177)
		(layer "B.Cu")
		(net 250)
	)
	(segment
		(start 249.15 149.6)
		(end 249.3 149.45)
		(width 0.177)
		(layer "B.Cu")
		(net 250)
	)
	(segment
		(start 195.5 118.5)
		(end 195 118)
		(width 0.256)
		(layer "F.Cu")
		(net 254)
	)
	(segment
		(start 157.555001 91.395001)
		(end 157.555001 91.576198)
		(width 0.16)
		(layer "F.Cu")
		(net 254)
	)
	(segment
		(start 157.555001 91.576198)
		(end 157.876804 91.898001)
		(width 0.16)
		(layer "F.Cu")
		(net 254)
	)
	(segment
		(start 158.045002 91.898)
		(end 158.190001 91.753001)
		(width 0.16)
		(layer "F.Cu")
		(net 254)
	)
	(segment
		(start 158.045002 91.898)
		(end 157.876804 91.898001)
		(width 0.16)
		(layer "F.Cu")
		(net 254)
	)
	(via
		(at 158.190001 91.753001)
		(size 0.45)
		(drill 0.2)
		(layers "F.Cu" "B.Cu")
		(net 254)
	)
	(via
		(at 195 118)
		(size 0.45)
		(drill 0.2)
		(layers "F.Cu" "B.Cu")
		(net 254)
	)
	(segment
		(start 193.758579 117.600001)
		(end 193.400001 117.241423)
		(width 0.1)
		(layer "In7.Cu")
		(net 254)
	)
	(segment
		(start 174.314135 94.017662)
		(end 174.314135 94.017663)
		(width 0.114)
		(layer "In7.Cu")
		(net 254)
	)
	(segment
		(start 174.314135 94.017663)
		(end 174.603589 93.728208)
		(width 0.114)
		(layer "In7.Cu")
		(net 254)
	)
	(segment
		(start 174.570815 94.936901)
		(end 174.570814 94.936901)
		(width 0.114)
		(layer "In7.Cu")
		(net 254)
	)
	(segment
		(start 177.071849 96.775377)
		(end 177.361303 96.485922)
		(width 0.114)
		(layer "In7.Cu")
		(net 254)
	)
	(segment
		(start 158.190001 91.753001)
		(end 158.056501 91.886501)
		(width 0.114)
		(layer "In7.Cu")
		(net 254)
	)
	(segment
		(start 175.490053 95.856139)
		(end 175.490052 95.856139)
		(width 0.114)
		(layer "In7.Cu")
		(net 254)
	)
	(segment
		(start 195.000001 118.000001)
		(end 194.600001 117.600001)
		(width 0.1)
		(layer "In7.Cu")
		(net 254)
	)
	(segment
		(start 173.651577 94.017663)
		(end 173.651576 94.017663)
		(width 0.114)
		(layer "In7.Cu")
		(net 254)
	)
	(segment
		(start 193.356501 112.224441)
		(end 193.356501 113.405001)
		(width 0.114)
		(layer "In7.Cu")
		(net 254)
	)
	(segment
		(start 193.400001 113.448501)
		(end 193.356501 113.405001)
		(width 0.1)
		(layer "In7.Cu")
		(net 254)
	)
	(segment
		(start 157.833276 93.163501)
		(end 158.817893 93.163501)
		(width 0.114)
		(layer "In7.Cu")
		(net 254)
	)
	(segment
		(start 178.537221 97.66184)
		(end 178.247766 97.951294)
		(width 0.114)
		(layer "In7.Cu")
		(net 254)
	)
	(segment
		(start 158.817893 93.163501)
		(end 159.177893 92.803501)
		(width 0.114)
		(layer "In7.Cu")
		(net 254)
	)
	(segment
		(start 175.233373 94.936901)
		(end 175.522827 94.647446)
		(width 0.114)
		(layer "In7.Cu")
		(net 254)
	)
	(segment
		(start 157.740561 91.886501)
		(end 157.456501 92.170561)
		(width 0.114)
		(layer "In7.Cu")
		(net 254)
	)
	(segment
		(start 170.569441 92.123501)
		(end 173.255561 92.123501)
		(width 0.114)
		(layer "In7.Cu")
		(net 254)
	)
	(segment
		(start 174.860269 93.984888)
		(end 174.570814 94.274342)
		(width 0.114)
		(layer "In7.Cu")
		(net 254)
	)
	(segment
		(start 158.056501 91.886501)
		(end 157.740561 91.886501)
		(width 0.114)
		(layer "In7.Cu")
		(net 254)
	)
	(segment
		(start 177.991087 97.694615)
		(end 178.280541 97.40516)
		(width 0.114)
		(layer "In7.Cu")
		(net 254)
	)
	(segment
		(start 176.152611 95.856138)
		(end 176.152611 95.856139)
		(width 0.114)
		(layer "In7.Cu")
		(net 254)
	)
	(segment
		(start 175.233373 94.9369)
		(end 175.233373 94.936901)
		(width 0.114)
		(layer "In7.Cu")
		(net 254)
	)
	(segment
		(start 176.152611 95.856139)
		(end 176.442065 95.566684)
		(width 0.114)
		(layer "In7.Cu")
		(net 254)
	)
	(segment
		(start 169.889441 92.803501)
		(end 170.569441 92.123501)
		(width 0.114)
		(layer "In7.Cu")
		(net 254)
	)
	(segment
		(start 179.456459 98.324398)
		(end 179.456458 98.324398)
		(width 0.114)
		(layer "In7.Cu")
		(net 254)
	)
	(segment
		(start 177.991087 97.694614)
		(end 177.991087 97.694615)
		(width 0.114)
		(layer "In7.Cu")
		(net 254)
	)
	(segment
		(start 178.247767 98.613853)
		(end 178.247766 98.613853)
		(width 0.114)
		(layer "In7.Cu")
		(net 254)
	)
	(segment
		(start 176.409291 96.775377)
		(end 176.40929 96.775377)
		(width 0.114)
		(layer "In7.Cu")
		(net 254)
	)
	(segment
		(start 179.456458 98.324398)
		(end 193.356501 112.224441)
		(width 0.114)
		(layer "In7.Cu")
		(net 254)
	)
	(segment
		(start 176.698745 95.823364)
		(end 176.40929 96.112818)
		(width 0.114)
		(layer "In7.Cu")
		(net 254)
	)
	(segment
		(start 194.600001 117.600001)
		(end 193.758579 117.600001)
		(width 0.1)
		(layer "In7.Cu")
		(net 254)
	)
	(segment
		(start 193.400001 117.241423)
		(end 193.400001 113.448501)
		(width 0.1)
		(layer "In7.Cu")
		(net 254)
	)
	(segment
		(start 175.779507 94.904126)
		(end 175.490052 95.19358)
		(width 0.114)
		(layer "In7.Cu")
		(net 254)
	)
	(segment
		(start 173.255561 92.123501)
		(end 173.941031 92.80897)
		(width 0.114)
		(layer "In7.Cu")
		(net 254)
	)
	(segment
		(start 177.617983 96.742602)
		(end 177.328528 97.032056)
		(width 0.114)
		(layer "In7.Cu")
		(net 254)
	)
	(segment
		(start 173.941031 93.06565)
		(end 173.651576 93.355104)
		(width 0.114)
		(layer "In7.Cu")
		(net 254)
	)
	(segment
		(start 157.456501 92.170561)
		(end 157.456501 92.786726)
		(width 0.114)
		(layer "In7.Cu")
		(net 254)
	)
	(segment
		(start 177.328529 97.694615)
		(end 177.328528 97.694615)
		(width 0.114)
		(layer "In7.Cu")
		(net 254)
	)
	(segment
		(start 157.456501 92.786726)
		(end 157.833276 93.163501)
		(width 0.114)
		(layer "In7.Cu")
		(net 254)
	)
	(segment
		(start 159.177893 92.803501)
		(end 169.889441 92.803501)
		(width 0.114)
		(layer "In7.Cu")
		(net 254)
	)
	(segment
		(start 177.071849 96.775376)
		(end 177.071849 96.775377)
		(width 0.114)
		(layer "In7.Cu")
		(net 254)
	)
	(segment
		(start 178.910325 98.613853)
		(end 179.199779 98.324398)
		(width 0.114)
		(layer "In7.Cu")
		(net 254)
	)
	(segment
		(start 178.910325 98.613852)
		(end 178.910325 98.613853)
		(width 0.114)
		(layer "In7.Cu")
		(net 254)
	)
	(arc
		(start 175.522827 94.647446)
		(mid 175.651167 94.594286)
		(end 175.779507 94.647446)
		(width 0.114)
		(layer "In7.Cu")
		(net 254)
	)
	(arc
		(start 175.490052 95.19358)
		(mid 175.352832 95.52486)
		(end 175.490053 95.856139)
		(width 0.114)
		(layer "In7.Cu")
		(net 254)
	)
	(arc
		(start 176.698745 95.566684)
		(mid 176.751905 95.695024)
		(end 176.698745 95.823364)
		(width 0.114)
		(layer "In7.Cu")
		(net 254)
	)
	(arc
		(start 177.361303 96.485922)
		(mid 177.489643 96.432762)
		(end 177.617983 96.485922)
		(width 0.114)
		(layer "In7.Cu")
		(net 254)
	)
	(arc
		(start 178.537221 97.40516)
		(mid 178.590381 97.5335)
		(end 178.537221 97.66184)
		(width 0.114)
		(layer "In7.Cu")
		(net 254)
	)
	(arc
		(start 178.280541 97.40516)
		(mid 178.408881 97.352)
		(end 178.537221 97.40516)
		(width 0.114)
		(layer "In7.Cu")
		(net 254)
	)
	(arc
		(start 176.40929 96.775377)
		(mid 176.74057 96.912597)
		(end 177.071849 96.775376)
		(width 0.114)
		(layer "In7.Cu")
		(net 254)
	)
	(arc
		(start 177.617983 96.485922)
		(mid 177.671143 96.614262)
		(end 177.617983 96.742602)
		(width 0.114)
		(layer "In7.Cu")
		(net 254)
	)
	(arc
		(start 176.40929 96.112818)
		(mid 176.27207 96.444098)
		(end 176.409291 96.775377)
		(width 0.114)
		(layer "In7.Cu")
		(net 254)
	)
	(arc
		(start 178.247766 97.951294)
		(mid 178.110546 98.282574)
		(end 178.247767 98.613853)
		(width 0.114)
		(layer "In7.Cu")
		(net 254)
	)
	(arc
		(start 175.490052 95.856139)
		(mid 175.821332 95.993359)
		(end 176.152611 95.856138)
		(width 0.114)
		(layer "In7.Cu")
		(net 254)
	)
	(arc
		(start 173.651576 93.355104)
		(mid 173.514356 93.686384)
		(end 173.651577 94.017663)
		(width 0.114)
		(layer "In7.Cu")
		(net 254)
	)
	(arc
		(start 177.328528 97.694615)
		(mid 177.659808 97.831835)
		(end 177.991087 97.694614)
		(width 0.114)
		(layer "In7.Cu")
		(net 254)
	)
	(arc
		(start 175.779507 94.647446)
		(mid 175.832667 94.775786)
		(end 175.779507 94.904126)
		(width 0.114)
		(layer "In7.Cu")
		(net 254)
	)
	(arc
		(start 174.570814 94.274342)
		(mid 174.433594 94.605622)
		(end 174.570815 94.936901)
		(width 0.114)
		(layer "In7.Cu")
		(net 254)
	)
	(arc
		(start 174.603589 93.728208)
		(mid 174.731929 93.675048)
		(end 174.860269 93.728208)
		(width 0.114)
		(layer "In7.Cu")
		(net 254)
	)
	(arc
		(start 173.941031 92.80897)
		(mid 173.994191 92.93731)
		(end 173.941031 93.06565)
		(width 0.114)
		(layer "In7.Cu")
		(net 254)
	)
	(arc
		(start 179.199779 98.324398)
		(mid 179.328119 98.271238)
		(end 179.456459 98.324398)
		(width 0.114)
		(layer "In7.Cu")
		(net 254)
	)
	(arc
		(start 174.570814 94.936901)
		(mid 174.902094 95.074121)
		(end 175.233373 94.9369)
		(width 0.114)
		(layer "In7.Cu")
		(net 254)
	)
	(arc
		(start 176.442065 95.566684)
		(mid 176.570405 95.513524)
		(end 176.698745 95.566684)
		(width 0.114)
		(layer "In7.Cu")
		(net 254)
	)
	(arc
		(start 174.860269 93.728208)
		(mid 174.913429 93.856548)
		(end 174.860269 93.984888)
		(width 0.114)
		(layer "In7.Cu")
		(net 254)
	)
	(arc
		(start 178.247766 98.613853)
		(mid 178.579046 98.751073)
		(end 178.910325 98.613852)
		(width 0.114)
		(layer "In7.Cu")
		(net 254)
	)
	(arc
		(start 173.651576 94.017663)
		(mid 173.982856 94.154883)
		(end 174.314135 94.017662)
		(width 0.114)
		(layer "In7.Cu")
		(net 254)
	)
	(arc
		(start 177.328528 97.032056)
		(mid 177.191308 97.363336)
		(end 177.328529 97.694615)
		(width 0.114)
		(layer "In7.Cu")
		(net 254)
	)
	(segment
		(start 209.375 81.74)
		(end 209.45 81.665)
		(width 0.182)
		(layer "F.Cu")
		(net 257)
	)
	(segment
		(start 206.45 78.5)
		(end 208.22 78.5)
		(width 0.182)
		(layer "F.Cu")
		(net 257)
	)
	(segment
		(start 206 78.95)
		(end 206.45 78.5)
		(width 0.182)
		(layer "F.Cu")
		(net 257)
	)
	(segment
		(start 194.5 115.5)
		(end 194 115)
		(width 0.256)
		(layer "F.Cu")
		(net 257)
	)
	(segment
		(start 208.22 78.5)
		(end 209.45 79.73)
		(width 0.182)
		(layer "F.Cu")
		(net 257)
	)
	(segment
		(start 209.45 81.665)
		(end 209.45 79.73)
		(width 0.182)
		(layer "F.Cu")
		(net 257)
	)
	(via
		(at 194 115)
		(size 0.45)
		(drill 0.2)
		(layers "F.Cu" "B.Cu")
		(net 257)
	)
	(via
		(at 206 78.95)
		(size 0.45)
		(drill 0.2)
		(layers "F.Cu" "B.Cu")
		(net 257)
	)
	(via
		(at 247.925 141.45)
		(size 0.45)
		(drill 0.2)
		(layers "F.Cu" "B.Cu")
		(net 257)
	)
	(segment
		(start 243.275 144.65)
		(end 243.925 145.3)
		(width 0.1)
		(layer "B.Cu")
		(net 257)
	)
	(segment
		(start 247.775 141.6)
		(end 244.2 141.6)
		(width 0.1)
		(layer "B.Cu")
		(net 257)
	)
	(segment
		(start 243.925 145.3)
		(end 248.1 145.3)
		(width 0.1)
		(layer "B.Cu")
		(net 257)
	)
	(segment
		(start 248.5 145.7)
		(end 248.5 148.273)
		(width 0.1)
		(layer "B.Cu")
		(net 257)
	)
	(segment
		(start 247.925 141.45)
		(end 247.775 141.6)
		(width 0.1)
		(layer "B.Cu")
		(net 257)
	)
	(segment
		(start 244.2 141.6)
		(end 243.275 142.525)
		(width 0.1)
		(layer "B.Cu")
		(net 257)
	)
	(segment
		(start 248.1 145.3)
		(end 248.5 145.7)
		(width 0.1)
		(layer "B.Cu")
		(net 257)
	)
	(segment
		(start 243.275 142.525)
		(end 243.275 144.65)
		(width 0.1)
		(layer "B.Cu")
		(net 257)
	)
	(segment
		(start 194 114.4)
		(end 194 115)
		(width 0.1)
		(layer "In3.Cu")
		(net 257)
	)
	(segment
		(start 206 78.95)
		(end 205.25 79.7)
		(width 0.1)
		(layer "In3.Cu")
		(net 257)
	)
	(segment
		(start 262.4 74.5)
		(end 262.4 94.4)
		(width 0.1)
		(layer "In3.Cu")
		(net 257)
	)
	(segment
		(start 246.617158 139.8)
		(end 247.925 141.107842)
		(width 0.1)
		(layer "In3.Cu")
		(net 257)
	)
	(segment
		(start 262.4 94.4)
		(end 245.4 111.4)
		(width 0.1)
		(layer "In3.Cu")
		(net 257)
	)
	(segment
		(start 206 78.95)
		(end 206 76.834315)
		(width 0.1)
		(layer "In3.Cu")
		(net 257)
	)
	(segment
		(start 193.8 86.631368)
		(end 193.8 114.2)
		(width 0.1)
		(layer "In3.Cu")
		(net 257)
	)
	(segment
		(start 245.4 111.4)
		(end 245.4 138.6)
		(width 0.1)
		(layer "In3.Cu")
		(net 257)
	)
	(segment
		(start 194.6 85.831369)
		(end 193.8 86.631368)
		(width 0.1)
		(layer "In3.Cu")
		(net 257)
	)
	(segment
		(start 206 76.834315)
		(end 210.434315 72.4)
		(width 0.1)
		(layer "In3.Cu")
		(net 257)
	)
	(segment
		(start 205.25 79.7)
		(end 195.68 79.7)
		(width 0.1)
		(layer "In3.Cu")
		(net 257)
	)
	(segment
		(start 210.434315 72.4)
		(end 260.3 72.4)
		(width 0.1)
		(layer "In3.Cu")
		(net 257)
	)
	(segment
		(start 246.6 139.8)
		(end 246.617158 139.8)
		(width 0.1)
		(layer "In3.Cu")
		(net 257)
	)
	(segment
		(start 194.6 80.78)
		(end 194.6 85.831369)
		(width 0.1)
		(layer "In3.Cu")
		(net 257)
	)
	(segment
		(start 193.8 114.2)
		(end 194 114.4)
		(width 0.1)
		(layer "In3.Cu")
		(net 257)
	)
	(segment
		(start 260.3 72.4)
		(end 262.4 74.5)
		(width 0.1)
		(layer "In3.Cu")
		(net 257)
	)
	(segment
		(start 247.925 141.107842)
		(end 247.925 141.45)
		(width 0.1)
		(layer "In3.Cu")
		(net 257)
	)
	(segment
		(start 195.68 79.7)
		(end 194.6 80.78)
		(width 0.1)
		(layer "In3.Cu")
		(net 257)
	)
	(segment
		(start 245.4 138.6)
		(end 246.6 139.8)
		(width 0.1)
		(layer "In3.Cu")
		(net 257)
	)
	(segment
		(start 249.65 144.65)
		(end 249.7 144.6)
		(width 0.177)
		(layer "F.Cu")
		(net 260)
	)
	(segment
		(start 249.65 146.125)
		(end 249.65 144.65)
		(width 0.177)
		(layer "F.Cu")
		(net 260)
	)
	(segment
		(start 246.65 123.825)
		(end 246.65 122.45)
		(width 0.177)
		(layer "F.Cu")
		(net 265)
	)
	(segment
		(start 246.65 122.45)
		(end 246.8 122.3)
		(width 0.177)
		(layer "F.Cu")
		(net 265)
	)
	(segment
		(start 229.15 165.36)
		(end 229.15 166.25)
		(width 0.1)
		(layer "F.Cu")
		(net 267)
	)
	(segment
		(start 229.15 166.25)
		(end 229.2 166.3)
		(width 0.1)
		(layer "F.Cu")
		(net 267)
	)
	(via
		(at 229.2 166.3)
		(size 0.45)
		(drill 0.2)
		(layers "F.Cu" "B.Cu")
		(net 267)
	)
	(segment
		(start 229.2 166.3)
		(end 229.2 165.885)
		(width 0.1)
		(layer "B.Cu")
		(net 267)
	)
	(segment
		(start 156.606804 89.622001)
		(end 156.285001 89.943804)
		(width 0.16)
		(layer "F.Cu")
		(net 268)
	)
	(segment
		(start 156.285001 89.943804)
		(end 156.285001 90.125001)
		(width 0.16)
		(layer "F.Cu")
		(net 268)
	)
	(segment
		(start 156.775002 89.622002)
		(end 156.920001 89.767001)
		(width 0.16)
		(layer "F.Cu")
		(net 268)
	)
	(segment
		(start 195.5 119.5)
		(end 195 119)
		(width 0.256)
		(layer "F.Cu")
		(net 268)
	)
	(segment
		(start 156.775002 89.622002)
		(end 156.606804 89.622001)
		(width 0.16)
		(layer "F.Cu")
		(net 268)
	)
	(via
		(at 156.920001 89.767001)
		(size 0.45)
		(drill 0.2)
		(layers "F.Cu" "B.Cu")
		(net 268)
	)
	(via
		(at 195 119)
		(size 0.45)
		(drill 0.2)
		(layers "F.Cu" "B.Cu")
		(net 268)
	)
	(segment
		(start 156.920001 89.767001)
		(end 157.053501 89.633501)
		(width 0.114)
		(layer "In7.Cu")
		(net 268)
	)
	(segment
		(start 172.205001 90.531788)
		(end 172.205001 89.394927)
		(width 0.114)
		(layer "In7.Cu")
		(net 268)
	)
	(segment
		(start 157.340561 89.633501)
		(end 157.980561 90.273501)
		(width 0.114)
		(layer "In7.Cu")
		(net 268)
	)
	(segment
		(start 195.400001 119.400001)
		(end 195.608579 119.400001)
		(width 0.1)
		(layer "In7.Cu")
		(net 268)
	)
	(segment
		(start 159.427501 90.498501)
		(end 159.427501 90.600866)
		(width 0.114)
		(layer "In7.Cu")
		(net 268)
	)
	(segment
		(start 173.770561 90.273501)
		(end 196.356501 112.859441)
		(width 0.114)
		(layer "In7.Cu")
		(net 268)
	)
	(segment
		(start 157.980561 90.273501)
		(end 159.202501 90.273501)
		(width 0.114)
		(layer "In7.Cu")
		(net 268)
	)
	(segment
		(start 161.002501 90.273501)
		(end 161.052501 90.273501)
		(width 0.114)
		(layer "In7.Cu")
		(net 268)
	)
	(segment
		(start 196.608579 118.400001)
		(end 197.188579 118.400001)
		(width 0.1)
		(layer "In7.Cu")
		(net 268)
	)
	(segment
		(start 160.777501 90.600866)
		(end 160.777501 90.498501)
		(width 0.114)
		(layer "In7.Cu")
		(net 268)
	)
	(segment
		(start 195.608579 119.400001)
		(end 196.608579 118.400001)
		(width 0.1)
		(layer "In7.Cu")
		(net 268)
	)
	(segment
		(start 197.163579 115.600001)
		(end 196.753579 115.600001)
		(width 0.1)
		(layer "In7.Cu")
		(net 268)
	)
	(segment
		(start 159.877501 90.600866)
		(end 159.877501 90.498501)
		(width 0.114)
		(layer "In7.Cu")
		(net 268)
	)
	(segment
		(start 157.053501 89.633501)
		(end 157.340561 89.633501)
		(width 0.114)
		(layer "In7.Cu")
		(net 268)
	)
	(segment
		(start 170.905001 89.805001)
		(end 170.905001 89.394927)
		(width 0.114)
		(layer "In7.Cu")
		(net 268)
	)
	(segment
		(start 161.052501 90.273501)
		(end 170.436501 90.273501)
		(width 0.114)
		(layer "In7.Cu")
		(net 268)
	)
	(segment
		(start 196.356501 112.859441)
		(end 196.356501 113.405001)
		(width 0.114)
		(layer "In7.Cu")
		(net 268)
	)
	(segment
		(start 173.036501 90.273501)
		(end 173.770561 90.273501)
		(width 0.114)
		(layer "In7.Cu")
		(net 268)
	)
	(segment
		(start 196.400001 115.246423)
		(end 196.400001 113.448501)
		(width 0.1)
		(layer "In7.Cu")
		(net 268)
	)
	(segment
		(start 195.000001 119.000001)
		(end 195.400001 119.400001)
		(width 0.1)
		(layer "In7.Cu")
		(net 268)
	)
	(segment
		(start 171.268001 89.394927)
		(end 171.268001 90.531788)
		(width 0.114)
		(layer "In7.Cu")
		(net 268)
	)
	(segment
		(start 196.400001 113.448501)
		(end 196.356501 113.405001)
		(width 0.1)
		(layer "In7.Cu")
		(net 268)
	)
	(segment
		(start 196.753579 115.600001)
		(end 196.400001 115.246423)
		(width 0.1)
		(layer "In7.Cu")
		(net 268)
	)
	(segment
		(start 197.400001 115.836423)
		(end 197.163579 115.600001)
		(width 0.1)
		(layer "In7.Cu")
		(net 268)
	)
	(segment
		(start 172.568001 89.394927)
		(end 172.568001 89.805001)
		(width 0.114)
		(layer "In7.Cu")
		(net 268)
	)
	(segment
		(start 197.400001 118.188579)
		(end 197.400001 115.836423)
		(width 0.1)
		(layer "In7.Cu")
		(net 268)
	)
	(segment
		(start 197.188579 118.400001)
		(end 197.400001 118.188579)
		(width 0.1)
		(layer "In7.Cu")
		(net 268)
	)
	(segment
		(start 171.669788 90.933575)
		(end 171.803214 90.933575)
		(width 0.114)
		(layer "In7.Cu")
		(net 268)
	)
	(segment
		(start 160.327501 90.498501)
		(end 160.327501 90.600866)
		(width 0.114)
		(layer "In7.Cu")
		(net 268)
	)
	(arc
		(start 172.386501 89.213427)
		(mid 172.514841 89.266587)
		(end 172.568001 89.394927)
		(width 0.114)
		(layer "In7.Cu")
		(net 268)
	)
	(arc
		(start 172.568001 89.805001)
		(mid 172.705221 90.136281)
		(end 173.036501 90.273501)
		(width 0.114)
		(layer "In7.Cu")
		(net 268)
	)
	(arc
		(start 171.086501 89.213427)
		(mid 171.214841 89.266587)
		(end 171.268001 89.394927)
		(width 0.114)
		(layer "In7.Cu")
		(net 268)
	)
	(arc
		(start 160.327501 90.600866)
		(mid 160.393402 90.759965)
		(end 160.552501 90.825866)
		(width 0.114)
		(layer "In7.Cu")
		(net 268)
	)
	(arc
		(start 159.427501 90.600866)
		(mid 159.493402 90.759965)
		(end 159.652501 90.825866)
		(width 0.114)
		(layer "In7.Cu")
		(net 268)
	)
	(arc
		(start 159.202501 90.273501)
		(mid 159.3616 90.339402)
		(end 159.427501 90.498501)
		(width 0.114)
		(layer "In7.Cu")
		(net 268)
	)
	(arc
		(start 159.652501 90.825866)
		(mid 159.8116 90.759965)
		(end 159.877501 90.600866)
		(width 0.114)
		(layer "In7.Cu")
		(net 268)
	)
	(arc
		(start 160.102501 90.273501)
		(mid 160.2616 90.339402)
		(end 160.327501 90.498501)
		(width 0.114)
		(layer "In7.Cu")
		(net 268)
	)
	(arc
		(start 160.777501 90.498501)
		(mid 160.843402 90.339402)
		(end 161.002501 90.273501)
		(width 0.114)
		(layer "In7.Cu")
		(net 268)
	)
	(arc
		(start 170.905001 89.394927)
		(mid 170.958161 89.266587)
		(end 171.086501 89.213427)
		(width 0.114)
		(layer "In7.Cu")
		(net 268)
	)
	(arc
		(start 170.436501 90.273501)
		(mid 170.767781 90.136281)
		(end 170.905001 89.805001)
		(width 0.114)
		(layer "In7.Cu")
		(net 268)
	)
	(arc
		(start 172.205001 89.394927)
		(mid 172.258161 89.266587)
		(end 172.386501 89.213427)
		(width 0.114)
		(layer "In7.Cu")
		(net 268)
	)
	(arc
		(start 159.877501 90.498501)
		(mid 159.943402 90.339402)
		(end 160.102501 90.273501)
		(width 0.114)
		(layer "In7.Cu")
		(net 268)
	)
	(arc
		(start 160.552501 90.825866)
		(mid 160.7116 90.759965)
		(end 160.777501 90.600866)
		(width 0.114)
		(layer "In7.Cu")
		(net 268)
	)
	(arc
		(start 171.268001 90.531788)
		(mid 171.385682 90.815894)
		(end 171.669788 90.933575)
		(width 0.114)
		(layer "In7.Cu")
		(net 268)
	)
	(arc
		(start 171.803214 90.933575)
		(mid 172.08732 90.815894)
		(end 172.205001 90.531788)
		(width 0.114)
		(layer "In7.Cu")
		(net 268)
	)
	(segment
		(start 251.15 127.775)
		(end 251.150001 128.827929)
		(width 0.1)
		(layer "F.Cu")
		(net 276)
	)
	(via
		(at 251.150001 128.827929)
		(size 0.45)
		(drill 0.2)
		(layers "F.Cu" "B.Cu")
		(net 276)
	)
	(segment
		(start 251.150001 128.827929)
		(end 251.150001 128.349999)
		(width 0.177)
		(layer "B.Cu")
		(net 276)
	)
	(segment
		(start 251.150001 128.349999)
		(end 251.3 128.2)
		(width 0.177)
		(layer "B.Cu")
		(net 276)
	)
	(segment
		(start 156.775002 89.358)
		(end 156.606804 89.358001)
		(width 0.16)
		(layer "F.Cu")
		(net 278)
	)
	(segment
		(start 156.285001 89.036198)
		(end 156.606804 89.358001)
		(width 0.16)
		(layer "F.Cu")
		(net 278)
	)
	(segment
		(start 156.285001 88.855001)
		(end 156.285001 89.036198)
		(width 0.16)
		(layer "F.Cu")
		(net 278)
	)
	(segment
		(start 156.775002 89.358)
		(end 156.920001 89.213001)
		(width 0.16)
		(layer "F.Cu")
		(net 278)
	)
	(segment
		(start 195.5 120.5)
		(end 195 120)
		(width 0.256)
		(layer "F.Cu")
		(net 278)
	)
	(via
		(at 156.920001 89.213001)
		(size 0.45)
		(drill 0.2)
		(layers "F.Cu" "B.Cu")
		(net 278)
	)
	(via
		(at 195 120)
		(size 0.45)
		(drill 0.2)
		(layers "F.Cu" "B.Cu")
		(net 278)
	)
	(segment
		(start 197.246423 115.400001)
		(end 196.836423 115.400001)
		(width 0.1)
		(layer "In7.Cu")
		(net 278)
	)
	(segment
		(start 197.271423 118.600001)
		(end 197.600001 118.271423)
		(width 0.1)
		(layer "In7.Cu")
		(net 278)
	)
	(segment
		(start 157.053501 89.346501)
		(end 157.459441 89.346501)
		(width 0.114)
		(layer "In7.Cu")
		(net 278)
	)
	(segment
		(start 173.889441 89.986501)
		(end 196.643501 112.740561)
		(width 0.114)
		(layer "In7.Cu")
		(net 278)
	)
	(segment
		(start 197.600001 115.753579)
		(end 197.246423 115.400001)
		(width 0.1)
		(layer "In7.Cu")
		(net 278)
	)
	(segment
		(start 195.400001 119.600001)
		(end 195.691423 119.600001)
		(width 0.1)
		(layer "In7.Cu")
		(net 278)
	)
	(segment
		(start 196.600001 115.163579)
		(end 196.600001 113.448501)
		(width 0.1)
		(layer "In7.Cu")
		(net 278)
	)
	(segment
		(start 171.918001 90.531788)
		(end 171.918001 89.394927)
		(width 0.114)
		(layer "In7.Cu")
		(net 278)
	)
	(segment
		(start 196.836423 115.400001)
		(end 196.600001 115.163579)
		(width 0.1)
		(layer "In7.Cu")
		(net 278)
	)
	(segment
		(start 171.555001 89.394927)
		(end 171.555001 90.531788)
		(width 0.114)
		(layer "In7.Cu")
		(net 278)
	)
	(segment
		(start 196.643501 112.740561)
		(end 196.643501 113.405001)
		(width 0.114)
		(layer "In7.Cu")
		(net 278)
	)
	(segment
		(start 156.920001 89.213001)
		(end 157.053501 89.346501)
		(width 0.114)
		(layer "In7.Cu")
		(net 278)
	)
	(segment
		(start 171.669788 90.646575)
		(end 171.803214 90.646575)
		(width 0.114)
		(layer "In7.Cu")
		(net 278)
	)
	(segment
		(start 172.855001 89.394927)
		(end 172.855001 89.805001)
		(width 0.114)
		(layer "In7.Cu")
		(net 278)
	)
	(segment
		(start 195.691423 119.600001)
		(end 196.691423 118.600001)
		(width 0.1)
		(layer "In7.Cu")
		(net 278)
	)
	(segment
		(start 170.618001 89.805001)
		(end 170.618001 89.394927)
		(width 0.114)
		(layer "In7.Cu")
		(net 278)
	)
	(segment
		(start 197.600001 118.271423)
		(end 197.600001 115.753579)
		(width 0.1)
		(layer "In7.Cu")
		(net 278)
	)
	(segment
		(start 195.000001 120.000001)
		(end 195.400001 119.600001)
		(width 0.1)
		(layer "In7.Cu")
		(net 278)
	)
	(segment
		(start 173.036501 89.986501)
		(end 173.889441 89.986501)
		(width 0.114)
		(layer "In7.Cu")
		(net 278)
	)
	(segment
		(start 158.099441 89.986501)
		(end 170.436501 89.986501)
		(width 0.114)
		(layer "In7.Cu")
		(net 278)
	)
	(segment
		(start 196.600001 113.448501)
		(end 196.643501 113.405001)
		(width 0.1)
		(layer "In7.Cu")
		(net 278)
	)
	(segment
		(start 157.459441 89.346501)
		(end 158.099441 89.986501)
		(width 0.114)
		(layer "In7.Cu")
		(net 278)
	)
	(segment
		(start 196.691423 118.600001)
		(end 197.271423 118.600001)
		(width 0.1)
		(layer "In7.Cu")
		(net 278)
	)
	(arc
		(start 172.386501 88.926427)
		(mid 172.717781 89.063647)
		(end 172.855001 89.394927)
		(width 0.114)
		(layer "In7.Cu")
		(net 278)
	)
	(arc
		(start 170.618001 89.394927)
		(mid 170.755221 89.063647)
		(end 171.086501 88.926427)
		(width 0.114)
		(layer "In7.Cu")
		(net 278)
	)
	(arc
		(start 171.803214 90.646575)
		(mid 171.884381 90.612955)
		(end 171.918001 90.531788)
		(width 0.114)
		(layer "In7.Cu")
		(net 278)
	)
	(arc
		(start 171.918001 89.394927)
		(mid 172.055221 89.063647)
		(end 172.386501 88.926427)
		(width 0.114)
		(layer "In7.Cu")
		(net 278)
	)
	(arc
		(start 171.086501 88.926427)
		(mid 171.417781 89.063647)
		(end 171.555001 89.394927)
		(width 0.114)
		(layer "In7.Cu")
		(net 278)
	)
	(arc
		(start 172.855001 89.805001)
		(mid 172.908161 89.933341)
		(end 173.036501 89.986501)
		(width 0.114)
		(layer "In7.Cu")
		(net 278)
	)
	(arc
		(start 170.436501 89.986501)
		(mid 170.564841 89.933341)
		(end 170.618001 89.805001)
		(width 0.114)
		(layer "In7.Cu")
		(net 278)
	)
	(arc
		(start 171.555001 90.531788)
		(mid 171.588621 90.612955)
		(end 171.669788 90.646575)
		(width 0.114)
		(layer "In7.Cu")
		(net 278)
	)
	(segment
		(start 158.5 184.01)
		(end 158.995 183.515)
		(width 0.1)
		(layer "F.Cu")
		(net 279)
	)
	(segment
		(start 158.5 184.883)
		(end 158.5 184.01)
		(width 0.1)
		(layer "F.Cu")
		(net 279)
	)
	(segment
		(start 158.995 183.515)
		(end 159 183.515)
		(width 0.1)
		(layer "F.Cu")
		(net 279)
	)
	(segment
		(start 171.018636 119.834019)
		(end 171.194706 119.834019)
		(width 0.201)
		(layer "F.Cu")
		(net 282)
	)
	(segment
		(start 187.899399 129.220821)
		(end 187.778579 129.100001)
		(width 0.1)
		(layer "F.Cu")
		(net 282)
	)
	(segment
		(start 187.830001 129.500002)
		(end 187.899399 129.430603)
		(width 0.1)
		(layer "F.Cu")
		(net 282)
	)
	(segment
		(start 186.861001 129.27215)
		(end 186.861001 129.225001)
		(width 0.1)
		(layer "F.Cu")
		(net 282)
	)
	(segment
		(start 178.156951 120.200501)
		(end 179.219501 121.263051)
		(width 0.201)
		(layer "F.Cu")
		(net 282)
	)
	(segment
		(start 187.500001 129.500001)
		(end 187.830001 129.500002)
		(width 0.1)
		(layer "F.Cu")
		(net 282)
	)
	(segment
		(start 187.778579 129.100001)
		(end 187.236001 129.100001)
		(width 0.1)
		(layer "F.Cu")
		(net 282)
	)
	(segment
		(start 187.899399 129.430603)
		(end 187.899399 129.220821)
		(width 0.1)
		(layer "F.Cu")
		(net 282)
	)
	(segment
		(start 165.665002 88.352002)
		(end 165.810001 88.497001)
		(width 0.16)
		(layer "F.Cu")
		(net 282)
	)
	(segment
		(start 179.219501 121.263051)
		(end 179.219501 127.533051)
		(width 0.201)
		(layer "F.Cu")
		(net 282)
	)
	(segment
		(start 187.111001 129.225001)
		(end 187.111001 129.27215)
		(width 0.1)
		(layer "F.Cu")
		(net 282)
	)
	(segment
		(start 171.561188 120.200501)
		(end 178.156951 120.200501)
		(width 0.201)
		(layer "F.Cu")
		(net 282)
	)
	(segment
		(start 186.736001 129.100001)
		(end 186.686001 129.100001)
		(width 0.1)
		(layer "F.Cu")
		(net 282)
	)
	(segment
		(start 171.194706 119.834019)
		(end 171.561188 120.200501)
		(width 0.201)
		(layer "F.Cu")
		(net 282)
	)
	(segment
		(start 186.686001 129.100001)
		(end 183.446376 129.100001)
		(width 0.1)
		(layer "F.Cu")
		(net 282)
	)
	(segment
		(start 183.446376 129.100001)
		(end 183.346376 129.200001)
		(width 0.1)
		(layer "F.Cu")
		(net 282)
	)
	(segment
		(start 165.665002 88.352002)
		(end 165.496804 88.352001)
		(width 0.16)
		(layer "F.Cu")
		(net 282)
	)
	(segment
		(start 165.496804 88.352001)
		(end 165.175001 88.673804)
		(width 0.16)
		(layer "F.Cu")
		(net 282)
	)
	(segment
		(start 180.886451 129.200001)
		(end 183.346376 129.200001)
		(width 0.201)
		(layer "F.Cu")
		(net 282)
	)
	(segment
		(start 179.219501 127.533051)
		(end 180.886451 129.200001)
		(width 0.201)
		(layer "F.Cu")
		(net 282)
	)
	(segment
		(start 165.175001 88.673804)
		(end 165.175001 88.855001)
		(width 0.16)
		(layer "F.Cu")
		(net 282)
	)
	(via
		(at 171.018636 119.834019)
		(size 0.45)
		(drill 0.2)
		(layers "F.Cu" "B.Cu")
		(net 282)
	)
	(via
		(at 165.810001 88.497001)
		(size 0.45)
		(drill 0.2)
		(layers "F.Cu" "B.Cu")
		(net 282)
	)
	(arc
		(start 187.236001 129.100001)
		(mid 187.147613 129.136613)
		(end 187.111001 129.225001)
		(width 0.1)
		(layer "F.Cu")
		(net 282)
	)
	(arc
		(start 186.861001 129.225001)
		(mid 186.824389 129.136613)
		(end 186.736001 129.100001)
		(width 0.1)
		(layer "F.Cu")
		(net 282)
	)
	(arc
		(start 187.111001 129.27215)
		(mid 187.074389 129.360538)
		(end 186.986001 129.39715)
		(width 0.1)
		(layer "F.Cu")
		(net 282)
	)
	(arc
		(start 186.986001 129.39715)
		(mid 186.897613 129.360538)
		(end 186.861001 129.27215)
		(width 0.1)
		(layer "F.Cu")
		(net 282)
	)
	(segment
		(start 165.886501 88.420501)
		(end 165.810001 88.497001)
		(width 0.201)
		(layer "B.Cu")
		(net 282)
	)
	(segment
		(start 170.119501 89.349501)
		(end 169.190501 88.420501)
		(width 0.201)
		(layer "B.Cu")
		(net 282)
	)
	(segment
		(start 169.190501 88.420501)
		(end 165.886501 88.420501)
		(width 0.201)
		(layer "B.Cu")
		(net 282)
	)
	(segment
		(start 171.018636 119.657949)
		(end 170.119501 118.758814)
		(width 0.201)
		(layer "B.Cu")
		(net 282)
	)
	(segment
		(start 171.018636 119.834019)
		(end 171.018636 119.657949)
		(width 0.201)
		(layer "B.Cu")
		(net 282)
	)
	(segment
		(start 170.119501 118.758814)
		(end 170.119501 89.349501)
		(width 0.201)
		(layer "B.Cu")
		(net 282)
	)
	(segment
		(start 170.504001 88.352001)
		(end 168.218 88.352002)
		(width 0.16)
		(layer "F.Cu")
		(net 283)
	)
	(segment
		(start 167.715001 88.855001)
		(end 168.218 88.352002)
		(width 0.16)
		(layer "F.Cu")
		(net 283)
	)
	(segment
		(start 177.583051 88.420501)
		(end 170.572501 88.420501)
		(width 0.201)
		(layer "F.Cu")
		(net 283)
	)
	(segment
		(start 178.253051 87.750501)
		(end 177.583051 88.420501)
		(width 0.201)
		(layer "F.Cu")
		(net 283)
	)
	(segment
		(start 170.504001 88.352001)
		(end 170.572501 88.420501)
		(width 0.16)
		(layer "F.Cu")
		(net 283)
	)
	(segment
		(start 179.290001 87.875001)
		(end 179.1655 87.750501)
		(width 0.201)
		(layer "F.Cu")
		(net 283)
	)
	(segment
		(start 179.1655 87.750501)
		(end 178.253051 87.750501)
		(width 0.201)
		(layer "F.Cu")
		(net 283)
	)
	(via
		(at 179.290001 87.875001)
		(size 0.45)
		(drill 0.2)
		(layers "F.Cu" "B.Cu")
		(net 283)
	)
	(via
		(at 189.5 126.5)
		(size 0.45)
		(drill 0.2)
		(layers "F.Cu" "B.Cu")
		(net 283)
	)
	(segment
		(start 189.8994 126.430604)
		(end 189.8994 126.220821)
		(width 0.1)
		(layer "B.Cu")
		(net 283)
	)
	(segment
		(start 186.741002 126.289444)
		(end 186.741002 126.275002)
		(width 0.1)
		(layer "B.Cu")
		(net 283)
	)
	(segment
		(start 184.5095 126.1005)
		(end 184.4095 126.2005)
		(width 0.1)
		(layer "B.Cu")
		(net 283)
	)
	(segment
		(start 186.391002 126.275002)
		(end 186.391002 126.289444)
		(width 0.1)
		(layer "B.Cu")
		(net 283)
	)
	(segment
		(start 184.5095 126.1005)
		(end 185.865504 126.1005)
		(width 0.1)
		(layer "B.Cu")
		(net 283)
	)
	(segment
		(start 179.414502 87.750501)
		(end 180.256951 87.750501)
		(width 0.201)
		(layer "B.Cu")
		(net 283)
	)
	(segment
		(start 186.041002 126.289444)
		(end 186.041002 126.275002)
		(width 0.1)
		(layer "B.Cu")
		(net 283)
	)
	(segment
		(start 189.830002 126.500001)
		(end 189.8994 126.430604)
		(width 0.1)
		(layer "B.Cu")
		(net 283)
	)
	(segment
		(start 183.1195 125.62305)
		(end 183.69695 126.2005)
		(width 0.201)
		(layer "B.Cu")
		(net 283)
	)
	(segment
		(start 185.865504 126.1005)
		(end 185.866002 126.100002)
		(width 0.1)
		(layer "B.Cu")
		(net 283)
	)
	(segment
		(start 189.77858 126.100002)
		(end 187.266002 126.100002)
		(width 0.1)
		(layer "B.Cu")
		(net 283)
	)
	(segment
		(start 183.1195 90.61305)
		(end 183.1195 125.62305)
		(width 0.201)
		(layer "B.Cu")
		(net 283)
	)
	(segment
		(start 183.69695 126.2005)
		(end 184.4095 126.2005)
		(width 0.201)
		(layer "B.Cu")
		(net 283)
	)
	(segment
		(start 180.256951 87.750501)
		(end 183.1195 90.61305)
		(width 0.201)
		(layer "B.Cu")
		(net 283)
	)
	(segment
		(start 189.500001 126.500001)
		(end 189.830002 126.500001)
		(width 0.1)
		(layer "B.Cu")
		(net 283)
	)
	(segment
		(start 187.091002 126.275002)
		(end 187.091002 126.289444)
		(width 0.1)
		(layer "B.Cu")
		(net 283)
	)
	(segment
		(start 179.290001 87.875001)
		(end 179.414502 87.750501)
		(width 0.201)
		(layer "B.Cu")
		(net 283)
	)
	(segment
		(start 189.8994 126.220821)
		(end 189.77858 126.100002)
		(width 0.1)
		(layer "B.Cu")
		(net 283)
	)
	(arc
		(start 186.916002 126.464444)
		(mid 186.792258 126.413188)
		(end 186.741002 126.289444)
		(width 0.1)
		(layer "B.Cu")
		(net 283)
	)
	(arc
		(start 186.041002 126.275002)
		(mid 185.989746 126.151258)
		(end 185.866002 126.100002)
		(width 0.1)
		(layer "B.Cu")
		(net 283)
	)
	(arc
		(start 187.091002 126.289444)
		(mid 187.039746 126.413188)
		(end 186.916002 126.464444)
		(width 0.1)
		(layer "B.Cu")
		(net 283)
	)
	(arc
		(start 186.566002 126.100002)
		(mid 186.442258 126.151258)
		(end 186.391002 126.275002)
		(width 0.1)
		(layer "B.Cu")
		(net 283)
	)
	(arc
		(start 186.391002 126.289444)
		(mid 186.339746 126.413188)
		(end 186.216002 126.464444)
		(width 0.1)
		(layer "B.Cu")
		(net 283)
	)
	(arc
		(start 186.216002 126.464444)
		(mid 186.092258 126.413188)
		(end 186.041002 126.289444)
		(width 0.1)
		(layer "B.Cu")
		(net 283)
	)
	(arc
		(start 186.741002 126.275002)
		(mid 186.689746 126.151258)
		(end 186.566002 126.100002)
		(width 0.1)
		(layer "B.Cu")
		(net 283)
	)
	(arc
		(start 187.266002 126.100002)
		(mid 187.142258 126.151258)
		(end 187.091002 126.275002)
		(width 0.1)
		(layer "B.Cu")
		(net 283)
	)
	(segment
		(start 188.500001 129.500001)
		(end 188.210001 129.500001)
		(width 0.1)
		(layer "F.Cu")
		(net 287)
	)
	(segment
		(start 188.099399 129.137977)
		(end 187.861423 128.900001)
		(width 0.1)
		(layer "F.Cu")
		(net 287)
	)
	(segment
		(start 165.175001 87.766198)
		(end 165.496804 88.088001)
		(width 0.16)
		(layer "F.Cu")
		(net 287)
	)
	(segment
		(start 178.323051 119.799501)
		(end 179.620501 121.096951)
		(width 0.201)
		(layer "F.Cu")
		(net 287)
	)
	(segment
		(start 171.478256 119.374399)
		(end 171.478256 119.550469)
		(width 0.201)
		(layer "F.Cu")
		(net 287)
	)
	(segment
		(start 187.861423 128.900001)
		(end 183.446376 128.900001)
		(width 0.1)
		(layer "F.Cu")
		(net 287)
	)
	(segment
		(start 181.052551 128.799001)
		(end 183.345376 128.799001)
		(width 0.201)
		(layer "F.Cu")
		(net 287)
	)
	(segment
		(start 188.210001 129.500001)
		(end 188.099399 129.389399)
		(width 0.1)
		(layer "F.Cu")
		(net 287)
	)
	(segment
		(start 165.665002 88.088)
		(end 165.496804 88.088001)
		(width 0.16)
		(layer "F.Cu")
		(net 287)
	)
	(segment
		(start 171.478256 119.550469)
		(end 171.727288 119.799501)
		(width 0.201)
		(layer "F.Cu")
		(net 287)
	)
	(segment
		(start 179.620501 121.096951)
		(end 179.620501 127.366951)
		(width 0.201)
		(layer "F.Cu")
		(net 287)
	)
	(segment
		(start 165.175001 87.585001)
		(end 165.175001 87.766198)
		(width 0.16)
		(layer "F.Cu")
		(net 287)
	)
	(segment
		(start 188.099399 129.389399)
		(end 188.099399 129.137977)
		(width 0.1)
		(layer "F.Cu")
		(net 287)
	)
	(segment
		(start 171.727288 119.799501)
		(end 178.323051 119.799501)
		(width 0.201)
		(layer "F.Cu")
		(net 287)
	)
	(segment
		(start 165.665002 88.088)
		(end 165.810001 87.943001)
		(width 0.16)
		(layer "F.Cu")
		(net 287)
	)
	(segment
		(start 179.620501 127.366951)
		(end 181.052551 128.799001)
		(width 0.201)
		(layer "F.Cu")
		(net 287)
	)
	(segment
		(start 183.446376 128.900001)
		(end 183.345376 128.799001)
		(width 0.1)
		(layer "F.Cu")
		(net 287)
	)
	(via
		(at 165.810001 87.943001)
		(size 0.45)
		(drill 0.2)
		(layers "F.Cu" "B.Cu")
		(net 287)
	)
	(via
		(at 171.478256 119.374399)
		(size 0.45)
		(drill 0.2)
		(layers "F.Cu" "B.Cu")
		(net 287)
	)
	(segment
		(start 170.520501 118.592714)
		(end 170.520501 89.190501)
		(width 0.201)
		(layer "B.Cu")
		(net 287)
	)
	(segment
		(start 171.302186 119.374399)
		(end 170.520501 118.592714)
		(width 0.201)
		(layer "B.Cu")
		(net 287)
	)
	(segment
		(start 171.478256 119.374399)
		(end 171.302186 119.374399)
		(width 0.201)
		(layer "B.Cu")
		(net 287)
	)
	(segment
		(start 165.886501 88.019501)
		(end 165.810001 87.943001)
		(width 0.201)
		(layer "B.Cu")
		(net 287)
	)
	(segment
		(start 169.349501 88.019501)
		(end 165.886501 88.019501)
		(width 0.201)
		(layer "B.Cu")
		(net 287)
	)
	(segment
		(start 170.520501 89.190501)
		(end 169.349501 88.019501)
		(width 0.201)
		(layer "B.Cu")
		(net 287)
	)
	(segment
		(start 170.504001 88.088001)
		(end 168.218 88.088)
		(width 0.16)
		(layer "F.Cu")
		(net 288)
	)
	(segment
		(start 177.416951 88.019501)
		(end 170.572501 88.019501)
		(width 0.201)
		(layer "F.Cu")
		(net 288)
	)
	(segment
		(start 179.290001 87.225)
		(end 179.1655 87.349501)
		(width 0.201)
		(layer "F.Cu")
		(net 288)
	)
	(segment
		(start 170.504001 88.088001)
		(end 170.572501 88.019501)
		(width 0.16)
		(layer "F.Cu")
		(net 288)
	)
	(segment
		(start 179.1655 87.349501)
		(end 178.086951 87.349501)
		(width 0.201)
		(layer "F.Cu")
		(net 288)
	)
	(segment
		(start 167.715001 87.585001)
		(end 168.218 88.088)
		(width 0.16)
		(layer "F.Cu")
		(net 288)
	)
	(segment
		(start 178.086951 87.349501)
		(end 177.416951 88.019501)
		(width 0.201)
		(layer "F.Cu")
		(net 288)
	)
	(via
		(at 179.290001 87.225)
		(size 0.45)
		(drill 0.2)
		(layers "F.Cu" "B.Cu")
		(net 288)
	)
	(via
		(at 190.5 126.5)
		(size 0.45)
		(drill 0.2)
		(layers "F.Cu" "B.Cu")
		(net 288)
	)
	(segment
		(start 190.099399 126.389399)
		(end 190.0994 126.137977)
		(width 0.1)
		(layer "B.Cu")
		(net 288)
	)
	(segment
		(start 190.500001 126.500001)
		(end 190.210001 126.500001)
		(width 0.1)
		(layer "B.Cu")
		(net 288)
	)
	(segment
		(start 183.5205 125.45695)
		(end 183.86305 125.7995)
		(width 0.201)
		(layer "B.Cu")
		(net 288)
	)
	(segment
		(start 184.510001 125.900001)
		(end 184.4095 125.7995)
		(width 0.1)
		(layer "B.Cu")
		(net 288)
	)
	(segment
		(start 179.290001 87.225)
		(end 179.414502 87.349501)
		(width 0.201)
		(layer "B.Cu")
		(net 288)
	)
	(segment
		(start 190.0994 126.137977)
		(end 189.861424 125.900001)
		(width 0.1)
		(layer "B.Cu")
		(net 288)
	)
	(segment
		(start 183.5205 90.44695)
		(end 183.5205 125.45695)
		(width 0.201)
		(layer "B.Cu")
		(net 288)
	)
	(segment
		(start 183.86305 125.7995)
		(end 184.4095 125.7995)
		(width 0.201)
		(layer "B.Cu")
		(net 288)
	)
	(segment
		(start 179.414502 87.349501)
		(end 180.423051 87.349501)
		(width 0.201)
		(layer "B.Cu")
		(net 288)
	)
	(segment
		(start 180.423051 87.349501)
		(end 183.5205 90.44695)
		(width 0.201)
		(layer "B.Cu")
		(net 288)
	)
	(segment
		(start 189.861424 125.900001)
		(end 184.510001 125.900001)
		(width 0.1)
		(layer "B.Cu")
		(net 288)
	)
	(segment
		(start 190.210001 126.500001)
		(end 190.099399 126.389399)
		(width 0.1)
		(layer "B.Cu")
		(net 288)
	)
	(segment
		(start 185.075 136.025)
		(end 185.5 136.45)
		(width 0.256)
		(layer "F.Cu")
		(net 298)
	)
	(segment
		(start 185.5 136.45)
		(end 185.5 136.5)
		(width 0.1)
		(layer "F.Cu")
		(net 298)
	)
	(via
		(at 204.101 77.183)
		(size 0.45)
		(drill 0.2)
		(layers "F.Cu" "B.Cu")
		(net 298)
	)
	(via
		(at 250.7 147.7)
		(size 0.45)
		(drill 0.2)
		(layers "F.Cu" "B.Cu")
		(net 298)
	)
	(via
		(at 185.075 136.025)
		(size 0.45)
		(drill 0.2)
		(layers "F.Cu" "B.Cu")
		(net 298)
	)
	(segment
		(start 251.7 147.675)
		(end 251.575 147.55)
		(width 0.1)
		(layer "B.Cu")
		(net 298)
	)
	(segment
		(start 204.101 77.183)
		(end 204.101 74.718)
		(width 0.1)
		(layer "B.Cu")
		(net 298)
	)
	(segment
		(start 251.7 148.273)
		(end 251.7 147.675)
		(width 0.1)
		(layer "B.Cu")
		(net 298)
	)
	(segment
		(start 251.575 147.55)
		(end 250.85 147.55)
		(width 0.1)
		(layer "B.Cu")
		(net 298)
	)
	(segment
		(start 250.85 147.55)
		(end 250.7 147.7)
		(width 0.1)
		(layer "B.Cu")
		(net 298)
	)
	(segment
		(start 250.7 147.9)
		(end 251.05 148.25)
		(width 0.1)
		(layer "In3.Cu")
		(net 298)
	)
	(segment
		(start 185.075 136.025)
		(end 185.075 136.125)
		(width 0.1)
		(layer "In3.Cu")
		(net 298)
	)
	(segment
		(start 263 94.7)
		(end 263 74.2)
		(width 0.1)
		(layer "In3.Cu")
		(net 298)
	)
	(segment
		(start 253 143.625)
		(end 252.875 143.75)
		(width 0.1)
		(layer "In3.Cu")
		(net 298)
	)
	(segment
		(start 252.05 149.2)
		(end 255.2 149.2)
		(width 0.1)
		(layer "In3.Cu")
		(net 298)
	)
	(segment
		(start 184.65 136.55)
		(end 183.15 136.55)
		(width 0.1)
		(layer "In3.Cu")
		(net 298)
	)
	(segment
		(start 246 111.7)
		(end 263 94.7)
		(width 0.1)
		(layer "In3.Cu")
		(net 298)
	)
	(segment
		(start 254.225 142.425)
		(end 252.9 142.425)
		(width 0.1)
		(layer "In3.Cu")
		(net 298)
	)
	(segment
		(start 251.05 148.25)
		(end 251.1 148.25)
		(width 0.1)
		(layer "In3.Cu")
		(net 298)
	)
	(segment
		(start 183.300001 84.700001)
		(end 183.300001 79.034317)
		(width 0.1)
		(layer "In3.Cu")
		(net 298)
	)
	(segment
		(start 252.875 143.75)
		(end 251.525 143.75)
		(width 0.1)
		(layer "In3.Cu")
		(net 298)
	)
	(segment
		(start 187.834316 74.500001)
		(end 203.200001 74.500001)
		(width 0.1)
		(layer "In3.Cu")
		(net 298)
	)
	(segment
		(start 255.4 144.4)
		(end 255.4 143.6)
		(width 0.1)
		(layer "In3.Cu")
		(net 298)
	)
	(segment
		(start 210.185789 71.8)
		(end 204.802789 77.183)
		(width 0.1)
		(layer "In3.Cu")
		(net 298)
	)
	(segment
		(start 204.101 75.401)
		(end 204.101 77.183)
		(width 0.1)
		(layer "In3.Cu")
		(net 298)
	)
	(segment
		(start 203.200001 74.500001)
		(end 204.101 75.401)
		(width 0.1)
		(layer "In3.Cu")
		(net 298)
	)
	(segment
		(start 185.075 136.125)
		(end 184.65 136.55)
		(width 0.1)
		(layer "In3.Cu")
		(net 298)
	)
	(segment
		(start 251.1 148.25)
		(end 252.05 149.2)
		(width 0.1)
		(layer "In3.Cu")
		(net 298)
	)
	(segment
		(start 182.500001 135.900001)
		(end 182.500001 85.500001)
		(width 0.1)
		(layer "In3.Cu")
		(net 298)
	)
	(segment
		(start 260.6 71.8)
		(end 210.185789 71.8)
		(width 0.1)
		(layer "In3.Cu")
		(net 298)
	)
	(segment
		(start 182.500001 85.500001)
		(end 183.300001 84.700001)
		(width 0.1)
		(layer "In3.Cu")
		(net 298)
	)
	(segment
		(start 183.15 136.55)
		(end 182.500001 135.900001)
		(width 0.1)
		(layer "In3.Cu")
		(net 298)
	)
	(segment
		(start 252.725 142.6)
		(end 252.725 142.825)
		(width 0.1)
		(layer "In3.Cu")
		(net 298)
	)
	(segment
		(start 252.9 142.425)
		(end 252.725 142.6)
		(width 0.1)
		(layer "In3.Cu")
		(net 298)
	)
	(segment
		(start 204.802789 77.183)
		(end 204.101 77.183)
		(width 0.1)
		(layer "In3.Cu")
		(net 298)
	)
	(segment
		(start 255.4 143.6)
		(end 254.225 142.425)
		(width 0.1)
		(layer "In3.Cu")
		(net 298)
	)
	(segment
		(start 250.7 147.7)
		(end 250.7 147.9)
		(width 0.1)
		(layer "In3.Cu")
		(net 298)
	)
	(segment
		(start 246 138.075)
		(end 246 111.7)
		(width 0.1)
		(layer "In3.Cu")
		(net 298)
	)
	(segment
		(start 252.725 142.825)
		(end 253 143.1)
		(width 0.1)
		(layer "In3.Cu")
		(net 298)
	)
	(segment
		(start 263 74.2)
		(end 260.6 71.8)
		(width 0.1)
		(layer "In3.Cu")
		(net 298)
	)
	(segment
		(start 251.225 143.45)
		(end 251.225 143.3)
		(width 0.1)
		(layer "In3.Cu")
		(net 298)
	)
	(segment
		(start 257.4 146.4)
		(end 255.4 144.4)
		(width 0.1)
		(layer "In3.Cu")
		(net 298)
	)
	(segment
		(start 255.2 149.2)
		(end 257.4 147)
		(width 0.1)
		(layer "In3.Cu")
		(net 298)
	)
	(segment
		(start 253 143.1)
		(end 253 143.625)
		(width 0.1)
		(layer "In3.Cu")
		(net 298)
	)
	(segment
		(start 257.4 147)
		(end 257.4 146.4)
		(width 0.1)
		(layer "In3.Cu")
		(net 298)
	)
	(segment
		(start 251.525 143.75)
		(end 251.225 143.45)
		(width 0.1)
		(layer "In3.Cu")
		(net 298)
	)
	(segment
		(start 251.225 143.3)
		(end 246 138.075)
		(width 0.1)
		(layer "In3.Cu")
		(net 298)
	)
	(segment
		(start 183.300001 79.034317)
		(end 187.834316 74.500001)
		(width 0.1)
		(layer "In3.Cu")
		(net 298)
	)
	(segment
		(start 186 136)
		(end 186.5 136.5)
		(width 0.256)
		(layer "F.Cu")
		(net 299)
	)
	(segment
		(start 249.3 143.473)
		(end 249.3 142.85)
		(width 0.1)
		(layer "F.Cu")
		(net 299)
	)
	(via
		(at 186 136)
		(size 0.45)
		(drill 0.2)
		(layers "F.Cu" "B.Cu")
		(net 299)
	)
	(via
		(at 203.101 77.183)
		(size 0.45)
		(drill 0.2)
		(layers "F.Cu" "B.Cu")
		(net 299)
	)
	(via
		(at 249.3 142.85)
		(size 0.45)
		(drill 0.2)
		(layers "F.Cu" "B.Cu")
		(net 299)
	)
	(segment
		(start 203.101 77.183)
		(end 203.101 74.718)
		(width 0.1)
		(layer "B.Cu")
		(net 299)
	)
	(segment
		(start 210.268631 72)
		(end 204.568631 77.7)
		(width 0.1)
		(layer "In3.Cu")
		(net 299)
	)
	(segment
		(start 186 136)
		(end 186 135.15)
		(width 0.1)
		(layer "In3.Cu")
		(net 299)
	)
	(segment
		(start 203.101 75.301)
		(end 203.101 77.183)
		(width 0.1)
		(layer "In3.Cu")
		(net 299)
	)
	(segment
		(start 245.8 138.4)
		(end 245.8 111.6)
		(width 0.1)
		(layer "In3.Cu")
		(net 299)
	)
	(segment
		(start 182.700001 85.582843)
		(end 183.500001 84.782843)
		(width 0.1)
		(layer "In3.Cu")
		(net 299)
	)
	(segment
		(start 183.157842 136.275)
		(end 182.700001 135.817159)
		(width 0.1)
		(layer "In3.Cu")
		(net 299)
	)
	(segment
		(start 183.500001 84.782843)
		(end 183.500001 79.117159)
		(width 0.1)
		(layer "In3.Cu")
		(net 299)
	)
	(segment
		(start 184.55 135.525)
		(end 184.55 136.075)
		(width 0.1)
		(layer "In3.Cu")
		(net 299)
	)
	(segment
		(start 185.1 134.975)
		(end 184.55 135.525)
		(width 0.1)
		(layer "In3.Cu")
		(net 299)
	)
	(segment
		(start 249.3 142.85)
		(end 249.3 141.9)
		(width 0.1)
		(layer "In3.Cu")
		(net 299)
	)
	(segment
		(start 187.917159 74.700001)
		(end 202.500001 74.700001)
		(width 0.1)
		(layer "In3.Cu")
		(net 299)
	)
	(segment
		(start 203.618 77.7)
		(end 203.101 77.183)
		(width 0.1)
		(layer "In3.Cu")
		(net 299)
	)
	(segment
		(start 182.700001 135.817159)
		(end 182.700001 85.582843)
		(width 0.1)
		(layer "In3.Cu")
		(net 299)
	)
	(segment
		(start 245.8 111.6)
		(end 262.8 94.6)
		(width 0.1)
		(layer "In3.Cu")
		(net 299)
	)
	(segment
		(start 186 135.15)
		(end 185.825 134.975)
		(width 0.1)
		(layer "In3.Cu")
		(net 299)
	)
	(segment
		(start 202.500001 74.700001)
		(end 203.101 75.301)
		(width 0.1)
		(layer "In3.Cu")
		(net 299)
	)
	(segment
		(start 184.55 136.075)
		(end 184.35 136.275)
		(width 0.1)
		(layer "In3.Cu")
		(net 299)
	)
	(segment
		(start 184.35 136.275)
		(end 183.157842 136.275)
		(width 0.1)
		(layer "In3.Cu")
		(net 299)
	)
	(segment
		(start 249.3 141.9)
		(end 245.8 138.4)
		(width 0.1)
		(layer "In3.Cu")
		(net 299)
	)
	(segment
		(start 183.500001 79.117159)
		(end 187.917159 74.700001)
		(width 0.1)
		(layer "In3.Cu")
		(net 299)
	)
	(segment
		(start 260.5 72)
		(end 210.268631 72)
		(width 0.1)
		(layer "In3.Cu")
		(net 299)
	)
	(segment
		(start 204.568631 77.7)
		(end 203.618 77.7)
		(width 0.1)
		(layer "In3.Cu")
		(net 299)
	)
	(segment
		(start 262.8 94.6)
		(end 262.8 74.3)
		(width 0.1)
		(layer "In3.Cu")
		(net 299)
	)
	(segment
		(start 262.8 74.3)
		(end 260.5 72)
		(width 0.1)
		(layer "In3.Cu")
		(net 299)
	)
	(segment
		(start 185.825 134.975)
		(end 185.1 134.975)
		(width 0.1)
		(layer "In3.Cu")
		(net 299)
	)
	(segment
		(start 247.7 143.473)
		(end 247.7 143.25)
		(width 0.1)
		(layer "F.Cu")
		(net 300)
	)
	(segment
		(start 189.5 136.5)
		(end 189 137)
		(width 0.256)
		(layer "F.Cu")
		(net 300)
	)
	(via
		(at 247.7 143.25)
		(size 0.45)
		(drill 0.2)
		(layers "F.Cu" "B.Cu")
		(net 300)
	)
	(via
		(at 189 137)
		(size 0.45)
		(drill 0.2)
		(layers "F.Cu" "B.Cu")
		(net 300)
	)
	(via
		(at 202.101 77.183)
		(size 0.45)
		(drill 0.2)
		(layers "F.Cu" "B.Cu")
		(net 300)
	)
	(segment
		(start 202.101 77.183)
		(end 202.101 74.718)
		(width 0.1)
		(layer "B.Cu")
		(net 300)
	)
	(segment
		(start 182.900001 135.734317)
		(end 182.900001 85.665685)
		(width 0.1)
		(layer "In3.Cu")
		(net 300)
	)
	(segment
		(start 262.6 94.5)
		(end 262.6 74.4)
		(width 0.1)
		(layer "In3.Cu")
		(net 300)
	)
	(segment
		(start 186.65 134.6)
		(end 185 134.6)
		(width 0.1)
		(layer "In3.Cu")
		(net 300)
	)
	(segment
		(start 186.575 136.375)
		(end 187.075 135.875)
		(width 0.1)
		(layer "In3.Cu")
		(net 300)
	)
	(segment
		(start 186.800001 137.000001)
		(end 186.575 136.775)
		(width 0.1)
		(layer "In3.Cu")
		(net 300)
	)
	(segment
		(start 204.651473 77.9)
		(end 202.818 77.9)
		(width 0.1)
		(layer "In3.Cu")
		(net 300)
	)
	(segment
		(start 245.6 138.5)
		(end 245.6 111.5)
		(width 0.1)
		(layer "In3.Cu")
		(net 300)
	)
	(segment
		(start 187.075 135.025)
		(end 186.65 134.6)
		(width 0.1)
		(layer "In3.Cu")
		(net 300)
	)
	(segment
		(start 210.351473 72.2)
		(end 204.651473 77.9)
		(width 0.1)
		(layer "In3.Cu")
		(net 300)
	)
	(segment
		(start 186.575 136.775)
		(end 186.575 136.375)
		(width 0.1)
		(layer "In3.Cu")
		(net 300)
	)
	(segment
		(start 184.2 135.4)
		(end 184.2 135.725)
		(width 0.1)
		(layer "In3.Cu")
		(net 300)
	)
	(segment
		(start 248.3 142.4)
		(end 248.3 141.2)
		(width 0.1)
		(layer "In3.Cu")
		(net 300)
	)
	(segment
		(start 262.6 74.4)
		(end 260.4 72.2)
		(width 0.1)
		(layer "In3.Cu")
		(net 300)
	)
	(segment
		(start 201.700001 74.900001)
		(end 202.101 75.301)
		(width 0.1)
		(layer "In3.Cu")
		(net 300)
	)
	(segment
		(start 247.7 143.25)
		(end 247.7 142.719669)
		(width 0.1)
		(layer "In3.Cu")
		(net 300)
	)
	(segment
		(start 184.2 135.725)
		(end 183.925 136)
		(width 0.1)
		(layer "In3.Cu")
		(net 300)
	)
	(segment
		(start 247.7 142.719669)
		(end 247.944669 142.475)
		(width 0.1)
		(layer "In3.Cu")
		(net 300)
	)
	(segment
		(start 183.925 136)
		(end 183.165684 136)
		(width 0.1)
		(layer "In3.Cu")
		(net 300)
	)
	(segment
		(start 189.000001 137.000001)
		(end 186.800001 137.000001)
		(width 0.1)
		(layer "In3.Cu")
		(net 300)
	)
	(segment
		(start 183.165684 136)
		(end 182.900001 135.734317)
		(width 0.1)
		(layer "In3.Cu")
		(net 300)
	)
	(segment
		(start 245.6 111.5)
		(end 262.6 94.5)
		(width 0.1)
		(layer "In3.Cu")
		(net 300)
	)
	(segment
		(start 187.075 135.875)
		(end 187.075 135.025)
		(width 0.1)
		(layer "In3.Cu")
		(net 300)
	)
	(segment
		(start 202.818 77.9)
		(end 202.101 77.183)
		(width 0.1)
		(layer "In3.Cu")
		(net 300)
	)
	(segment
		(start 185 134.6)
		(end 184.2 135.4)
		(width 0.1)
		(layer "In3.Cu")
		(net 300)
	)
	(segment
		(start 188.000001 74.900001)
		(end 201.700001 74.900001)
		(width 0.1)
		(layer "In3.Cu")
		(net 300)
	)
	(segment
		(start 248.3 141.2)
		(end 245.6 138.5)
		(width 0.1)
		(layer "In3.Cu")
		(net 300)
	)
	(segment
		(start 260.4 72.2)
		(end 210.351473 72.2)
		(width 0.1)
		(layer "In3.Cu")
		(net 300)
	)
	(segment
		(start 247.944669 142.475)
		(end 248.225 142.475)
		(width 0.1)
		(layer "In3.Cu")
		(net 300)
	)
	(segment
		(start 183.700001 84.865685)
		(end 183.700001 79.200001)
		(width 0.1)
		(layer "In3.Cu")
		(net 300)
	)
	(segment
		(start 182.900001 85.665685)
		(end 183.700001 84.865685)
		(width 0.1)
		(layer "In3.Cu")
		(net 300)
	)
	(segment
		(start 248.225 142.475)
		(end 248.3 142.4)
		(width 0.1)
		(layer "In3.Cu")
		(net 300)
	)
	(segment
		(start 202.101 75.301)
		(end 202.101 77.183)
		(width 0.1)
		(layer "In3.Cu")
		(net 300)
	)
	(segment
		(start 183.700001 79.200001)
		(end 188.000001 74.900001)
		(width 0.1)
		(layer "In3.Cu")
		(net 300)
	)
	(segment
		(start 179.82 77.73)
		(end 179.345 77.255)
		(width 0.1)
		(layer "F.Cu")
		(net 301)
	)
	(segment
		(start 179.345 77.255)
		(end 178.8 77.255)
		(width 0.1)
		(layer "F.Cu")
		(net 301)
	)
	(segment
		(start 179.82 78.24)
		(end 179.82 77.73)
		(width 0.1)
		(layer "F.Cu")
		(net 301)
	)
	(segment
		(start 178.78 75.67)
		(end 178.78 71.57)
		(width 0.1)
		(layer "F.Cu")
		(net 301)
	)
	(segment
		(start 178.8 77.255)
		(end 178.78 77.235)
		(width 0.1)
		(layer "F.Cu")
		(net 301)
	)
	(segment
		(start 194.5 124.5)
		(end 194 124)
		(width 0.256)
		(layer "F.Cu")
		(net 301)
	)
	(segment
		(start 178.78 77.235)
		(end 178.78 75.67)
		(width 0.1)
		(layer "F.Cu")
		(net 301)
	)
	(via
		(at 249.75 147.25)
		(size 0.45)
		(drill 0.2)
		(layers "F.Cu" "B.Cu")
		(net 301)
	)
	(via
		(at 247.85 142)
		(size 0.45)
		(drill 0.2)
		(layers "F.Cu" "B.Cu")
		(net 301)
	)
	(via
		(at 179.82 78.24)
		(size 0.45)
		(drill 0.2)
		(layers "F.Cu" "B.Cu")
		(net 301)
	)
	(via
		(at 194 124)
		(size 0.45)
		(drill 0.2)
		(layers "F.Cu" "B.Cu")
		(net 301)
	)
	(via
		(at 206.75 78.95)
		(size 0.45)
		(drill 0.2)
		(layers "F.Cu" "B.Cu")
		(net 301)
	)
	(segment
		(start 249.7 148.273)
		(end 249.7 147.3)
		(width 0.1)
		(layer "B.Cu")
		(net 301)
	)
	(segment
		(start 249.7 147.3)
		(end 249.75 147.25)
		(width 0.1)
		(layer "B.Cu")
		(net 301)
	)
	(segment
		(start 194.8 85.914211)
		(end 194 86.71421)
		(width 0.1)
		(layer "In3.Cu")
		(net 301)
	)
	(segment
		(start 206.75 76.367157)
		(end 210.517157 72.6)
		(width 0.1)
		(layer "In3.Cu")
		(net 301)
	)
	(segment
		(start 194.8 81.26)
		(end 194.8 85.914211)
		(width 0.1)
		(layer "In3.Cu")
		(net 301)
	)
	(segment
		(start 205.49 80.21)
		(end 195.85 80.21)
		(width 0.1)
		(layer "In3.Cu")
		(net 301)
	)
	(segment
		(start 262.2 74.6)
		(end 262.2 94.3)
		(width 0.1)
		(layer "In3.Cu")
		(net 301)
	)
	(segment
		(start 195.85 80.21)
		(end 194.8 81.26)
		(width 0.1)
		(layer "In3.Cu")
		(net 301)
	)
	(segment
		(start 260.2 72.6)
		(end 262.2 74.6)
		(width 0.1)
		(layer "In3.Cu")
		(net 301)
	)
	(segment
		(start 262.2 94.3)
		(end 245.2 111.3)
		(width 0.1)
		(layer "In3.Cu")
		(net 301)
	)
	(segment
		(start 194.4 114.5)
		(end 194.4 123.6)
		(width 0.1)
		(layer "In3.Cu")
		(net 301)
	)
	(segment
		(start 245.2 111.3)
		(end 245.2 138.7)
		(width 0.1)
		(layer "In3.Cu")
		(net 301)
	)
	(segment
		(start 210.517157 72.6)
		(end 260.2 72.6)
		(width 0.1)
		(layer "In3.Cu")
		(net 301)
	)
	(segment
		(start 194 86.71421)
		(end 194 114.1)
		(width 0.1)
		(layer "In3.Cu")
		(net 301)
	)
	(segment
		(start 247.45 140.95)
		(end 247.45 141.6)
		(width 0.1)
		(layer "In3.Cu")
		(net 301)
	)
	(segment
		(start 194 114.1)
		(end 194.4 114.5)
		(width 0.1)
		(layer "In3.Cu")
		(net 301)
	)
	(segment
		(start 245.2 138.7)
		(end 247.45 140.95)
		(width 0.1)
		(layer "In3.Cu")
		(net 301)
	)
	(segment
		(start 206.75 78.95)
		(end 205.49 80.21)
		(width 0.1)
		(layer "In3.Cu")
		(net 301)
	)
	(segment
		(start 194.4 123.6)
		(end 194 124)
		(width 0.1)
		(layer "In3.Cu")
		(net 301)
	)
	(segment
		(start 247.45 141.6)
		(end 247.85 142)
		(width 0.1)
		(layer "In3.Cu")
		(net 301)
	)
	(segment
		(start 206.75 78.95)
		(end 206.75 76.367157)
		(width 0.1)
		(layer "In3.Cu")
		(net 301)
	)
	(segment
		(start 206.04 78.24)
		(end 179.82 78.24)
		(width 0.1)
		(layer "In5.Cu")
		(net 301)
	)
	(segment
		(start 249.75 143.9)
		(end 249.75 147.25)
		(width 0.1)
		(layer "In5.Cu")
		(net 301)
	)
	(segment
		(start 206.75 78.95)
		(end 206.04 78.24)
		(width 0.1)
		(layer "In5.Cu")
		(net 301)
	)
	(segment
		(start 247.85 142)
		(end 249.75 143.9)
		(width 0.1)
		(layer "In5.Cu")
		(net 301)
	)
	(segment
		(start 175.570191 83.729811)
		(end 175.570191 83.553741)
		(width 0.201)
		(layer "F.Cu")
		(net 307)
	)
	(segment
		(start 175.356951 83.340501)
		(end 170.572501 83.340501)
		(width 0.201)
		(layer "F.Cu")
		(net 307)
	)
	(segment
		(start 167.715001 83.775001)
		(end 168.218 83.272002)
		(width 0.16)
		(layer "F.Cu")
		(net 307)
	)
	(segment
		(start 170.504001 83.272001)
		(end 170.572501 83.340501)
		(width 0.16)
		(layer "F.Cu")
		(net 307)
	)
	(segment
		(start 175.570191 83.553741)
		(end 175.356951 83.340501)
		(width 0.201)
		(layer "F.Cu")
		(net 307)
	)
	(segment
		(start 170.504001 83.272001)
		(end 168.218 83.272002)
		(width 0.16)
		(layer "F.Cu")
		(net 307)
	)
	(via
		(at 175.570191 83.729811)
		(size 0.45)
		(drill 0.2)
		(layers "F.Cu" "B.Cu")
		(net 307)
	)
	(via
		(at 189.5 128.5)
		(size 0.45)
		(drill 0.2)
		(layers "F.Cu" "B.Cu")
		(net 307)
	)
	(segment
		(start 189.8994 128.220821)
		(end 189.77858 128.100002)
		(width 0.1)
		(layer "B.Cu")
		(net 307)
	)
	(segment
		(start 181.786451 128.200001)
		(end 183.346376 128.200001)
		(width 0.201)
		(layer "B.Cu")
		(net 307)
	)
	(segment
		(start 175.570191 83.729811)
		(end 175.746261 83.729811)
		(width 0.201)
		(layer "B.Cu")
		(net 307)
	)
	(segment
		(start 176.619501 84.603051)
		(end 176.619501 89.503051)
		(width 0.201)
		(layer "B.Cu")
		(net 307)
	)
	(segment
		(start 176.619501 89.503051)
		(end 180.519501 93.403051)
		(width 0.201)
		(layer "B.Cu")
		(net 307)
	)
	(segment
		(start 189.500001 128.500001)
		(end 189.830002 128.500001)
		(width 0.1)
		(layer "B.Cu")
		(net 307)
	)
	(segment
		(start 188.864002 128.314229)
		(end 188.864002 128.225002)
		(width 0.1)
		(layer "B.Cu")
		(net 307)
	)
	(segment
		(start 183.446376 128.100001)
		(end 183.346376 128.200001)
		(width 0.1)
		(layer "B.Cu")
		(net 307)
	)
	(segment
		(start 189.830002 128.500001)
		(end 189.8994 128.430604)
		(width 0.1)
		(layer "B.Cu")
		(net 307)
	)
	(segment
		(start 180.519501 93.403051)
		(end 180.519501 126.933051)
		(width 0.201)
		(layer "B.Cu")
		(net 307)
	)
	(segment
		(start 189.77858 128.100002)
		(end 189.239002 128.100002)
		(width 0.1)
		(layer "B.Cu")
		(net 307)
	)
	(segment
		(start 175.746261 83.729811)
		(end 176.619501 84.603051)
		(width 0.201)
		(layer "B.Cu")
		(net 307)
	)
	(segment
		(start 180.519501 126.933051)
		(end 181.786451 128.200001)
		(width 0.201)
		(layer "B.Cu")
		(net 307)
	)
	(segment
		(start 188.689002 128.100002)
		(end 183.446376 128.100001)
		(width 0.1)
		(layer "B.Cu")
		(net 307)
	)
	(segment
		(start 189.8994 128.430604)
		(end 189.8994 128.220821)
		(width 0.1)
		(layer "B.Cu")
		(net 307)
	)
	(segment
		(start 189.114002 128.225002)
		(end 189.114002 128.314229)
		(width 0.1)
		(layer "B.Cu")
		(net 307)
	)
	(segment
		(start 188.739002 128.100002)
		(end 188.689002 128.100002)
		(width 0.1)
		(layer "B.Cu")
		(net 307)
	)
	(arc
		(start 189.114002 128.314229)
		(mid 189.07739 128.402617)
		(end 188.989002 128.439229)
		(width 0.1)
		(layer "B.Cu")
		(net 307)
	)
	(arc
		(start 188.864002 128.225002)
		(mid 188.82739 128.136614)
		(end 188.739002 128.100002)
		(width 0.1)
		(layer "B.Cu")
		(net 307)
	)
	(arc
		(start 188.989002 128.439229)
		(mid 188.900614 128.402617)
		(end 188.864002 128.314229)
		(width 0.1)
		(layer "B.Cu")
		(net 307)
	)
	(arc
		(start 189.239002 128.100002)
		(mid 189.150614 128.136614)
		(end 189.114002 128.225002)
		(width 0.1)
		(layer "B.Cu")
		(net 307)
	)
	(segment
		(start 175.853741 83.270191)
		(end 175.523051 82.939501)
		(width 0.201)
		(layer "F.Cu")
		(net 312)
	)
	(segment
		(start 176.029811 83.270191)
		(end 175.853741 83.270191)
		(width 0.201)
		(layer "F.Cu")
		(net 312)
	)
	(segment
		(start 170.504001 83.008001)
		(end 170.572501 82.939501)
		(width 0.16)
		(layer "F.Cu")
		(net 312)
	)
	(segment
		(start 167.715001 82.505001)
		(end 168.218 83.008)
		(width 0.16)
		(layer "F.Cu")
		(net 312)
	)
	(segment
		(start 170.504001 83.008001)
		(end 168.218 83.008)
		(width 0.16)
		(layer "F.Cu")
		(net 312)
	)
	(segment
		(start 175.523051 82.939501)
		(end 170.572501 82.939501)
		(width 0.201)
		(layer "F.Cu")
		(net 312)
	)
	(via
		(at 190.5 128.5)
		(size 0.45)
		(drill 0.2)
		(layers "F.Cu" "B.Cu")
		(net 312)
	)
	(via
		(at 176.029811 83.270191)
		(size 0.45)
		(drill 0.2)
		(layers "F.Cu" "B.Cu")
		(net 312)
	)
	(segment
		(start 180.920501 126.766951)
		(end 181.952551 127.799001)
		(width 0.201)
		(layer "B.Cu")
		(net 312)
	)
	(segment
		(start 190.210001 128.500001)
		(end 190.099399 128.389399)
		(width 0.1)
		(layer "B.Cu")
		(net 312)
	)
	(segment
		(start 190.099399 128.389399)
		(end 190.0994 128.137977)
		(width 0.1)
		(layer "B.Cu")
		(net 312)
	)
	(segment
		(start 183.447376 127.900001)
		(end 183.346376 127.799001)
		(width 0.1)
		(layer "B.Cu")
		(net 312)
	)
	(segment
		(start 177.020501 84.436951)
		(end 177.020501 89.336951)
		(width 0.201)
		(layer "B.Cu")
		(net 312)
	)
	(segment
		(start 181.952551 127.799001)
		(end 183.346376 127.799001)
		(width 0.201)
		(layer "B.Cu")
		(net 312)
	)
	(segment
		(start 176.029811 83.270191)
		(end 176.029811 83.446261)
		(width 0.201)
		(layer "B.Cu")
		(net 312)
	)
	(segment
		(start 176.029811 83.446261)
		(end 177.020501 84.436951)
		(width 0.201)
		(layer "B.Cu")
		(net 312)
	)
	(segment
		(start 190.210001 128.500001)
		(end 190.500001 128.500001)
		(width 0.1)
		(layer "B.Cu")
		(net 312)
	)
	(segment
		(start 190.0994 128.137977)
		(end 189.861424 127.900001)
		(width 0.1)
		(layer "B.Cu")
		(net 312)
	)
	(segment
		(start 189.861424 127.900001)
		(end 183.447376 127.900001)
		(width 0.1)
		(layer "B.Cu")
		(net 312)
	)
	(segment
		(start 177.020501 89.336951)
		(end 180.920501 93.236951)
		(width 0.201)
		(layer "B.Cu")
		(net 312)
	)
	(segment
		(start 180.920501 93.236951)
		(end 180.920501 126.766951)
		(width 0.201)
		(layer "B.Cu")
		(net 312)
	)
	(segment
		(start 251.65 138.3)
		(end 252.725 139.375)
		(width 0.182)
		(layer "B.Cu")
		(net 327)
	)
	(segment
		(start 251.55 138.3)
		(end 251.65 138.3)
		(width 0.182)
		(layer "B.Cu")
		(net 327)
	)
	(segment
		(start 252.725 139.375)
		(end 253.31 139.375)
		(width 0.182)
		(layer "B.Cu")
		(net 327)
	)
	(segment
		(start 252.45 138.275)
		(end 252.075 137.9)
		(width 0.182)
		(layer "B.Cu")
		(net 328)
	)
	(segment
		(start 252.075 137.9)
		(end 251.55 137.9)
		(width 0.182)
		(layer "B.Cu")
		(net 328)
	)
	(segment
		(start 253.31 138.275)
		(end 252.45 138.275)
		(width 0.182)
		(layer "B.Cu")
		(net 328)
	)
	(segment
		(start 252 137.55)
		(end 251.6 137.55)
		(width 0.182)
		(layer "B.Cu")
		(net 329)
	)
	(segment
		(start 253.31 137.175)
		(end 252.375 137.175)
		(width 0.182)
		(layer "B.Cu")
		(net 329)
	)
	(segment
		(start 252.375 137.175)
		(end 252 137.55)
		(width 0.182)
		(layer "B.Cu")
		(net 329)
	)
	(segment
		(start 251.6 137.55)
		(end 251.55 137.5)
		(width 0.182)
		(layer "B.Cu")
		(net 329)
	)
	(segment
		(start 252.775 134.975)
		(end 253.31 134.975)
		(width 0.182)
		(layer "B.Cu")
		(net 330)
	)
	(segment
		(start 251.7 133.9)
		(end 252.775 134.975)
		(width 0.182)
		(layer "B.Cu")
		(net 330)
	)
	(segment
		(start 251.55 133.9)
		(end 251.7 133.9)
		(width 0.182)
		(layer "B.Cu")
		(net 330)
	)
	(segment
		(start 253.025 132.775)
		(end 252.7 133.1)
		(width 0.182)
		(layer "B.Cu")
		(net 331)
	)
	(segment
		(start 252.7 133.1)
		(end 251.55 133.1)
		(width 0.182)
		(layer "B.Cu")
		(net 331)
	)
	(segment
		(start 253.31 131.675)
		(end 252.825 131.675)
		(width 0.182)
		(layer "B.Cu")
		(net 332)
	)
	(segment
		(start 251.8 132.7)
		(end 251.55 132.7)
		(width 0.182)
		(layer "B.Cu")
		(net 332)
	)
	(segment
		(start 252.825 131.675)
		(end 251.8 132.7)
		(width 0.182)
		(layer "B.Cu")
		(net 332)
	)
	(segment
		(start 206.69 76.49)
		(end 207.4 77.2)
		(width 0.182)
		(layer "F.Cu")
		(net 333)
	)
	(segment
		(start 207.4 77.2)
		(end 207.4 77.84)
		(width 0.182)
		(layer "F.Cu")
		(net 333)
	)
	(segment
		(start 206.69 75.925)
		(end 206.69 76.49)
		(width 0.182)
		(layer "F.Cu")
		(net 333)
	)
	(segment
		(start 200.5 120.5)
		(end 201 120)
		(width 0.256)
		(layer "F.Cu")
		(net 334)
	)
	(segment
		(start 156.285001 115.525001)
		(end 156.900001 116.140001)
		(width 0.198)
		(layer "F.Cu")
		(net 334)
	)
	(via
		(at 156.900001 116.140001)
		(size 0.45)
		(drill 0.2)
		(layers "F.Cu" "B.Cu")
		(net 334)
	)
	(via
		(at 171.450001 122.950001)
		(size 0.45)
		(drill 0.2)
		(layers "F.Cu" "B.Cu")
		(net 334)
	)
	(via
		(at 201 120)
		(size 0.45)
		(drill 0.2)
		(layers "F.Cu" "B.Cu")
		(net 334)
	)
	(segment
		(start 156.300001 121.370001)
		(end 158.030001 123.100001)
		(width 0.114)
		(layer "In3.Cu")
		(net 334)
	)
	(segment
		(start 156.300001 116.740001)
		(end 156.300001 121.370001)
		(width 0.114)
		(layer "In3.Cu")
		(net 334)
	)
	(segment
		(start 158.030001 123.100001)
		(end 171.300001 123.100001)
		(width 0.114)
		(layer "In3.Cu")
		(net 334)
	)
	(segment
		(start 156.900001 116.140001)
		(end 156.300001 116.740001)
		(width 0.114)
		(layer "In3.Cu")
		(net 334)
	)
	(segment
		(start 171.300001 123.100001)
		(end 171.450001 122.950001)
		(width 0.114)
		(layer "In3.Cu")
		(net 334)
	)
	(segment
		(start 201 120)
		(end 200.5 120.5)
		(width 0.1)
		(layer "In7.Cu")
		(net 334)
	)
	(segment
		(start 200.500001 120.500001)
		(end 199.675001 120.500001)
		(width 0.1)
		(layer "In7.Cu")
		(net 334)
	)
	(segment
		(start 199.250002 121.6)
		(end 193.850002 121.6)
		(width 0.1)
		(layer "In7.Cu")
		(net 334)
	)
	(segment
		(start 193.325001 122.125001)
		(end 173.300001 122.125001)
		(width 0.1)
		(layer "In7.Cu")
		(net 334)
	)
	(segment
		(start 199.675001 120.500001)
		(end 199.500001 120.675001)
		(width 0.1)
		(layer "In7.Cu")
		(net 334)
	)
	(segment
		(start 199.500001 121.350001)
		(end 199.250002 121.6)
		(width 0.1)
		(layer "In7.Cu")
		(net 334)
	)
	(segment
		(start 193.850002 121.6)
		(end 193.325001 122.125001)
		(width 0.1)
		(layer "In7.Cu")
		(net 334)
	)
	(segment
		(start 172.275001 123.150001)
		(end 171.650001 123.150001)
		(width 0.1)
		(layer "In7.Cu")
		(net 334)
	)
	(segment
		(start 199.500001 120.675001)
		(end 199.500001 121.350001)
		(width 0.1)
		(layer "In7.Cu")
		(net 334)
	)
	(segment
		(start 171.650001 123.150001)
		(end 171.450001 122.950001)
		(width 0.1)
		(layer "In7.Cu")
		(net 334)
	)
	(segment
		(start 173.300001 122.125001)
		(end 172.275001 123.150001)
		(width 0.1)
		(layer "In7.Cu")
		(net 334)
	)
	(segment
		(start 199.5 119.5)
		(end 199 119)
		(width 0.256)
		(layer "F.Cu")
		(net 335)
	)
	(segment
		(start 156.775002 112.482002)
		(end 156.606804 112.482001)
		(width 0.16)
		(layer "F.Cu")
		(net 335)
	)
	(segment
		(start 156.285001 112.803804)
		(end 156.285001 112.985001)
		(width 0.16)
		(layer "F.Cu")
		(net 335)
	)
	(segment
		(start 156.606804 112.482001)
		(end 156.285001 112.803804)
		(width 0.16)
		(layer "F.Cu")
		(net 335)
	)
	(segment
		(start 156.775002 112.482002)
		(end 156.920001 112.627001)
		(width 0.16)
		(layer "F.Cu")
		(net 335)
	)
	(via
		(at 199 119)
		(size 0.45)
		(drill 0.2)
		(layers "F.Cu" "B.Cu")
		(net 335)
	)
	(via
		(at 156.920001 112.627001)
		(size 0.45)
		(drill 0.2)
		(layers "F.Cu" "B.Cu")
		(net 335)
	)
	(via
		(at 171.510265 122.383765)
		(size 0.45)
		(drill 0.2)
		(layers "F.Cu" "B.Cu")
		(net 335)
	)
	(segment
		(start 170.455561 122.658501)
		(end 169.810561 122.013501)
		(width 0.114)
		(layer "In3.Cu")
		(net 335)
	)
	(segment
		(start 170.997941 122.658501)
		(end 170.455561 122.658501)
		(width 0.114)
		(layer "In3.Cu")
		(net 335)
	)
	(segment
		(start 158.280561 122.013501)
		(end 157.416501 121.149441)
		(width 0.114)
		(layer "In3.Cu")
		(net 335)
	)
	(segment
		(start 157.250561 112.493501)
		(end 157.053501 112.493501)
		(width 0.114)
		(layer "In3.Cu")
		(net 335)
	)
	(segment
		(start 171.272677 122.383765)
		(end 170.997941 122.658501)
		(width 0.114)
		(layer "In3.Cu")
		(net 335)
	)
	(segment
		(start 157.416501 112.659441)
		(end 157.250561 112.493501)
		(width 0.114)
		(layer "In3.Cu")
		(net 335)
	)
	(segment
		(start 171.510265 122.383765)
		(end 171.272677 122.383765)
		(width 0.114)
		(layer "In3.Cu")
		(net 335)
	)
	(segment
		(start 169.810561 122.013501)
		(end 158.280561 122.013501)
		(width 0.114)
		(layer "In3.Cu")
		(net 335)
	)
	(segment
		(start 157.053501 112.493501)
		(end 156.920001 112.627001)
		(width 0.114)
		(layer "In3.Cu")
		(net 335)
	)
	(segment
		(start 157.416501 121.149441)
		(end 157.416501 112.659441)
		(width 0.114)
		(layer "In3.Cu")
		(net 335)
	)
	(segment
		(start 198.600001 119.400001)
		(end 198.600001 120.241423)
		(width 0.1)
		(layer "In7.Cu")
		(net 335)
	)
	(segment
		(start 178.788001 120.245541)
		(end 178.788001 120.675001)
		(width 0.114)
		(layer "In7.Cu")
		(net 335)
	)
	(segment
		(start 172.512941 121.143501)
		(end 172.756501 121.143501)
		(width 0.114)
		(layer "In7.Cu")
		(net 335)
	)
	(segment
		(start 181.388001 120.245541)
		(end 181.388001 120.675001)
		(width 0.114)
		(layer "In7.Cu")
		(net 335)
	)
	(segment
		(start 193.216423 121.100001)
		(end 183.448501 121.100001)
		(width 0.1)
		(layer "In7.Cu")
		(net 335)
	)
	(segment
		(start 179.725001 120.675001)
		(end 179.725001 120.245541)
		(width 0.114)
		(layer "In7.Cu")
		(net 335)
	)
	(segment
		(start 183.156501 121.143501)
		(end 183.405001 121.143501)
		(width 0.114)
		(layer "In7.Cu")
		(net 335)
	)
	(segment
		(start 198.600001 120.241423)
		(end 198.241423 120.600001)
		(width 0.1)
		(layer "In7.Cu")
		(net 335)
	)
	(segment
		(start 182.325001 120.675001)
		(end 182.325001 120.245541)
		(width 0.114)
		(layer "In7.Cu")
		(net 335)
	)
	(segment
		(start 182.688001 120.245541)
		(end 182.688001 120.675001)
		(width 0.114)
		(layer "In7.Cu")
		(net 335)
	)
	(segment
		(start 181.025001 120.675001)
		(end 181.025001 120.245541)
		(width 0.114)
		(layer "In7.Cu")
		(net 335)
	)
	(segment
		(start 199.000001 119.000001)
		(end 198.600001 119.400001)
		(width 0.1)
		(layer "In7.Cu")
		(net 335)
	)
	(segment
		(start 171.510265 122.383765)
		(end 171.510265 122.146177)
		(width 0.114)
		(layer "In7.Cu")
		(net 335)
	)
	(segment
		(start 171.510265 122.146177)
		(end 172.512941 121.143501)
		(width 0.114)
		(layer "In7.Cu")
		(net 335)
	)
	(segment
		(start 178.425001 120.675001)
		(end 178.425001 120.245541)
		(width 0.114)
		(layer "In7.Cu")
		(net 335)
	)
	(segment
		(start 198.241423 120.600001)
		(end 193.716423 120.600001)
		(width 0.1)
		(layer "In7.Cu")
		(net 335)
	)
	(segment
		(start 173.588001 120.245541)
		(end 173.588001 120.675001)
		(width 0.114)
		(layer "In7.Cu")
		(net 335)
	)
	(segment
		(start 183.448501 121.100001)
		(end 183.405001 121.143501)
		(width 0.1)
		(layer "In7.Cu")
		(net 335)
	)
	(segment
		(start 173.225001 120.675001)
		(end 173.225001 120.245541)
		(width 0.114)
		(layer "In7.Cu")
		(net 335)
	)
	(segment
		(start 177.125001 120.675001)
		(end 177.125001 120.245541)
		(width 0.114)
		(layer "In7.Cu")
		(net 335)
	)
	(segment
		(start 174.525001 120.675001)
		(end 174.525001 120.245541)
		(width 0.114)
		(layer "In7.Cu")
		(net 335)
	)
	(segment
		(start 177.488001 120.245541)
		(end 177.488001 120.675001)
		(width 0.114)
		(layer "In7.Cu")
		(net 335)
	)
	(segment
		(start 175.825001 120.675001)
		(end 175.825001 120.245541)
		(width 0.114)
		(layer "In7.Cu")
		(net 335)
	)
	(segment
		(start 180.088001 120.245541)
		(end 180.088001 120.675001)
		(width 0.114)
		(layer "In7.Cu")
		(net 335)
	)
	(segment
		(start 176.188001 120.245541)
		(end 176.188001 120.675001)
		(width 0.114)
		(layer "In7.Cu")
		(net 335)
	)
	(segment
		(start 174.888001 120.245541)
		(end 174.888001 120.675001)
		(width 0.114)
		(layer "In7.Cu")
		(net 335)
	)
	(segment
		(start 193.716423 120.600001)
		(end 193.216423 121.100001)
		(width 0.1)
		(layer "In7.Cu")
		(net 335)
	)
	(arc
		(start 182.325001 120.245541)
		(mid 182.378161 120.117201)
		(end 182.506501 120.064041)
		(width 0.114)
		(layer "In7.Cu")
		(net 335)
	)
	(arc
		(start 176.006501 120.064041)
		(mid 176.134841 120.117201)
		(end 176.188001 120.245541)
		(width 0.114)
		(layer "In7.Cu")
		(net 335)
	)
	(arc
		(start 180.088001 120.675001)
		(mid 180.225221 121.006281)
		(end 180.556501 121.143501)
		(width 0.114)
		(layer "In7.Cu")
		(net 335)
	)
	(arc
		(start 179.725001 120.245541)
		(mid 179.778161 120.117201)
		(end 179.906501 120.064041)
		(width 0.114)
		(layer "In7.Cu")
		(net 335)
	)
	(arc
		(start 174.888001 120.675001)
		(mid 175.025221 121.006281)
		(end 175.356501 121.143501)
		(width 0.114)
		(layer "In7.Cu")
		(net 335)
	)
	(arc
		(start 175.825001 120.245541)
		(mid 175.878161 120.117201)
		(end 176.006501 120.064041)
		(width 0.114)
		(layer "In7.Cu")
		(net 335)
	)
	(arc
		(start 173.406501 120.064041)
		(mid 173.534841 120.117201)
		(end 173.588001 120.245541)
		(width 0.114)
		(layer "In7.Cu")
		(net 335)
	)
	(arc
		(start 181.025001 120.245541)
		(mid 181.078161 120.117201)
		(end 181.206501 120.064041)
		(width 0.114)
		(layer "In7.Cu")
		(net 335)
	)
	(arc
		(start 173.225001 120.245541)
		(mid 173.278161 120.117201)
		(end 173.406501 120.064041)
		(width 0.114)
		(layer "In7.Cu")
		(net 335)
	)
	(arc
		(start 178.788001 120.675001)
		(mid 178.925221 121.006281)
		(end 179.256501 121.143501)
		(width 0.114)
		(layer "In7.Cu")
		(net 335)
	)
	(arc
		(start 176.188001 120.675001)
		(mid 176.325221 121.006281)
		(end 176.656501 121.143501)
		(width 0.114)
		(layer "In7.Cu")
		(net 335)
	)
	(arc
		(start 177.306501 120.064041)
		(mid 177.434841 120.117201)
		(end 177.488001 120.245541)
		(width 0.114)
		(layer "In7.Cu")
		(net 335)
	)
	(arc
		(start 178.606501 120.064041)
		(mid 178.734841 120.117201)
		(end 178.788001 120.245541)
		(width 0.114)
		(layer "In7.Cu")
		(net 335)
	)
	(arc
		(start 175.356501 121.143501)
		(mid 175.687781 121.006281)
		(end 175.825001 120.675001)
		(width 0.114)
		(layer "In7.Cu")
		(net 335)
	)
	(arc
		(start 177.488001 120.675001)
		(mid 177.625221 121.006281)
		(end 177.956501 121.143501)
		(width 0.114)
		(layer "In7.Cu")
		(net 335)
	)
	(arc
		(start 181.388001 120.675001)
		(mid 181.525221 121.006281)
		(end 181.856501 121.143501)
		(width 0.114)
		(layer "In7.Cu")
		(net 335)
	)
	(arc
		(start 179.906501 120.064041)
		(mid 180.034841 120.117201)
		(end 180.088001 120.245541)
		(width 0.114)
		(layer "In7.Cu")
		(net 335)
	)
	(arc
		(start 172.756501 121.143501)
		(mid 173.087781 121.006281)
		(end 173.225001 120.675001)
		(width 0.114)
		(layer "In7.Cu")
		(net 335)
	)
	(arc
		(start 177.125001 120.245541)
		(mid 177.178161 120.117201)
		(end 177.306501 120.064041)
		(width 0.114)
		(layer "In7.Cu")
		(net 335)
	)
	(arc
		(start 182.688001 120.675001)
		(mid 182.825221 121.006281)
		(end 183.156501 121.143501)
		(width 0.114)
		(layer "In7.Cu")
		(net 335)
	)
	(arc
		(start 179.256501 121.143501)
		(mid 179.587781 121.006281)
		(end 179.725001 120.675001)
		(width 0.114)
		(layer "In7.Cu")
		(net 335)
	)
	(arc
		(start 182.506501 120.064041)
		(mid 182.634841 120.117201)
		(end 182.688001 120.245541)
		(width 0.114)
		(layer "In7.Cu")
		(net 335)
	)
	(arc
		(start 177.956501 121.143501)
		(mid 178.287781 121.006281)
		(end 178.425001 120.675001)
		(width 0.114)
		(layer "In7.Cu")
		(net 335)
	)
	(arc
		(start 174.056501 121.143501)
		(mid 174.387781 121.006281)
		(end 174.525001 120.675001)
		(width 0.114)
		(layer "In7.Cu")
		(net 335)
	)
	(arc
		(start 180.556501 121.143501)
		(mid 180.887781 121.006281)
		(end 181.025001 120.675001)
		(width 0.114)
		(layer "In7.Cu")
		(net 335)
	)
	(arc
		(start 181.856501 121.143501)
		(mid 182.187781 121.006281)
		(end 182.325001 120.675001)
		(width 0.114)
		(layer "In7.Cu")
		(net 335)
	)
	(arc
		(start 181.206501 120.064041)
		(mid 181.334841 120.117201)
		(end 181.388001 120.245541)
		(width 0.114)
		(layer "In7.Cu")
		(net 335)
	)
	(arc
		(start 176.656501 121.143501)
		(mid 176.987781 121.006281)
		(end 177.125001 120.675001)
		(width 0.114)
		(layer "In7.Cu")
		(net 335)
	)
	(arc
		(start 173.588001 120.675001)
		(mid 173.725221 121.006281)
		(end 174.056501 121.143501)
		(width 0.114)
		(layer "In7.Cu")
		(net 335)
	)
	(arc
		(start 174.706501 120.064041)
		(mid 174.834841 120.117201)
		(end 174.888001 120.245541)
		(width 0.114)
		(layer "In7.Cu")
		(net 335)
	)
	(arc
		(start 174.525001 120.245541)
		(mid 174.578161 120.117201)
		(end 174.706501 120.064041)
		(width 0.114)
		(layer "In7.Cu")
		(net 335)
	)
	(arc
		(start 178.425001 120.245541)
		(mid 178.478161 120.117201)
		(end 178.606501 120.064041)
		(width 0.114)
		(layer "In7.Cu")
		(net 335)
	)
	(segment
		(start 210.81 76.48)
		(end 210.1 77.19)
		(width 0.182)
		(layer "F.Cu")
		(net 336)
	)
	(segment
		(start 210.81 75.925)
		(end 210.81 76.48)
		(width 0.182)
		(layer "F.Cu")
		(net 336)
	)
	(segment
		(start 210.1 77.19)
		(end 210.1 77.83)
		(width 0.182)
		(layer "F.Cu")
		(net 336)
	)
	(segment
		(start 156.285001 111.896198)
		(end 156.606804 112.218001)
		(width 0.16)
		(layer "F.Cu")
		(net 337)
	)
	(segment
		(start 198.5 119.5)
		(end 198 119)
		(width 0.256)
		(layer "F.Cu")
		(net 337)
	)
	(segment
		(start 156.285001 111.715001)
		(end 156.285001 111.896198)
		(width 0.16)
		(layer "F.Cu")
		(net 337)
	)
	(segment
		(start 156.775002 112.218)
		(end 156.920001 112.073001)
		(width 0.16)
		(layer "F.Cu")
		(net 337)
	)
	(segment
		(start 156.775002 112.218)
		(end 156.606804 112.218001)
		(width 0.16)
		(layer "F.Cu")
		(net 337)
	)
	(via
		(at 156.920001 112.073001)
		(size 0.45)
		(drill 0.2)
		(layers "F.Cu" "B.Cu")
		(net 337)
	)
	(via
		(at 171.069737 121.943237)
		(size 0.45)
		(drill 0.2)
		(layers "F.Cu" "B.Cu")
		(net 337)
	)
	(via
		(at 198 119)
		(size 0.45)
		(drill 0.2)
		(layers "F.Cu" "B.Cu")
		(net 337)
	)
	(segment
		(start 156.920001 112.073001)
		(end 157.053501 112.206501)
		(width 0.114)
		(layer "In3.Cu")
		(net 337)
	)
	(segment
		(start 171.069737 122.180825)
		(end 171.069737 121.943237)
		(width 0.114)
		(layer "In3.Cu")
		(net 337)
	)
	(segment
		(start 158.399441 121.726501)
		(end 169.929441 121.726501)
		(width 0.114)
		(layer "In3.Cu")
		(net 337)
	)
	(segment
		(start 157.053501 112.206501)
		(end 157.369441 112.206501)
		(width 0.114)
		(layer "In3.Cu")
		(net 337)
	)
	(segment
		(start 157.703501 113.294501)
		(end 157.703501 121.030561)
		(width 0.114)
		(layer "In3.Cu")
		(net 337)
	)
	(segment
		(start 157.810501 112.973501)
		(end 157.860037 112.973501)
		(width 0.114)
		(layer "In3.Cu")
		(net 337)
	)
	(segment
		(start 157.369441 112.206501)
		(end 157.703501 112.540561)
		(width 0.114)
		(layer "In3.Cu")
		(net 337)
	)
	(segment
		(start 169.929441 121.726501)
		(end 170.574441 122.371501)
		(width 0.114)
		(layer "In3.Cu")
		(net 337)
	)
	(segment
		(start 157.703501 121.030561)
		(end 158.399441 121.726501)
		(width 0.114)
		(layer "In3.Cu")
		(net 337)
	)
	(segment
		(start 170.879061 122.371501)
		(end 171.069737 122.180825)
		(width 0.114)
		(layer "In3.Cu")
		(net 337)
	)
	(segment
		(start 157.703501 112.540561)
		(end 157.703501 112.866501)
		(width 0.114)
		(layer "In3.Cu")
		(net 337)
	)
	(segment
		(start 170.574441 122.371501)
		(end 170.879061 122.371501)
		(width 0.114)
		(layer "In3.Cu")
		(net 337)
	)
	(segment
		(start 157.860037 113.187501)
		(end 157.810501 113.187501)
		(width 0.114)
		(layer "In3.Cu")
		(net 337)
	)
	(arc
		(start 157.967037 113.080501)
		(mid 157.935697 113.156161)
		(end 157.860037 113.187501)
		(width 0.114)
		(layer "In3.Cu")
		(net 337)
	)
	(arc
		(start 157.860037 112.973501)
		(mid 157.935697 113.004841)
		(end 157.967037 113.080501)
		(width 0.114)
		(layer "In3.Cu")
		(net 337)
	)
	(arc
		(start 157.810501 113.187501)
		(mid 157.734841 113.218841)
		(end 157.703501 113.294501)
		(width 0.114)
		(layer "In3.Cu")
		(net 337)
	)
	(arc
		(start 157.703501 112.866501)
		(mid 157.734841 112.942161)
		(end 157.810501 112.973501)
		(width 0.114)
		(layer "In3.Cu")
		(net 337)
	)
	(segment
		(start 176.475001 120.245541)
		(end 176.475001 120.675001)
		(width 0.114)
		(layer "In7.Cu")
		(net 337)
	)
	(segment
		(start 177.775001 120.245541)
		(end 177.775001 120.675001)
		(width 0.114)
		(layer "In7.Cu")
		(net 337)
	)
	(segment
		(start 174.238001 120.675001)
		(end 174.238001 120.245541)
		(width 0.114)
		(layer "In7.Cu")
		(net 337)
	)
	(segment
		(start 173.875001 120.245541)
		(end 173.875001 120.675001)
		(width 0.114)
		(layer "In7.Cu")
		(net 337)
	)
	(segment
		(start 181.675001 120.245541)
		(end 181.675001 120.675001)
		(width 0.114)
		(layer "In7.Cu")
		(net 337)
	)
	(segment
		(start 171.307325 121.943237)
		(end 172.394061 120.856501)
		(width 0.114)
		(layer "In7.Cu")
		(net 337)
	)
	(segment
		(start 182.975001 120.245541)
		(end 182.975001 120.675001)
		(width 0.114)
		(layer "In7.Cu")
		(net 337)
	)
	(segment
		(start 172.938001 120.675001)
		(end 172.938001 120.245541)
		(width 0.114)
		(layer "In7.Cu")
		(net 337)
	)
	(segment
		(start 193.633579 120.400001)
		(end 193.133579 120.900001)
		(width 0.1)
		(layer "In7.Cu")
		(net 337)
	)
	(segment
		(start 183.448501 120.900001)
		(end 183.405001 120.856501)
		(width 0.1)
		(layer "In7.Cu")
		(net 337)
	)
	(segment
		(start 175.538001 120.675001)
		(end 175.538001 120.245541)
		(width 0.114)
		(layer "In7.Cu")
		(net 337)
	)
	(segment
		(start 179.438001 120.675001)
		(end 179.438001 120.245541)
		(width 0.114)
		(layer "In7.Cu")
		(net 337)
	)
	(segment
		(start 176.838001 120.675001)
		(end 176.838001 120.245541)
		(width 0.114)
		(layer "In7.Cu")
		(net 337)
	)
	(segment
		(start 179.075001 120.245541)
		(end 179.075001 120.675001)
		(width 0.114)
		(layer "In7.Cu")
		(net 337)
	)
	(segment
		(start 171.069737 121.943237)
		(end 171.307325 121.943237)
		(width 0.114)
		(layer "In7.Cu")
		(net 337)
	)
	(segment
		(start 172.394061 120.856501)
		(end 172.756501 120.856501)
		(width 0.114)
		(layer "In7.Cu")
		(net 337)
	)
	(segment
		(start 175.175001 120.245541)
		(end 175.175001 120.675001)
		(width 0.114)
		(layer "In7.Cu")
		(net 337)
	)
	(segment
		(start 198.400001 119.400001)
		(end 198.400001 120.158579)
		(width 0.1)
		(layer "In7.Cu")
		(net 337)
	)
	(segment
		(start 193.133579 120.900001)
		(end 183.448501 120.900001)
		(width 0.1)
		(layer "In7.Cu")
		(net 337)
	)
	(segment
		(start 180.738001 120.675001)
		(end 180.738001 120.245541)
		(width 0.114)
		(layer "In7.Cu")
		(net 337)
	)
	(segment
		(start 182.038001 120.675001)
		(end 182.038001 120.245541)
		(width 0.114)
		(layer "In7.Cu")
		(net 337)
	)
	(segment
		(start 178.138001 120.675001)
		(end 178.138001 120.245541)
		(width 0.114)
		(layer "In7.Cu")
		(net 337)
	)
	(segment
		(start 198.000001 119.000001)
		(end 198.400001 119.400001)
		(width 0.1)
		(layer "In7.Cu")
		(net 337)
	)
	(segment
		(start 198.400001 120.158579)
		(end 198.158579 120.400001)
		(width 0.1)
		(layer "In7.Cu")
		(net 337)
	)
	(segment
		(start 183.156501 120.856501)
		(end 183.405001 120.856501)
		(width 0.114)
		(layer "In7.Cu")
		(net 337)
	)
	(segment
		(start 180.375001 120.245541)
		(end 180.375001 120.675001)
		(width 0.114)
		(layer "In7.Cu")
		(net 337)
	)
	(segment
		(start 198.158579 120.400001)
		(end 193.633579 120.400001)
		(width 0.1)
		(layer "In7.Cu")
		(net 337)
	)
	(arc
		(start 179.075001 120.675001)
		(mid 179.128161 120.803341)
		(end 179.256501 120.856501)
		(width 0.114)
		(layer "In7.Cu")
		(net 337)
	)
	(arc
		(start 178.606501 119.777041)
		(mid 178.937781 119.914261)
		(end 179.075001 120.245541)
		(width 0.114)
		(layer "In7.Cu")
		(net 337)
	)
	(arc
		(start 176.006501 119.777041)
		(mid 176.337781 119.914261)
		(end 176.475001 120.245541)
		(width 0.114)
		(layer "In7.Cu")
		(net 337)
	)
	(arc
		(start 176.838001 120.245541)
		(mid 176.975221 119.914261)
		(end 177.306501 119.777041)
		(width 0.114)
		(layer "In7.Cu")
		(net 337)
	)
	(arc
		(start 174.706501 119.777041)
		(mid 175.037781 119.914261)
		(end 175.175001 120.245541)
		(width 0.114)
		(layer "In7.Cu")
		(net 337)
	)
	(arc
		(start 177.956501 120.856501)
		(mid 178.084841 120.803341)
		(end 178.138001 120.675001)
		(width 0.114)
		(layer "In7.Cu")
		(net 337)
	)
	(arc
		(start 177.775001 120.675001)
		(mid 177.828161 120.803341)
		(end 177.956501 120.856501)
		(width 0.114)
		(layer "In7.Cu")
		(net 337)
	)
	(arc
		(start 175.356501 120.856501)
		(mid 175.484841 120.803341)
		(end 175.538001 120.675001)
		(width 0.114)
		(layer "In7.Cu")
		(net 337)
	)
	(arc
		(start 182.975001 120.675001)
		(mid 183.028161 120.803341)
		(end 183.156501 120.856501)
		(width 0.114)
		(layer "In7.Cu")
		(net 337)
	)
	(arc
		(start 179.256501 120.856501)
		(mid 179.384841 120.803341)
		(end 179.438001 120.675001)
		(width 0.114)
		(layer "In7.Cu")
		(net 337)
	)
	(arc
		(start 172.938001 120.245541)
		(mid 173.075221 119.914261)
		(end 173.406501 119.777041)
		(width 0.114)
		(layer "In7.Cu")
		(net 337)
	)
	(arc
		(start 179.438001 120.245541)
		(mid 179.575221 119.914261)
		(end 179.906501 119.777041)
		(width 0.114)
		(layer "In7.Cu")
		(net 337)
	)
	(arc
		(start 180.556501 120.856501)
		(mid 180.684841 120.803341)
		(end 180.738001 120.675001)
		(width 0.114)
		(layer "In7.Cu")
		(net 337)
	)
	(arc
		(start 181.206501 119.777041)
		(mid 181.537781 119.914261)
		(end 181.675001 120.245541)
		(width 0.114)
		(layer "In7.Cu")
		(net 337)
	)
	(arc
		(start 174.056501 120.856501)
		(mid 174.184841 120.803341)
		(end 174.238001 120.675001)
		(width 0.114)
		(layer "In7.Cu")
		(net 337)
	)
	(arc
		(start 174.238001 120.245541)
		(mid 174.375221 119.914261)
		(end 174.706501 119.777041)
		(width 0.114)
		(layer "In7.Cu")
		(net 337)
	)
	(arc
		(start 173.406501 119.777041)
		(mid 173.737781 119.914261)
		(end 173.875001 120.245541)
		(width 0.114)
		(layer "In7.Cu")
		(net 337)
	)
	(arc
		(start 181.856501 120.856501)
		(mid 181.984841 120.803341)
		(end 182.038001 120.675001)
		(width 0.114)
		(layer "In7.Cu")
		(net 337)
	)
	(arc
		(start 173.875001 120.675001)
		(mid 173.928161 120.803341)
		(end 174.056501 120.856501)
		(width 0.114)
		(layer "In7.Cu")
		(net 337)
	)
	(arc
		(start 178.138001 120.245541)
		(mid 178.275221 119.914261)
		(end 178.606501 119.777041)
		(width 0.114)
		(layer "In7.Cu")
		(net 337)
	)
	(arc
		(start 175.175001 120.675001)
		(mid 175.228161 120.803341)
		(end 175.356501 120.856501)
		(width 0.114)
		(layer "In7.Cu")
		(net 337)
	)
	(arc
		(start 176.656501 120.856501)
		(mid 176.784841 120.803341)
		(end 176.838001 120.675001)
		(width 0.114)
		(layer "In7.Cu")
		(net 337)
	)
	(arc
		(start 177.306501 119.777041)
		(mid 177.637781 119.914261)
		(end 177.775001 120.245541)
		(width 0.114)
		(layer "In7.Cu")
		(net 337)
	)
	(arc
		(start 179.906501 119.777041)
		(mid 180.237781 119.914261)
		(end 180.375001 120.245541)
		(width 0.114)
		(layer "In7.Cu")
		(net 337)
	)
	(arc
		(start 182.506501 119.777041)
		(mid 182.837781 119.914261)
		(end 182.975001 120.245541)
		(width 0.114)
		(layer "In7.Cu")
		(net 337)
	)
	(arc
		(start 180.738001 120.245541)
		(mid 180.875221 119.914261)
		(end 181.206501 119.777041)
		(width 0.114)
		(layer "In7.Cu")
		(net 337)
	)
	(arc
		(start 182.038001 120.245541)
		(mid 182.175221 119.914261)
		(end 182.506501 119.777041)
		(width 0.114)
		(layer "In7.Cu")
		(net 337)
	)
	(arc
		(start 180.375001 120.675001)
		(mid 180.428161 120.803341)
		(end 180.556501 120.856501)
		(width 0.114)
		(layer "In7.Cu")
		(net 337)
	)
	(arc
		(start 176.475001 120.675001)
		(mid 176.528161 120.803341)
		(end 176.656501 120.856501)
		(width 0.114)
		(layer "In7.Cu")
		(net 337)
	)
	(arc
		(start 175.538001 120.245541)
		(mid 175.675221 119.914261)
		(end 176.006501 119.777041)
		(width 0.114)
		(layer "In7.Cu")
		(net 337)
	)
	(arc
		(start 181.675001 120.675001)
		(mid 181.728161 120.803341)
		(end 181.856501 120.856501)
		(width 0.114)
		(layer "In7.Cu")
		(net 337)
	)
	(arc
		(start 172.756501 120.856501)
		(mid 172.884841 120.803341)
		(end 172.938001 120.675001)
		(width 0.114)
		(layer "In7.Cu")
		(net 337)
	)
	(segment
		(start 189.149999 183.749999)
		(end 189.6 184.2)
		(width 0.182)
		(layer "F.Cu")
		(net 338)
	)
	(segment
		(start 188.075 183.749999)
		(end 189.149999 183.749999)
		(width 0.182)
		(layer "F.Cu")
		(net 338)
	)
	(segment
		(start 188.79 188.64)
		(end 189.21 188.64)
		(width 0.182)
		(layer "F.Cu")
		(net 338)
	)
	(segment
		(start 189.21 188.64)
		(end 189.6 188.25)
		(width 0.182)
		(layer "F.Cu")
		(net 338)
	)
	(segment
		(start 189.6 184.2)
		(end 189.6 188.25)
		(width 0.182)
		(layer "F.Cu")
		(net 338)
	)
	(segment
		(start 156.285001 108.993804)
		(end 156.285001 109.175001)
		(width 0.16)
		(layer "F.Cu")
		(net 339)
	)
	(segment
		(start 156.775002 108.672002)
		(end 156.920001 108.817001)
		(width 0.16)
		(layer "F.Cu")
		(net 339)
	)
	(segment
		(start 156.606804 108.672001)
		(end 156.285001 108.993804)
		(width 0.16)
		(layer "F.Cu")
		(net 339)
	)
	(segment
		(start 198.5 121.5)
		(end 198 121)
		(width 0.256)
		(layer "F.Cu")
		(net 339)
	)
	(segment
		(start 156.775002 108.672002)
		(end 156.606804 108.672001)
		(width 0.16)
		(layer "F.Cu")
		(net 339)
	)
	(via
		(at 198 121)
		(size 0.45)
		(drill 0.2)
		(layers "F.Cu" "B.Cu")
		(net 339)
	)
	(via
		(at 156.920001 108.817001)
		(size 0.45)
		(drill 0.2)
		(layers "F.Cu" "B.Cu")
		(net 339)
	)
	(via
		(at 171.665265 109.705265)
		(size 0.45)
		(drill 0.2)
		(layers "F.Cu" "B.Cu")
		(net 339)
	)
	(segment
		(start 158.107501 108.683501)
		(end 158.160561 108.683501)
		(width 0.114)
		(layer "In3.Cu")
		(net 339)
	)
	(segment
		(start 170.511106 110.044046)
		(end 171.088896 110.044046)
		(width 0.114)
		(layer "In3.Cu")
		(net 339)
	)
	(segment
		(start 160.269441 109.313501)
		(end 169.780561 109.313501)
		(width 0.114)
		(layer "In3.Cu")
		(net 339)
	)
	(segment
		(start 171.088896 110.044046)
		(end 171.427677 109.705265)
		(width 0.114)
		(layer "In3.Cu")
		(net 339)
	)
	(segment
		(start 169.780561 109.313501)
		(end 170.511106 110.044046)
		(width 0.114)
		(layer "In3.Cu")
		(net 339)
	)
	(segment
		(start 157.532501 108.858501)
		(end 157.532501 109.188982)
		(width 0.114)
		(layer "In3.Cu")
		(net 339)
	)
	(segment
		(start 159.150561 109.673501)
		(end 159.909441 109.673501)
		(width 0.114)
		(layer "In3.Cu")
		(net 339)
	)
	(segment
		(start 158.160561 108.683501)
		(end 159.150561 109.673501)
		(width 0.114)
		(layer "In3.Cu")
		(net 339)
	)
	(segment
		(start 157.882501 109.188982)
		(end 157.882501 108.858501)
		(width 0.114)
		(layer "In3.Cu")
		(net 339)
	)
	(segment
		(start 171.427677 109.705265)
		(end 171.665265 109.705265)
		(width 0.114)
		(layer "In3.Cu")
		(net 339)
	)
	(segment
		(start 158.057501 108.683501)
		(end 158.107501 108.683501)
		(width 0.114)
		(layer "In3.Cu")
		(net 339)
	)
	(segment
		(start 156.920001 108.817001)
		(end 157.053501 108.683501)
		(width 0.114)
		(layer "In3.Cu")
		(net 339)
	)
	(segment
		(start 157.053501 108.683501)
		(end 157.357501 108.683501)
		(width 0.114)
		(layer "In3.Cu")
		(net 339)
	)
	(segment
		(start 159.909441 109.673501)
		(end 160.269441 109.313501)
		(width 0.114)
		(layer "In3.Cu")
		(net 339)
	)
	(arc
		(start 157.707501 109.363982)
		(mid 157.831245 109.312726)
		(end 157.882501 109.188982)
		(width 0.114)
		(layer "In3.Cu")
		(net 339)
	)
	(arc
		(start 157.357501 108.683501)
		(mid 157.481245 108.734757)
		(end 157.532501 108.858501)
		(width 0.114)
		(layer "In3.Cu")
		(net 339)
	)
	(arc
		(start 157.882501 108.858501)
		(mid 157.933757 108.734757)
		(end 158.057501 108.683501)
		(width 0.114)
		(layer "In3.Cu")
		(net 339)
	)
	(arc
		(start 157.532501 109.188982)
		(mid 157.583757 109.312726)
		(end 157.707501 109.363982)
		(width 0.114)
		(layer "In3.Cu")
		(net 339)
	)
	(segment
		(start 171.153501 109.979441)
		(end 171.153501 110.200561)
		(width 0.114)
		(layer "In5.Cu")
		(net 339)
	)
	(segment
		(start 178.888001 121.998421)
		(end 178.888001 121.325001)
		(width 0.114)
		(layer "In5.Cu")
		(net 339)
	)
	(segment
		(start 198.000001 121.000001)
		(end 197.600001 121.400001)
		(width 0.1)
		(layer "In5.Cu")
		(net 339)
	)
	(segment
		(start 183.448501 120.900001)
		(end 183.405001 120.856501)
		(width 0.1)
		(layer "In5.Cu")
		(net 339)
	)
	(segment
		(start 193.191423 120.900001)
		(end 183.448501 120.900001)
		(width 0.1)
		(layer "In5.Cu")
		(net 339)
	)
	(segment
		(start 182.425001 121.325001)
		(end 182.425001 121.998421)
		(width 0.114)
		(layer "In5.Cu")
		(net 339)
	)
	(segment
		(start 180.188001 121.998421)
		(end 180.188001 121.325001)
		(width 0.114)
		(layer "In5.Cu")
		(net 339)
	)
	(segment
		(start 174.625001 121.325001)
		(end 174.625001 121.998421)
		(width 0.114)
		(layer "In5.Cu")
		(net 339)
	)
	(segment
		(start 176.288001 121.998421)
		(end 176.288001 121.325001)
		(width 0.114)
		(layer "In5.Cu")
		(net 339)
	)
	(segment
		(start 171.665265 109.705265)
		(end 171.427677 109.705265)
		(width 0.114)
		(layer "In5.Cu")
		(net 339)
	)
	(segment
		(start 174.988001 121.998421)
		(end 174.988001 121.325001)
		(width 0.114)
		(layer "In5.Cu")
		(net 339)
	)
	(segment
		(start 173.809441 120.856501)
		(end 174.156501 120.856501)
		(width 0.114)
		(layer "In5.Cu")
		(net 339)
	)
	(segment
		(start 193.691423 121.400001)
		(end 193.191423 120.900001)
		(width 0.1)
		(layer "In5.Cu")
		(net 339)
	)
	(segment
		(start 171.427677 109.705265)
		(end 171.153501 109.979441)
		(width 0.114)
		(layer "In5.Cu")
		(net 339)
	)
	(segment
		(start 173.483501 112.530561)
		(end 173.483501 120.530561)
		(width 0.114)
		(layer "In5.Cu")
		(net 339)
	)
	(segment
		(start 182.788001 121.998421)
		(end 182.788001 121.325001)
		(width 0.114)
		(layer "In5.Cu")
		(net 339)
	)
	(segment
		(start 171.153501 110.200561)
		(end 173.483501 112.530561)
		(width 0.114)
		(layer "In5.Cu")
		(net 339)
	)
	(segment
		(start 181.125001 121.325001)
		(end 181.125001 121.998421)
		(width 0.114)
		(layer "In5.Cu")
		(net 339)
	)
	(segment
		(start 197.600001 121.400001)
		(end 193.691423 121.400001)
		(width 0.1)
		(layer "In5.Cu")
		(net 339)
	)
	(segment
		(start 177.588001 121.998421)
		(end 177.588001 121.325001)
		(width 0.114)
		(layer "In5.Cu")
		(net 339)
	)
	(segment
		(start 181.488001 121.998421)
		(end 181.488001 121.325001)
		(width 0.114)
		(layer "In5.Cu")
		(net 339)
	)
	(segment
		(start 175.925001 121.325001)
		(end 175.925001 121.998421)
		(width 0.114)
		(layer "In5.Cu")
		(net 339)
	)
	(segment
		(start 177.225001 121.325001)
		(end 177.225001 121.998421)
		(width 0.114)
		(layer "In5.Cu")
		(net 339)
	)
	(segment
		(start 179.825001 121.325001)
		(end 179.825001 121.998421)
		(width 0.114)
		(layer "In5.Cu")
		(net 339)
	)
	(segment
		(start 183.256501 120.856501)
		(end 183.405001 120.856501)
		(width 0.114)
		(layer "In5.Cu")
		(net 339)
	)
	(segment
		(start 178.525001 121.325001)
		(end 178.525001 121.998421)
		(width 0.114)
		(layer "In5.Cu")
		(net 339)
	)
	(segment
		(start 173.483501 120.530561)
		(end 173.809441 120.856501)
		(width 0.114)
		(layer "In5.Cu")
		(net 339)
	)
	(arc
		(start 178.525001 121.998421)
		(mid 178.578161 122.126761)
		(end 178.706501 122.179921)
		(width 0.114)
		(layer "In5.Cu")
		(net 339)
	)
	(arc
		(start 176.756501 120.856501)
		(mid 177.087781 120.993721)
		(end 177.225001 121.325001)
		(width 0.114)
		(layer "In5.Cu")
		(net 339)
	)
	(arc
		(start 177.225001 121.998421)
		(mid 177.278161 122.126761)
		(end 177.406501 122.179921)
		(width 0.114)
		(layer "In5.Cu")
		(net 339)
	)
	(arc
		(start 178.056501 120.856501)
		(mid 178.387781 120.993721)
		(end 178.525001 121.325001)
		(width 0.114)
		(layer "In5.Cu")
		(net 339)
	)
	(arc
		(start 176.106501 122.179921)
		(mid 176.234841 122.126761)
		(end 176.288001 121.998421)
		(width 0.114)
		(layer "In5.Cu")
		(net 339)
	)
	(arc
		(start 180.656501 120.856501)
		(mid 180.987781 120.993721)
		(end 181.125001 121.325001)
		(width 0.114)
		(layer "In5.Cu")
		(net 339)
	)
	(arc
		(start 179.825001 121.998421)
		(mid 179.878161 122.126761)
		(end 180.006501 122.179921)
		(width 0.114)
		(layer "In5.Cu")
		(net 339)
	)
	(arc
		(start 181.125001 121.998421)
		(mid 181.178161 122.126761)
		(end 181.306501 122.179921)
		(width 0.114)
		(layer "In5.Cu")
		(net 339)
	)
	(arc
		(start 182.606501 122.179921)
		(mid 182.734841 122.126761)
		(end 182.788001 121.998421)
		(width 0.114)
		(layer "In5.Cu")
		(net 339)
	)
	(arc
		(start 176.288001 121.325001)
		(mid 176.425221 120.993721)
		(end 176.756501 120.856501)
		(width 0.114)
		(layer "In5.Cu")
		(net 339)
	)
	(arc
		(start 180.006501 122.179921)
		(mid 180.134841 122.126761)
		(end 180.188001 121.998421)
		(width 0.114)
		(layer "In5.Cu")
		(net 339)
	)
	(arc
		(start 179.356501 120.856501)
		(mid 179.687781 120.993721)
		(end 179.825001 121.325001)
		(width 0.114)
		(layer "In5.Cu")
		(net 339)
	)
	(arc
		(start 182.425001 121.998421)
		(mid 182.478161 122.126761)
		(end 182.606501 122.179921)
		(width 0.114)
		(layer "In5.Cu")
		(net 339)
	)
	(arc
		(start 174.806501 122.179921)
		(mid 174.934841 122.126761)
		(end 174.988001 121.998421)
		(width 0.114)
		(layer "In5.Cu")
		(net 339)
	)
	(arc
		(start 181.488001 121.325001)
		(mid 181.625221 120.993721)
		(end 181.956501 120.856501)
		(width 0.114)
		(layer "In5.Cu")
		(net 339)
	)
	(arc
		(start 181.956501 120.856501)
		(mid 182.287781 120.993721)
		(end 182.425001 121.325001)
		(width 0.114)
		(layer "In5.Cu")
		(net 339)
	)
	(arc
		(start 180.188001 121.325001)
		(mid 180.325221 120.993721)
		(end 180.656501 120.856501)
		(width 0.114)
		(layer "In5.Cu")
		(net 339)
	)
	(arc
		(start 177.588001 121.325001)
		(mid 177.725221 120.993721)
		(end 178.056501 120.856501)
		(width 0.114)
		(layer "In5.Cu")
		(net 339)
	)
	(arc
		(start 174.156501 120.856501)
		(mid 174.487781 120.993721)
		(end 174.625001 121.325001)
		(width 0.114)
		(layer "In5.Cu")
		(net 339)
	)
	(arc
		(start 177.406501 122.179921)
		(mid 177.534841 122.126761)
		(end 177.588001 121.998421)
		(width 0.114)
		(layer "In5.Cu")
		(net 339)
	)
	(arc
		(start 174.625001 121.998421)
		(mid 174.678161 122.126761)
		(end 174.806501 122.179921)
		(width 0.114)
		(layer "In5.Cu")
		(net 339)
	)
	(arc
		(start 175.925001 121.998421)
		(mid 175.978161 122.126761)
		(end 176.106501 122.179921)
		(width 0.114)
		(layer "In5.Cu")
		(net 339)
	)
	(arc
		(start 175.456501 120.856501)
		(mid 175.787781 120.993721)
		(end 175.925001 121.325001)
		(width 0.114)
		(layer "In5.Cu")
		(net 339)
	)
	(arc
		(start 178.888001 121.325001)
		(mid 179.025221 120.993721)
		(end 179.356501 120.856501)
		(width 0.114)
		(layer "In5.Cu")
		(net 339)
	)
	(arc
		(start 178.706501 122.179921)
		(mid 178.834841 122.126761)
		(end 178.888001 121.998421)
		(width 0.114)
		(layer "In5.Cu")
		(net 339)
	)
	(arc
		(start 181.306501 122.179921)
		(mid 181.434841 122.126761)
		(end 181.488001 121.998421)
		(width 0.114)
		(layer "In5.Cu")
		(net 339)
	)
	(arc
		(start 174.988001 121.325001)
		(mid 175.125221 120.993721)
		(end 175.456501 120.856501)
		(width 0.114)
		(layer "In5.Cu")
		(net 339)
	)
	(arc
		(start 182.788001 121.325001)
		(mid 182.925221 120.993721)
		(end 183.256501 120.856501)
		(width 0.114)
		(layer "In5.Cu")
		(net 339)
	)
	(segment
		(start 156.775002 108.408)
		(end 156.920001 108.263001)
		(width 0.16)
		(layer "F.Cu")
		(net 340)
	)
	(segment
		(start 156.285001 107.905001)
		(end 156.285001 108.086198)
		(width 0.16)
		(layer "F.Cu")
		(net 340)
	)
	(segment
		(start 156.775002 108.408)
		(end 156.606804 108.408001)
		(width 0.16)
		(layer "F.Cu")
		(net 340)
	)
	(segment
		(start 156.285001 108.086198)
		(end 156.606804 108.408001)
		(width 0.16)
		(layer "F.Cu")
		(net 340)
	)
	(segment
		(start 198.5 122.5)
		(end 198.025001 122.025001)
		(width 0.256)
		(layer "F.Cu")
		(net 340)
	)
	(segment
		(start 198.025001 122.025001)
		(end 198.025001 121.975)
		(width 0.256)
		(layer "F.Cu")
		(net 340)
	)
	(via
		(at 198.025001 121.975)
		(size 0.45)
		(drill 0.2)
		(layers "F.Cu" "B.Cu")
		(net 340)
	)
	(via
		(at 156.920001 108.263001)
		(size 0.45)
		(drill 0.2)
		(layers "F.Cu" "B.Cu")
		(net 340)
	)
	(via
		(at 171.224737 109.264737)
		(size 0.45)
		(drill 0.2)
		(layers "F.Cu" "B.Cu")
		(net 340)
	)
	(segment
		(start 159.269441 109.386501)
		(end 158.279441 108.396501)
		(width 0.114)
		(layer "In3.Cu")
		(net 340)
	)
	(segment
		(start 160.150561 109.026501)
		(end 159.790561 109.386501)
		(width 0.114)
		(layer "In3.Cu")
		(net 340)
	)
	(segment
		(start 159.790561 109.386501)
		(end 159.269441 109.386501)
		(width 0.114)
		(layer "In3.Cu")
		(net 340)
	)
	(segment
		(start 170.629986 109.757046)
		(end 169.899441 109.026501)
		(width 0.114)
		(layer "In3.Cu")
		(net 340)
	)
	(segment
		(start 171.224737 109.502325)
		(end 170.970016 109.757046)
		(width 0.114)
		(layer "In3.Cu")
		(net 340)
	)
	(segment
		(start 158.279441 108.396501)
		(end 157.053501 108.396501)
		(width 0.114)
		(layer "In3.Cu")
		(net 340)
	)
	(segment
		(start 169.899441 109.026501)
		(end 160.150561 109.026501)
		(width 0.114)
		(layer "In3.Cu")
		(net 340)
	)
	(segment
		(start 170.970016 109.757046)
		(end 170.629986 109.757046)
		(width 0.114)
		(layer "In3.Cu")
		(net 340)
	)
	(segment
		(start 157.053501 108.396501)
		(end 156.920001 108.263001)
		(width 0.114)
		(layer "In3.Cu")
		(net 340)
	)
	(segment
		(start 171.224737 109.264737)
		(end 171.224737 109.502325)
		(width 0.114)
		(layer "In3.Cu")
		(net 340)
	)
	(segment
		(start 181.775001 121.998421)
		(end 181.775001 121.325001)
		(width 0.114)
		(layer "In5.Cu")
		(net 340)
	)
	(segment
		(start 193.608579 121.600001)
		(end 193.108579 121.100001)
		(width 0.1)
		(layer "In5.Cu")
		(net 340)
	)
	(segment
		(start 170.866501 109.860561)
		(end 170.866501 110.319441)
		(width 0.114)
		(layer "In5.Cu")
		(net 340)
	)
	(segment
		(start 183.256501 121.143501)
		(end 183.405001 121.143501)
		(width 0.114)
		(layer "In5.Cu")
		(net 340)
	)
	(segment
		(start 175.275001 121.998421)
		(end 175.275001 121.325001)
		(width 0.114)
		(layer "In5.Cu")
		(net 340)
	)
	(segment
		(start 177.875001 121.998421)
		(end 177.875001 121.325001)
		(width 0.114)
		(layer "In5.Cu")
		(net 340)
	)
	(segment
		(start 183.075001 121.998421)
		(end 183.075001 121.325001)
		(width 0.114)
		(layer "In5.Cu")
		(net 340)
	)
	(segment
		(start 175.638001 121.325001)
		(end 175.638001 121.998421)
		(width 0.114)
		(layer "In5.Cu")
		(net 340)
	)
	(segment
		(start 176.938001 121.325001)
		(end 176.938001 121.998421)
		(width 0.114)
		(layer "In5.Cu")
		(net 340)
	)
	(segment
		(start 179.175001 121.998421)
		(end 179.175001 121.325001)
		(width 0.114)
		(layer "In5.Cu")
		(net 340)
	)
	(segment
		(start 180.838001 121.325001)
		(end 180.838001 121.998421)
		(width 0.114)
		(layer "In5.Cu")
		(net 340)
	)
	(segment
		(start 198.000001 122.000001)
		(end 197.600001 121.600001)
		(width 0.1)
		(layer "In5.Cu")
		(net 340)
	)
	(segment
		(start 173.196501 112.649441)
		(end 173.196501 120.649441)
		(width 0.114)
		(layer "In5.Cu")
		(net 340)
	)
	(segment
		(start 170.866501 110.319441)
		(end 173.196501 112.649441)
		(width 0.114)
		(layer "In5.Cu")
		(net 340)
	)
	(segment
		(start 179.538001 121.325001)
		(end 179.538001 121.998421)
		(width 0.114)
		(layer "In5.Cu")
		(net 340)
	)
	(segment
		(start 171.224737 109.264737)
		(end 171.224737 109.502325)
		(width 0.114)
		(layer "In5.Cu")
		(net 340)
	)
	(segment
		(start 193.108579 121.100001)
		(end 183.448501 121.100001)
		(width 0.1)
		(layer "In5.Cu")
		(net 340)
	)
	(segment
		(start 182.138001 121.325001)
		(end 182.138001 121.998421)
		(width 0.114)
		(layer "In5.Cu")
		(net 340)
	)
	(segment
		(start 180.475001 121.998421)
		(end 180.475001 121.325001)
		(width 0.114)
		(layer "In5.Cu")
		(net 340)
	)
	(segment
		(start 173.196501 120.649441)
		(end 173.690561 121.143501)
		(width 0.114)
		(layer "In5.Cu")
		(net 340)
	)
	(segment
		(start 178.238001 121.325001)
		(end 178.238001 121.998421)
		(width 0.114)
		(layer "In5.Cu")
		(net 340)
	)
	(segment
		(start 174.338001 121.325001)
		(end 174.338001 121.998421)
		(width 0.114)
		(layer "In5.Cu")
		(net 340)
	)
	(segment
		(start 197.600001 121.600001)
		(end 193.608579 121.600001)
		(width 0.1)
		(layer "In5.Cu")
		(net 340)
	)
	(segment
		(start 171.224737 109.502325)
		(end 170.866501 109.860561)
		(width 0.114)
		(layer "In5.Cu")
		(net 340)
	)
	(segment
		(start 176.575001 121.998421)
		(end 176.575001 121.325001)
		(width 0.114)
		(layer "In5.Cu")
		(net 340)
	)
	(segment
		(start 183.448501 121.100001)
		(end 183.405001 121.143501)
		(width 0.1)
		(layer "In5.Cu")
		(net 340)
	)
	(segment
		(start 173.690561 121.143501)
		(end 174.156501 121.143501)
		(width 0.114)
		(layer "In5.Cu")
		(net 340)
	)
	(arc
		(start 174.338001 121.998421)
		(mid 174.475221 122.329701)
		(end 174.806501 122.466921)
		(width 0.114)
		(layer "In5.Cu")
		(net 340)
	)
	(arc
		(start 176.756501 121.143501)
		(mid 176.884841 121.196661)
		(end 176.938001 121.325001)
		(width 0.114)
		(layer "In5.Cu")
		(net 340)
	)
	(arc
		(start 175.275001 121.325001)
		(mid 175.328161 121.196661)
		(end 175.456501 121.143501)
		(width 0.114)
		(layer "In5.Cu")
		(net 340)
	)
	(arc
		(start 183.075001 121.325001)
		(mid 183.128161 121.196661)
		(end 183.256501 121.143501)
		(width 0.114)
		(layer "In5.Cu")
		(net 340)
	)
	(arc
		(start 176.575001 121.325001)
		(mid 176.628161 121.196661)
		(end 176.756501 121.143501)
		(width 0.114)
		(layer "In5.Cu")
		(net 340)
	)
	(arc
		(start 180.838001 121.998421)
		(mid 180.975221 122.329701)
		(end 181.306501 122.466921)
		(width 0.114)
		(layer "In5.Cu")
		(net 340)
	)
	(arc
		(start 180.475001 121.325001)
		(mid 180.528161 121.196661)
		(end 180.656501 121.143501)
		(width 0.114)
		(layer "In5.Cu")
		(net 340)
	)
	(arc
		(start 182.606501 122.466921)
		(mid 182.937781 122.329701)
		(end 183.075001 121.998421)
		(width 0.114)
		(layer "In5.Cu")
		(net 340)
	)
	(arc
		(start 180.656501 121.143501)
		(mid 180.784841 121.196661)
		(end 180.838001 121.325001)
		(width 0.114)
		(layer "In5.Cu")
		(net 340)
	)
	(arc
		(start 182.138001 121.998421)
		(mid 182.275221 122.329701)
		(end 182.606501 122.466921)
		(width 0.114)
		(layer "In5.Cu")
		(net 340)
	)
	(arc
		(start 176.938001 121.998421)
		(mid 177.075221 122.329701)
		(end 177.406501 122.466921)
		(width 0.114)
		(layer "In5.Cu")
		(net 340)
	)
	(arc
		(start 175.638001 121.998421)
		(mid 175.775221 122.329701)
		(end 176.106501 122.466921)
		(width 0.114)
		(layer "In5.Cu")
		(net 340)
	)
	(arc
		(start 178.238001 121.998421)
		(mid 178.375221 122.329701)
		(end 178.706501 122.466921)
		(width 0.114)
		(layer "In5.Cu")
		(net 340)
	)
	(arc
		(start 179.175001 121.325001)
		(mid 179.228161 121.196661)
		(end 179.356501 121.143501)
		(width 0.114)
		(layer "In5.Cu")
		(net 340)
	)
	(arc
		(start 177.406501 122.466921)
		(mid 177.737781 122.329701)
		(end 177.875001 121.998421)
		(width 0.114)
		(layer "In5.Cu")
		(net 340)
	)
	(arc
		(start 179.538001 121.998421)
		(mid 179.675221 122.329701)
		(end 180.006501 122.466921)
		(width 0.114)
		(layer "In5.Cu")
		(net 340)
	)
	(arc
		(start 174.156501 121.143501)
		(mid 174.284841 121.196661)
		(end 174.338001 121.325001)
		(width 0.114)
		(layer "In5.Cu")
		(net 340)
	)
	(arc
		(start 180.006501 122.466921)
		(mid 180.337781 122.329701)
		(end 180.475001 121.998421)
		(width 0.114)
		(layer "In5.Cu")
		(net 340)
	)
	(arc
		(start 181.775001 121.325001)
		(mid 181.828161 121.196661)
		(end 181.956501 121.143501)
		(width 0.114)
		(layer "In5.Cu")
		(net 340)
	)
	(arc
		(start 175.456501 121.143501)
		(mid 175.584841 121.196661)
		(end 175.638001 121.325001)
		(width 0.114)
		(layer "In5.Cu")
		(net 340)
	)
	(arc
		(start 178.056501 121.143501)
		(mid 178.184841 121.196661)
		(end 178.238001 121.325001)
		(width 0.114)
		(layer "In5.Cu")
		(net 340)
	)
	(arc
		(start 181.306501 122.466921)
		(mid 181.637781 122.329701)
		(end 181.775001 121.998421)
		(width 0.114)
		(layer "In5.Cu")
		(net 340)
	)
	(arc
		(start 176.106501 122.466921)
		(mid 176.437781 122.329701)
		(end 176.575001 121.998421)
		(width 0.114)
		(layer "In5.Cu")
		(net 340)
	)
	(arc
		(start 177.875001 121.325001)
		(mid 177.928161 121.196661)
		(end 178.056501 121.143501)
		(width 0.114)
		(layer "In5.Cu")
		(net 340)
	)
	(arc
		(start 179.356501 121.143501)
		(mid 179.484841 121.196661)
		(end 179.538001 121.325001)
		(width 0.114)
		(layer "In5.Cu")
		(net 340)
	)
	(arc
		(start 174.806501 122.466921)
		(mid 175.137781 122.329701)
		(end 175.275001 121.998421)
		(width 0.114)
		(layer "In5.Cu")
		(net 340)
	)
	(arc
		(start 181.956501 121.143501)
		(mid 182.084841 121.196661)
		(end 182.138001 121.325001)
		(width 0.114)
		(layer "In5.Cu")
		(net 340)
	)
	(arc
		(start 178.706501 122.466921)
		(mid 179.037781 122.329701)
		(end 179.175001 121.998421)
		(width 0.114)
		(layer "In5.Cu")
		(net 340)
	)
	(segment
		(start 190.6 170.4)
		(end 190.35 170.65)
		(width 0.182)
		(layer "F.Cu")
		(net 341)
	)
	(segment
		(start 190.5 168.7)
		(end 190.6 168.8)
		(width 0.182)
		(layer "F.Cu")
		(net 341)
	)
	(segment
		(start 189.01 173.34)
		(end 188.6325 173.34)
		(width 0.182)
		(layer "F.Cu")
		(net 341)
	)
	(segment
		(start 189.6 170.65)
		(end 189.45 170.8)
		(width 0.182)
		(layer "F.Cu")
		(net 341)
	)
	(segment
		(start 189.45 170.8)
		(end 189.45 172.9)
		(width 0.182)
		(layer "F.Cu")
		(net 341)
	)
	(segment
		(start 190.35 170.65)
		(end 189.6 170.65)
		(width 0.182)
		(layer "F.Cu")
		(net 341)
	)
	(segment
		(start 189.45 172.9)
		(end 189.01 173.34)
		(width 0.182)
		(layer "F.Cu")
		(net 341)
	)
	(segment
		(start 189.65 168.7)
		(end 190.5 168.7)
		(width 0.182)
		(layer "F.Cu")
		(net 341)
	)
	(segment
		(start 190.6 168.8)
		(end 190.6 170.4)
		(width 0.182)
		(layer "F.Cu")
		(net 341)
	)
	(segment
		(start 188.9 176.15)
		(end 187.875 176.15)
		(width 0.182)
		(layer "F.Cu")
		(net 342)
	)
	(segment
		(start 188.59 180.94)
		(end 189.01 180.94)
		(width 0.182)
		(layer "F.Cu")
		(net 342)
	)
	(segment
		(start 189.425 176.675)
		(end 188.9 176.15)
		(width 0.182)
		(layer "F.Cu")
		(net 342)
	)
	(segment
		(start 189.425 180.525)
		(end 189.425 176.675)
		(width 0.182)
		(layer "F.Cu")
		(net 342)
	)
	(segment
		(start 189.01 180.94)
		(end 189.425 180.525)
		(width 0.182)
		(layer "F.Cu")
		(net 342)
	)
	(segment
		(start 241.15 143.1)
		(end 241.22 143.1)
		(width 0.1)
		(layer "B.Cu")
		(net 343)
	)
	(segment
		(start 241.22 143.1)
		(end 241.75 142.57)
		(width 0.1)
		(layer "B.Cu")
		(net 343)
	)
	(segment
		(start 241.75 142.57)
		(end 242.205 142.57)
		(width 0.1)
		(layer "B.Cu")
		(net 343)
	)
	(segment
		(start 242.205 142.57)
		(end 242.3 142.665)
		(width 0.1)
		(layer "B.Cu")
		(net 343)
	)
	(segment
		(start 254.8 174.975)
		(end 255.225 175.4)
		(width 0.1)
		(layer "B.Cu")
		(net 344)
	)
	(segment
		(start 256.9 175.1625)
		(end 256.9 173.37262)
		(width 0.1)
		(layer "B.Cu")
		(net 344)
	)
	(segment
		(start 254.8 173.53262)
		(end 254.8 174.975)
		(width 0.1)
		(layer "B.Cu")
		(net 344)
	)
	(segment
		(start 255.225 175.4)
		(end 256.6625 175.4)
		(width 0.1)
		(layer "B.Cu")
		(net 344)
	)
	(segment
		(start 256.6625 175.4)
		(end 256.9 175.1625)
		(width 0.1)
		(layer "B.Cu")
		(net 344)
	)
	(segment
		(start 218.0375 163.8875)
		(end 218.315 164.165)
		(width 0.1)
		(layer "F.Cu")
		(net 345)
	)
	(segment
		(start 217.1457 163.8875)
		(end 218.0375 163.8875)
		(width 0.1)
		(layer "F.Cu")
		(net 345)
	)
	(segment
		(start 218.315 164.165)
		(end 218.315 165.7)
		(width 0.1)
		(layer "F.Cu")
		(net 345)
	)
	(segment
		(start 199.5 115.5)
		(end 199 115)
		(width 0.256)
		(layer "F.Cu")
		(net 349)
	)
	(segment
		(start 158.045002 115.022002)
		(end 158.190001 115.167001)
		(width 0.16)
		(layer "F.Cu")
		(net 349)
	)
	(segment
		(start 157.876804 115.022001)
		(end 157.555001 115.343804)
		(width 0.16)
		(layer "F.Cu")
		(net 349)
	)
	(segment
		(start 158.045002 115.022002)
		(end 157.876804 115.022001)
		(width 0.16)
		(layer "F.Cu")
		(net 349)
	)
	(segment
		(start 157.555001 115.343804)
		(end 157.555001 115.525001)
		(width 0.16)
		(layer "F.Cu")
		(net 349)
	)
	(via
		(at 158.190001 115.167001)
		(size 0.45)
		(drill 0.2)
		(layers "F.Cu" "B.Cu")
		(net 349)
	)
	(via
		(at 199 115)
		(size 0.45)
		(drill 0.2)
		(layers "F.Cu" "B.Cu")
		(net 349)
	)
	(segment
		(start 158.056501 115.033501)
		(end 158.190001 115.167001)
		(width 0.114)
		(layer "In7.Cu")
		(net 349)
	)
	(segment
		(start 157.406501 87.155309)
		(end 153.512501 91.049309)
		(width 0.114)
		(layer "In7.Cu")
		(net 349)
	)
	(segment
		(start 153.512501 114.277501)
		(end 153.512501 115.233501)
		(width 0.114)
		(layer "In7.Cu")
		(net 349)
	)
	(segment
		(start 156.969441 115.033501)
		(end 158.056501 115.033501)
		(width 0.114)
		(layer "In7.Cu")
		(net 349)
	)
	(segment
		(start 197.350001 114.208579)
		(end 197.350001 113.448501)
		(width 0.1)
		(layer "In7.Cu")
		(net 349)
	)
	(segment
		(start 153.512501 91.049309)
		(end 153.512501 112.777501)
		(width 0.114)
		(layer "In7.Cu")
		(net 349)
	)
	(segment
		(start 198.141423 115.000001)
		(end 197.350001 114.208579)
		(width 0.1)
		(layer "In7.Cu")
		(net 349)
	)
	(segment
		(start 197.393501 113.405001)
		(end 197.393501 112.205561)
		(width 0.114)
		(layer "In7.Cu")
		(net 349)
	)
	(segment
		(start 153.512501 115.233501)
		(end 154.072501 115.793501)
		(width 0.114)
		(layer "In7.Cu")
		(net 349)
	)
	(segment
		(start 172.204441 88.081501)
		(end 170.304441 86.181501)
		(width 0.114)
		(layer "In7.Cu")
		(net 349)
	)
	(segment
		(start 199.000001 115.000001)
		(end 198.141423 115.000001)
		(width 0.1)
		(layer "In7.Cu")
		(net 349)
	)
	(segment
		(start 157.856175 86.181501)
		(end 157.406501 86.631175)
		(width 0.114)
		(layer "In7.Cu")
		(net 349)
	)
	(segment
		(start 197.350001 113.448501)
		(end 197.393501 113.405001)
		(width 0.1)
		(layer "In7.Cu")
		(net 349)
	)
	(segment
		(start 170.304441 86.181501)
		(end 157.856175 86.181501)
		(width 0.114)
		(layer "In7.Cu")
		(net 349)
	)
	(segment
		(start 173.269441 88.081501)
		(end 172.204441 88.081501)
		(width 0.114)
		(layer "In7.Cu")
		(net 349)
	)
	(segment
		(start 197.393501 112.205561)
		(end 173.269441 88.081501)
		(width 0.114)
		(layer "In7.Cu")
		(net 349)
	)
	(segment
		(start 157.406501 86.631175)
		(end 157.406501 87.155309)
		(width 0.114)
		(layer "In7.Cu")
		(net 349)
	)
	(segment
		(start 156.209441 115.793501)
		(end 156.969441 115.033501)
		(width 0.114)
		(layer "In7.Cu")
		(net 349)
	)
	(segment
		(start 154.424501 113.759001)
		(end 154.031001 113.759001)
		(width 0.114)
		(layer "In7.Cu")
		(net 349)
	)
	(segment
		(start 154.072501 115.793501)
		(end 156.209441 115.793501)
		(width 0.114)
		(layer "In7.Cu")
		(net 349)
	)
	(segment
		(start 154.031001 113.296001)
		(end 154.424501 113.296001)
		(width 0.114)
		(layer "In7.Cu")
		(net 349)
	)
	(arc
		(start 154.424501 113.296001)
		(mid 154.588196 113.363806)
		(end 154.656001 113.527501)
		(width 0.114)
		(layer "In7.Cu")
		(net 349)
	)
	(arc
		(start 154.031001 113.759001)
		(mid 153.664366 113.910866)
		(end 153.512501 114.277501)
		(width 0.114)
		(layer "In7.Cu")
		(net 349)
	)
	(arc
		(start 154.656001 113.527501)
		(mid 154.588196 113.691196)
		(end 154.424501 113.759001)
		(width 0.114)
		(layer "In7.Cu")
		(net 349)
	)
	(arc
		(start 153.512501 112.777501)
		(mid 153.664366 113.144136)
		(end 154.031001 113.296001)
		(width 0.114)
		(layer "In7.Cu")
		(net 349)
	)
	(segment
		(start 158.045002 114.758)
		(end 157.876804 114.758001)
		(width 0.16)
		(layer "F.Cu")
		(net 350)
	)
	(segment
		(start 157.555001 114.436198)
		(end 157.876804 114.758001)
		(width 0.16)
		(layer "F.Cu")
		(net 350)
	)
	(segment
		(start 158.045002 114.758)
		(end 158.190001 114.613001)
		(width 0.16)
		(layer "F.Cu")
		(net 350)
	)
	(segment
		(start 198.5 116.5)
		(end 198 116)
		(width 0.256)
		(layer "F.Cu")
		(net 350)
	)
	(segment
		(start 157.555001 114.255001)
		(end 157.555001 114.436198)
		(width 0.16)
		(layer "F.Cu")
		(net 350)
	)
	(via
		(at 198 116)
		(size 0.45)
		(drill 0.2)
		(layers "F.Cu" "B.Cu")
		(net 350)
	)
	(via
		(at 158.190001 114.613001)
		(size 0.45)
		(drill 0.2)
		(layers "F.Cu" "B.Cu")
		(net 350)
	)
	(segment
		(start 198.000001 116.000001)
		(end 198.000001 115.141423)
		(width 0.1)
		(layer "In7.Cu")
		(net 350)
	)
	(segment
		(start 173.150561 88.368501)
		(end 172.085561 88.368501)
		(width 0.114)
		(layer "In7.Cu")
		(net 350)
	)
	(segment
		(start 154.424501 114.046001)
		(end 154.031001 114.046001)
		(width 0.114)
		(layer "In7.Cu")
		(net 350)
	)
	(segment
		(start 156.090561 115.506501)
		(end 156.850561 114.746501)
		(width 0.114)
		(layer "In7.Cu")
		(net 350)
	)
	(segment
		(start 157.975055 86.468501)
		(end 157.693501 86.750055)
		(width 0.114)
		(layer "In7.Cu")
		(net 350)
	)
	(segment
		(start 154.192501 115.506501)
		(end 156.090561 115.506501)
		(width 0.114)
		(layer "In7.Cu")
		(net 350)
	)
	(segment
		(start 198.000001 115.141423)
		(end 197.150001 114.291423)
		(width 0.1)
		(layer "In7.Cu")
		(net 350)
	)
	(segment
		(start 158.056501 114.746501)
		(end 158.190001 114.613001)
		(width 0.114)
		(layer "In7.Cu")
		(net 350)
	)
	(segment
		(start 157.693501 87.274189)
		(end 153.799501 91.168189)
		(width 0.114)
		(layer "In7.Cu")
		(net 350)
	)
	(segment
		(start 197.150001 113.448501)
		(end 197.106501 113.405001)
		(width 0.1)
		(layer "In7.Cu")
		(net 350)
	)
	(segment
		(start 156.850561 114.746501)
		(end 156.983501 114.746501)
		(width 0.114)
		(layer "In7.Cu")
		(net 350)
	)
	(segment
		(start 153.799501 115.113501)
		(end 154.192501 115.506501)
		(width 0.114)
		(layer "In7.Cu")
		(net 350)
	)
	(segment
		(start 154.031001 113.009001)
		(end 154.424501 113.009001)
		(width 0.114)
		(layer "In7.Cu")
		(net 350)
	)
	(segment
		(start 157.679501 114.306916)
		(end 157.679501 114.514501)
		(width 0.114)
		(layer "In7.Cu")
		(net 350)
	)
	(segment
		(start 197.106501 112.324441)
		(end 173.150561 88.368501)
		(width 0.114)
		(layer "In7.Cu")
		(net 350)
	)
	(segment
		(start 157.215501 114.514501)
		(end 157.215501 114.306916)
		(width 0.114)
		(layer "In7.Cu")
		(net 350)
	)
	(segment
		(start 197.106501 113.405001)
		(end 197.106501 112.324441)
		(width 0.114)
		(layer "In7.Cu")
		(net 350)
	)
	(segment
		(start 170.185561 86.468501)
		(end 157.975055 86.468501)
		(width 0.114)
		(layer "In7.Cu")
		(net 350)
	)
	(segment
		(start 197.150001 114.291423)
		(end 197.150001 113.448501)
		(width 0.1)
		(layer "In7.Cu")
		(net 350)
	)
	(segment
		(start 157.911501 114.746501)
		(end 158.056501 114.746501)
		(width 0.114)
		(layer "In7.Cu")
		(net 350)
	)
	(segment
		(start 172.085561 88.368501)
		(end 170.185561 86.468501)
		(width 0.114)
		(layer "In7.Cu")
		(net 350)
	)
	(segment
		(start 157.693501 86.750055)
		(end 157.693501 87.274189)
		(width 0.114)
		(layer "In7.Cu")
		(net 350)
	)
	(segment
		(start 153.799501 114.277501)
		(end 153.799501 115.113501)
		(width 0.114)
		(layer "In7.Cu")
		(net 350)
	)
	(segment
		(start 153.799501 91.168189)
		(end 153.799501 112.777501)
		(width 0.114)
		(layer "In7.Cu")
		(net 350)
	)
	(arc
		(start 157.679501 114.514501)
		(mid 157.747452 114.67855)
		(end 157.911501 114.746501)
		(width 0.114)
		(layer "In7.Cu")
		(net 350)
	)
	(arc
		(start 154.943001 113.527501)
		(mid 154.791136 113.894136)
		(end 154.424501 114.046001)
		(width 0.114)
		(layer "In7.Cu")
		(net 350)
	)
	(arc
		(start 157.447501 114.074916)
		(mid 157.61155 114.142867)
		(end 157.679501 114.306916)
		(width 0.114)
		(layer "In7.Cu")
		(net 350)
	)
	(arc
		(start 157.215501 114.306916)
		(mid 157.283452 114.142867)
		(end 157.447501 114.074916)
		(width 0.114)
		(layer "In7.Cu")
		(net 350)
	)
	(arc
		(start 154.031001 114.046001)
		(mid 153.867306 114.113806)
		(end 153.799501 114.277501)
		(width 0.114)
		(layer "In7.Cu")
		(net 350)
	)
	(arc
		(start 154.424501 113.009001)
		(mid 154.791136 113.160866)
		(end 154.943001 113.527501)
		(width 0.114)
		(layer "In7.Cu")
		(net 350)
	)
	(arc
		(start 156.983501 114.746501)
		(mid 157.14755 114.67855)
		(end 157.215501 114.514501)
		(width 0.114)
		(layer "In7.Cu")
		(net 350)
	)
	(arc
		(start 153.799501 112.777501)
		(mid 153.867306 112.941196)
		(end 154.031001 113.009001)
		(width 0.114)
		(layer "In7.Cu")
		(net 350)
	)
	(segment
		(start 158.045002 111.212002)
		(end 157.876804 111.212001)
		(width 0.16)
		(layer "F.Cu")
		(net 351)
	)
	(segment
		(start 157.555001 111.533804)
		(end 157.555001 111.715001)
		(width 0.16)
		(layer "F.Cu")
		(net 351)
	)
	(segment
		(start 157.876804 111.212001)
		(end 157.555001 111.533804)
		(width 0.16)
		(layer "F.Cu")
		(net 351)
	)
	(segment
		(start 158.045002 111.212002)
		(end 158.190001 111.357001)
		(width 0.16)
		(layer "F.Cu")
		(net 351)
	)
	(segment
		(start 197.010741 119.010741)
		(end 197.010741 118.975001)
		(width 0.256)
		(layer "F.Cu")
		(net 351)
	)
	(segment
		(start 197.5 119.5)
		(end 197.010741 119.010741)
		(width 0.256)
		(layer "F.Cu")
		(net 351)
	)
	(via
		(at 197.010741 118.975001)
		(size 0.45)
		(drill 0.2)
		(layers "F.Cu" "B.Cu")
		(net 351)
	)
	(via
		(at 158.190001 111.357001)
		(size 0.45)
		(drill 0.2)
		(layers "F.Cu" "B.Cu")
		(net 351)
	)
	(via
		(at 171.129737 112.245265)
		(size 0.45)
		(drill 0.2)
		(layers "F.Cu" "B.Cu")
		(net 351)
	)
	(segment
		(start 158.323501 111.223501)
		(end 158.190001 111.357001)
		(width 0.114)
		(layer "In3.Cu")
		(net 351)
	)
	(segment
		(start 171.129737 112.245265)
		(end 171.129737 112.007677)
		(width 0.114)
		(layer "In3.Cu")
		(net 351)
	)
	(segment
		(start 169.715561 110.593501)
		(end 159.539441 110.593501)
		(width 0.114)
		(layer "In3.Cu")
		(net 351)
	)
	(segment
		(start 158.909441 111.223501)
		(end 158.323501 111.223501)
		(width 0.114)
		(layer "In3.Cu")
		(net 351)
	)
	(segment
		(start 159.539441 110.593501)
		(end 158.909441 111.223501)
		(width 0.114)
		(layer "In3.Cu")
		(net 351)
	)
	(segment
		(start 171.129737 112.007677)
		(end 169.715561 110.593501)
		(width 0.114)
		(layer "In3.Cu")
		(net 351)
	)
	(segment
		(start 195.541423 118.400001)
		(end 193.533579 118.400001)
		(width 0.1)
		(layer "In5.Cu")
		(net 351)
	)
	(segment
		(start 176.843501 111.156501)
		(end 176.843501 111.052172)
		(width 0.114)
		(layer "In5.Cu")
		(net 351)
	)
	(segment
		(start 193.533579 118.400001)
		(end 193.033579 118.900001)
		(width 0.1)
		(layer "In5.Cu")
		(net 351)
	)
	(segment
		(start 183.405001 118.856501)
		(end 177.759441 118.856501)
		(width 0.114)
		(layer "In5.Cu")
		(net 351)
	)
	(segment
		(start 177.050001 112.350001)
		(end 177.469622 112.350001)
		(width 0.114)
		(layer "In5.Cu")
		(net 351)
	)
	(segment
		(start 173.209441 105.906501)
		(end 170.615561 105.906501)
		(width 0.114)
		(layer "In5.Cu")
		(net 351)
	)
	(segment
		(start 193.033579 118.900001)
		(end 183.448501 118.900001)
		(width 0.1)
		(layer "In5.Cu")
		(net 351)
	)
	(segment
		(start 170.056501 110.934441)
		(end 171.129737 112.007677)
		(width 0.114)
		(layer "In5.Cu")
		(net 351)
	)
	(segment
		(start 177.050001 113.750001)
		(end 177.469622 113.750001)
		(width 0.114)
		(layer "In5.Cu")
		(net 351)
	)
	(segment
		(start 170.056501 106.465561)
		(end 170.056501 110.934441)
		(width 0.114)
		(layer "In5.Cu")
		(net 351)
	)
	(segment
		(start 177.050001 115.150001)
		(end 177.469622 115.150001)
		(width 0.114)
		(layer "In5.Cu")
		(net 351)
	)
	(segment
		(start 196.141423 119.000001)
		(end 195.541423 118.400001)
		(width 0.1)
		(layer "In5.Cu")
		(net 351)
	)
	(segment
		(start 176.843501 111.052172)
		(end 176.843501 109.540561)
		(width 0.114)
		(layer "In5.Cu")
		(net 351)
	)
	(segment
		(start 170.615561 105.906501)
		(end 170.056501 106.465561)
		(width 0.114)
		(layer "In5.Cu")
		(net 351)
	)
	(segment
		(start 177.050001 116.550001)
		(end 177.469622 116.550001)
		(width 0.114)
		(layer "In5.Cu")
		(net 351)
	)
	(segment
		(start 171.129737 112.007677)
		(end 171.129737 112.245265)
		(width 0.114)
		(layer "In5.Cu")
		(net 351)
	)
	(segment
		(start 177.469622 115.563001)
		(end 177.050001 115.563001)
		(width 0.114)
		(layer "In5.Cu")
		(net 351)
	)
	(segment
		(start 197.000001 119.000001)
		(end 196.141423 119.000001)
		(width 0.1)
		(layer "In5.Cu")
		(net 351)
	)
	(segment
		(start 177.759441 118.856501)
		(end 176.843501 117.940561)
		(width 0.114)
		(layer "In5.Cu")
		(net 351)
	)
	(segment
		(start 176.843501 109.540561)
		(end 173.209441 105.906501)
		(width 0.114)
		(layer "In5.Cu")
		(net 351)
	)
	(segment
		(start 177.469622 112.763001)
		(end 177.050001 112.763001)
		(width 0.114)
		(layer "In5.Cu")
		(net 351)
	)
	(segment
		(start 177.469622 114.163001)
		(end 177.050001 114.163001)
		(width 0.114)
		(layer "In5.Cu")
		(net 351)
	)
	(segment
		(start 183.448501 118.900001)
		(end 183.405001 118.856501)
		(width 0.1)
		(layer "In5.Cu")
		(net 351)
	)
	(segment
		(start 177.469622 111.363001)
		(end 177.050001 111.363001)
		(width 0.114)
		(layer "In5.Cu")
		(net 351)
	)
	(segment
		(start 176.843501 117.940561)
		(end 176.843501 116.756501)
		(width 0.114)
		(layer "In5.Cu")
		(net 351)
	)
	(arc
		(start 176.843501 113.956501)
		(mid 176.903983 113.810483)
		(end 177.050001 113.750001)
		(width 0.114)
		(layer "In5.Cu")
		(net 351)
	)
	(arc
		(start 176.843501 112.556501)
		(mid 176.903983 112.410483)
		(end 177.050001 112.350001)
		(width 0.114)
		(layer "In5.Cu")
		(net 351)
	)
	(arc
		(start 177.050001 111.363001)
		(mid 176.903983 111.302519)
		(end 176.843501 111.156501)
		(width 0.114)
		(layer "In5.Cu")
		(net 351)
	)
	(arc
		(start 177.469622 113.750001)
		(mid 177.818579 113.605458)
		(end 177.963122 113.256501)
		(width 0.114)
		(layer "In5.Cu")
		(net 351)
	)
	(arc
		(start 177.963122 116.056501)
		(mid 177.818579 115.707544)
		(end 177.469622 115.563001)
		(width 0.114)
		(layer "In5.Cu")
		(net 351)
	)
	(arc
		(start 177.469622 115.150001)
		(mid 177.818579 115.005458)
		(end 177.963122 114.656501)
		(width 0.114)
		(layer "In5.Cu")
		(net 351)
	)
	(arc
		(start 177.963122 113.256501)
		(mid 177.818579 112.907544)
		(end 177.469622 112.763001)
		(width 0.114)
		(layer "In5.Cu")
		(net 351)
	)
	(arc
		(start 177.963122 114.656501)
		(mid 177.818579 114.307544)
		(end 177.469622 114.163001)
		(width 0.114)
		(layer "In5.Cu")
		(net 351)
	)
	(arc
		(start 177.050001 114.163001)
		(mid 176.903983 114.102519)
		(end 176.843501 113.956501)
		(width 0.114)
		(layer "In5.Cu")
		(net 351)
	)
	(arc
		(start 176.843501 115.356501)
		(mid 176.903983 115.210483)
		(end 177.050001 115.150001)
		(width 0.114)
		(layer "In5.Cu")
		(net 351)
	)
	(arc
		(start 177.963122 111.856501)
		(mid 177.818579 111.507544)
		(end 177.469622 111.363001)
		(width 0.114)
		(layer "In5.Cu")
		(net 351)
	)
	(arc
		(start 177.050001 112.763001)
		(mid 176.903983 112.702519)
		(end 176.843501 112.556501)
		(width 0.114)
		(layer "In5.Cu")
		(net 351)
	)
	(arc
		(start 177.050001 115.563001)
		(mid 176.903983 115.502519)
		(end 176.843501 115.356501)
		(width 0.114)
		(layer "In5.Cu")
		(net 351)
	)
	(arc
		(start 176.843501 116.756501)
		(mid 176.903983 116.610483)
		(end 177.050001 116.550001)
		(width 0.114)
		(layer "In5.Cu")
		(net 351)
	)
	(arc
		(start 177.469622 112.350001)
		(mid 177.818579 112.205458)
		(end 177.963122 111.856501)
		(width 0.114)
		(layer "In5.Cu")
		(net 351)
	)
	(arc
		(start 177.469622 116.550001)
		(mid 177.818579 116.405458)
		(end 177.963122 116.056501)
		(width 0.114)
		(layer "In5.Cu")
		(net 351)
	)
	(segment
		(start 157.555001 110.626198)
		(end 157.876804 110.948001)
		(width 0.16)
		(layer "F.Cu")
		(net 352)
	)
	(segment
		(start 158.045002 110.948)
		(end 157.876804 110.948001)
		(width 0.16)
		(layer "F.Cu")
		(net 352)
	)
	(segment
		(start 158.045002 110.948)
		(end 158.190001 110.803001)
		(width 0.16)
		(layer "F.Cu")
		(net 352)
	)
	(segment
		(start 196.5 120.5)
		(end 196 120)
		(width 0.256)
		(layer "F.Cu")
		(net 352)
	)
	(segment
		(start 157.555001 110.445001)
		(end 157.555001 110.626198)
		(width 0.16)
		(layer "F.Cu")
		(net 352)
	)
	(via
		(at 158.190001 110.803001)
		(size 0.45)
		(drill 0.2)
		(layers "F.Cu" "B.Cu")
		(net 352)
	)
	(via
		(at 196 120)
		(size 0.45)
		(drill 0.2)
		(layers "F.Cu" "B.Cu")
		(net 352)
	)
	(via
		(at 171.570265 111.804737)
		(size 0.45)
		(drill 0.2)
		(layers "F.Cu" "B.Cu")
		(net 352)
	)
	(segment
		(start 169.834441 110.306501)
		(end 159.420561 110.306501)
		(width 0.114)
		(layer "In3.Cu")
		(net 352)
	)
	(segment
		(start 158.790561 110.936501)
		(end 158.323501 110.936501)
		(width 0.114)
		(layer "In3.Cu")
		(net 352)
	)
	(segment
		(start 171.570265 111.804737)
		(end 171.332677 111.804737)
		(width 0.114)
		(layer "In3.Cu")
		(net 352)
	)
	(segment
		(start 159.420561 110.306501)
		(end 158.790561 110.936501)
		(width 0.114)
		(layer "In3.Cu")
		(net 352)
	)
	(segment
		(start 158.323501 110.936501)
		(end 158.190001 110.803001)
		(width 0.114)
		(layer "In3.Cu")
		(net 352)
	)
	(segment
		(start 171.332677 111.804737)
		(end 169.834441 110.306501)
		(width 0.114)
		(layer "In3.Cu")
		(net 352)
	)
	(segment
		(start 177.469622 115.850001)
		(end 177.050001 115.850001)
		(width 0.114)
		(layer "In5.Cu")
		(net 352)
	)
	(segment
		(start 177.469622 111.650001)
		(end 177.050001 111.650001)
		(width 0.114)
		(layer "In5.Cu")
		(net 352)
	)
	(segment
		(start 177.050001 114.863001)
		(end 177.469622 114.863001)
		(width 0.114)
		(layer "In5.Cu")
		(net 352)
	)
	(segment
		(start 176.556501 118.059441)
		(end 176.556501 116.756501)
		(width 0.114)
		(layer "In5.Cu")
		(net 352)
	)
	(segment
		(start 183.405001 119.143501)
		(end 177.640561 119.143501)
		(width 0.114)
		(layer "In5.Cu")
		(net 352)
	)
	(segment
		(start 173.090561 106.193501)
		(end 170.734441 106.193501)
		(width 0.114)
		(layer "In5.Cu")
		(net 352)
	)
	(segment
		(start 170.734441 106.193501)
		(end 170.343501 106.584441)
		(width 0.114)
		(layer "In5.Cu")
		(net 352)
	)
	(segment
		(start 177.050001 116.263001)
		(end 177.469622 116.263001)
		(width 0.114)
		(layer "In5.Cu")
		(net 352)
	)
	(segment
		(start 177.469622 114.450001)
		(end 177.050001 114.450001)
		(width 0.114)
		(layer "In5.Cu")
		(net 352)
	)
	(segment
		(start 193.116423 119.100001)
		(end 183.448501 119.100001)
		(width 0.1)
		(layer "In5.Cu")
		(net 352)
	)
	(segment
		(start 177.050001 113.463001)
		(end 177.469622 113.463001)
		(width 0.114)
		(layer "In5.Cu")
		(net 352)
	)
	(segment
		(start 177.469622 113.050001)
		(end 177.050001 113.050001)
		(width 0.114)
		(layer "In5.Cu")
		(net 352)
	)
	(segment
		(start 176.556501 111.052172)
		(end 176.556501 109.659441)
		(width 0.114)
		(layer "In5.Cu")
		(net 352)
	)
	(segment
		(start 177.050001 112.063001)
		(end 177.469622 112.063001)
		(width 0.114)
		(layer "In5.Cu")
		(net 352)
	)
	(segment
		(start 176.556501 111.156501)
		(end 176.556501 111.052172)
		(width 0.114)
		(layer "In5.Cu")
		(net 352)
	)
	(segment
		(start 193.616423 118.600001)
		(end 193.116423 119.100001)
		(width 0.1)
		(layer "In5.Cu")
		(net 352)
	)
	(segment
		(start 183.448501 119.100001)
		(end 183.405001 119.143501)
		(width 0.1)
		(layer "In5.Cu")
		(net 352)
	)
	(segment
		(start 195.458579 118.600001)
		(end 193.616423 118.600001)
		(width 0.1)
		(layer "In5.Cu")
		(net 352)
	)
	(segment
		(start 196.000001 119.141423)
		(end 195.458579 118.600001)
		(width 0.1)
		(layer "In5.Cu")
		(net 352)
	)
	(segment
		(start 176.556501 109.659441)
		(end 173.090561 106.193501)
		(width 0.114)
		(layer "In5.Cu")
		(net 352)
	)
	(segment
		(start 196.000001 120.000001)
		(end 196.000001 119.141423)
		(width 0.1)
		(layer "In5.Cu")
		(net 352)
	)
	(segment
		(start 177.640561 119.143501)
		(end 176.556501 118.059441)
		(width 0.114)
		(layer "In5.Cu")
		(net 352)
	)
	(segment
		(start 170.343501 110.815561)
		(end 171.332677 111.804737)
		(width 0.114)
		(layer "In5.Cu")
		(net 352)
	)
	(segment
		(start 171.332677 111.804737)
		(end 171.570265 111.804737)
		(width 0.114)
		(layer "In5.Cu")
		(net 352)
	)
	(segment
		(start 170.343501 106.584441)
		(end 170.343501 110.815561)
		(width 0.114)
		(layer "In5.Cu")
		(net 352)
	)
	(arc
		(start 177.050001 111.650001)
		(mid 176.701044 111.505458)
		(end 176.556501 111.156501)
		(width 0.114)
		(layer "In5.Cu")
		(net 352)
	)
	(arc
		(start 177.050001 113.050001)
		(mid 176.701044 112.905458)
		(end 176.556501 112.556501)
		(width 0.114)
		(layer "In5.Cu")
		(net 352)
	)
	(arc
		(start 176.556501 113.956501)
		(mid 176.701044 113.607544)
		(end 177.050001 113.463001)
		(width 0.114)
		(layer "In5.Cu")
		(net 352)
	)
	(arc
		(start 177.050001 114.450001)
		(mid 176.701044 114.305458)
		(end 176.556501 113.956501)
		(width 0.114)
		(layer "In5.Cu")
		(net 352)
	)
	(arc
		(start 177.469622 114.863001)
		(mid 177.61564 114.802519)
		(end 177.676122 114.656501)
		(width 0.114)
		(layer "In5.Cu")
		(net 352)
	)
	(arc
		(start 176.556501 116.756501)
		(mid 176.701044 116.407544)
		(end 177.050001 116.263001)
		(width 0.114)
		(layer "In5.Cu")
		(net 352)
	)
	(arc
		(start 177.469622 112.063001)
		(mid 177.61564 112.002519)
		(end 177.676122 111.856501)
		(width 0.114)
		(layer "In5.Cu")
		(net 352)
	)
	(arc
		(start 177.676122 111.856501)
		(mid 177.61564 111.710483)
		(end 177.469622 111.650001)
		(width 0.114)
		(layer "In5.Cu")
		(net 352)
	)
	(arc
		(start 177.676122 113.256501)
		(mid 177.61564 113.110483)
		(end 177.469622 113.050001)
		(width 0.114)
		(layer "In5.Cu")
		(net 352)
	)
	(arc
		(start 177.676122 114.656501)
		(mid 177.61564 114.510483)
		(end 177.469622 114.450001)
		(width 0.114)
		(layer "In5.Cu")
		(net 352)
	)
	(arc
		(start 177.676122 116.056501)
		(mid 177.61564 115.910483)
		(end 177.469622 115.850001)
		(width 0.114)
		(layer "In5.Cu")
		(net 352)
	)
	(arc
		(start 176.556501 115.356501)
		(mid 176.701044 115.007544)
		(end 177.050001 114.863001)
		(width 0.114)
		(layer "In5.Cu")
		(net 352)
	)
	(arc
		(start 176.556501 112.556501)
		(mid 176.701044 112.207544)
		(end 177.050001 112.063001)
		(width 0.114)
		(layer "In5.Cu")
		(net 352)
	)
	(arc
		(start 177.469622 116.263001)
		(mid 177.61564 116.202519)
		(end 177.676122 116.056501)
		(width 0.114)
		(layer "In5.Cu")
		(net 352)
	)
	(arc
		(start 177.469622 113.463001)
		(mid 177.61564 113.402519)
		(end 177.676122 113.256501)
		(width 0.114)
		(layer "In5.Cu")
		(net 352)
	)
	(arc
		(start 177.050001 115.850001)
		(mid 176.701044 115.705458)
		(end 176.556501 115.356501)
		(width 0.114)
		(layer "In5.Cu")
		(net 352)
	)
	(segment
		(start 197.012358 120.012358)
		(end 196.999885 120.012358)
		(width 0.256)
		(layer "F.Cu")
		(net 353)
	)
	(segment
		(start 197.5 120.5)
		(end 197.012358 120.012358)
		(width 0.256)
		(layer "F.Cu")
		(net 353)
	)
	(segment
		(start 158.045002 107.402002)
		(end 158.190001 107.547001)
		(width 0.16)
		(layer "F.Cu")
		(net 353)
	)
	(segment
		(start 157.876804 107.402001)
		(end 157.555001 107.723804)
		(width 0.16)
		(layer "F.Cu")
		(net 353)
	)
	(segment
		(start 158.045002 107.402002)
		(end 157.876804 107.402001)
		(width 0.16)
		(layer "F.Cu")
		(net 353)
	)
	(segment
		(start 157.555001 107.723804)
		(end 157.555001 107.905001)
		(width 0.16)
		(layer "F.Cu")
		(net 353)
	)
	(via
		(at 158.190001 107.547001)
		(size 0.45)
		(drill 0.2)
		(layers "F.Cu" "B.Cu")
		(net 353)
	)
	(via
		(at 196.999885 120.012358)
		(size 0.45)
		(drill 0.2)
		(layers "F.Cu" "B.Cu")
		(net 353)
	)
	(via
		(at 171.680265 107.145265)
		(size 0.45)
		(drill 0.2)
		(layers "F.Cu" "B.Cu")
		(net 353)
	)
	(segment
		(start 160.119501 106.57811)
		(end 160.119501 106.550501)
		(width 0.114)
		(layer "In3.Cu")
		(net 353)
	)
	(segment
		(start 158.323501 107.413501)
		(end 158.689441 107.413501)
		(width 0.114)
		(layer "In3.Cu")
		(net 353)
	)
	(segment
		(start 163.505561 108.043501)
		(end 170.544441 108.043501)
		(width 0.114)
		(layer "In3.Cu")
		(net 353)
	)
	(segment
		(start 171.442677 107.145265)
		(end 171.680265 107.145265)
		(width 0.114)
		(layer "In3.Cu")
		(net 353)
	)
	(segment
		(start 170.544441 108.043501)
		(end 171.442677 107.145265)
		(width 0.114)
		(layer "In3.Cu")
		(net 353)
	)
	(segment
		(start 159.905501 106.550501)
		(end 159.905501 106.57811)
		(width 0.114)
		(layer "In3.Cu")
		(net 353)
	)
	(segment
		(start 160.226501 106.443501)
		(end 161.905561 106.443501)
		(width 0.114)
		(layer "In3.Cu")
		(net 353)
	)
	(segment
		(start 158.190001 107.547001)
		(end 158.323501 107.413501)
		(width 0.114)
		(layer "In3.Cu")
		(net 353)
	)
	(segment
		(start 161.905561 106.443501)
		(end 163.505561 108.043501)
		(width 0.114)
		(layer "In3.Cu")
		(net 353)
	)
	(segment
		(start 159.659441 106.443501)
		(end 159.798501 106.443501)
		(width 0.114)
		(layer "In3.Cu")
		(net 353)
	)
	(segment
		(start 158.689441 107.413501)
		(end 159.659441 106.443501)
		(width 0.114)
		(layer "In3.Cu")
		(net 353)
	)
	(arc
		(start 159.798501 106.443501)
		(mid 159.874161 106.474841)
		(end 159.905501 106.550501)
		(width 0.114)
		(layer "In3.Cu")
		(net 353)
	)
	(arc
		(start 160.119501 106.550501)
		(mid 160.150841 106.474841)
		(end 160.226501 106.443501)
		(width 0.114)
		(layer "In3.Cu")
		(net 353)
	)
	(arc
		(start 159.905501 106.57811)
		(mid 159.936841 106.65377)
		(end 160.012501 106.68511)
		(width 0.114)
		(layer "In3.Cu")
		(net 353)
	)
	(arc
		(start 160.012501 106.68511)
		(mid 160.088161 106.65377)
		(end 160.119501 106.57811)
		(width 0.114)
		(layer "In3.Cu")
		(net 353)
	)
	(segment
		(start 175.525876 116.600001)
		(end 174.600001 116.600001)
		(width 0.114)
		(layer "In5.Cu")
		(net 353)
	)
	(segment
		(start 197.000001 120.000001)
		(end 196.600001 120.400001)
		(width 0.1)
		(layer "In5.Cu")
		(net 353)
	)
	(segment
		(start 193.666423 120.400001)
		(end 193.166423 119.900001)
		(width 0.1)
		(layer "In5.Cu")
		(net 353)
	)
	(segment
		(start 171.283501 107.304441)
		(end 171.442677 107.145265)
		(width 0.114)
		(layer "In5.Cu")
		(net 353)
	)
	(segment
		(start 175.525876 115.300001)
		(end 174.600001 115.300001)
		(width 0.114)
		(layer "In5.Cu")
		(net 353)
	)
	(segment
		(start 196.600001 120.400001)
		(end 193.666423 120.400001)
		(width 0.1)
		(layer "In5.Cu")
		(net 353)
	)
	(segment
		(start 175.525876 114.000001)
		(end 174.600001 114.000001)
		(width 0.114)
		(layer "In5.Cu")
		(net 353)
	)
	(segment
		(start 174.600001 112.337001)
		(end 175.525876 112.337001)
		(width 0.114)
		(layer "In5.Cu")
		(net 353)
	)
	(segment
		(start 171.283501 107.530561)
		(end 171.283501 107.304441)
		(width 0.114)
		(layer "In5.Cu")
		(net 353)
	)
	(segment
		(start 174.418501 110.665561)
		(end 171.283501 107.530561)
		(width 0.114)
		(layer "In5.Cu")
		(net 353)
	)
	(segment
		(start 183.405001 119.856501)
		(end 174.754441 119.856501)
		(width 0.114)
		(layer "In5.Cu")
		(net 353)
	)
	(segment
		(start 183.448501 119.900001)
		(end 183.405001 119.856501)
		(width 0.1)
		(layer "In5.Cu")
		(net 353)
	)
	(segment
		(start 174.600001 114.937001)
		(end 175.525876 114.937001)
		(width 0.114)
		(layer "In5.Cu")
		(net 353)
	)
	(segment
		(start 174.600001 113.637001)
		(end 175.525876 113.637001)
		(width 0.114)
		(layer "In5.Cu")
		(net 353)
	)
	(segment
		(start 174.600001 117.537001)
		(end 175.525876 117.537001)
		(width 0.114)
		(layer "In5.Cu")
		(net 353)
	)
	(segment
		(start 171.442677 107.145265)
		(end 171.680265 107.145265)
		(width 0.114)
		(layer "In5.Cu")
		(net 353)
	)
	(segment
		(start 174.418501 111.218501)
		(end 174.418501 110.665561)
		(width 0.114)
		(layer "In5.Cu")
		(net 353)
	)
	(segment
		(start 174.418501 119.520561)
		(end 174.418501 119.018501)
		(width 0.114)
		(layer "In5.Cu")
		(net 353)
	)
	(segment
		(start 174.600001 116.237001)
		(end 175.525876 116.237001)
		(width 0.114)
		(layer "In5.Cu")
		(net 353)
	)
	(segment
		(start 193.166423 119.900001)
		(end 183.448501 119.900001)
		(width 0.1)
		(layer "In5.Cu")
		(net 353)
	)
	(segment
		(start 175.525876 112.700001)
		(end 174.600001 112.700001)
		(width 0.114)
		(layer "In5.Cu")
		(net 353)
	)
	(segment
		(start 174.754441 119.856501)
		(end 174.418501 119.520561)
		(width 0.114)
		(layer "In5.Cu")
		(net 353)
	)
	(segment
		(start 174.600001 118.837001)
		(end 175.525876 118.837001)
		(width 0.114)
		(layer "In5.Cu")
		(net 353)
	)
	(segment
		(start 175.525876 117.900001)
		(end 174.600001 117.900001)
		(width 0.114)
		(layer "In5.Cu")
		(net 353)
	)
	(segment
		(start 175.525876 111.400001)
		(end 174.600001 111.400001)
		(width 0.114)
		(layer "In5.Cu")
		(net 353)
	)
	(arc
		(start 175.525876 116.237001)
		(mid 175.857156 116.099781)
		(end 175.994376 115.768501)
		(width 0.114)
		(layer "In5.Cu")
		(net 353)
	)
	(arc
		(start 175.994376 115.768501)
		(mid 175.857156 115.437221)
		(end 175.525876 115.300001)
		(width 0.114)
		(layer "In5.Cu")
		(net 353)
	)
	(arc
		(start 175.994376 117.068501)
		(mid 175.857156 116.737221)
		(end 175.525876 116.600001)
		(width 0.114)
		(layer "In5.Cu")
		(net 353)
	)
	(arc
		(start 174.600001 116.600001)
		(mid 174.471661 116.546841)
		(end 174.418501 116.418501)
		(width 0.114)
		(layer "In5.Cu")
		(net 353)
	)
	(arc
		(start 175.525876 117.537001)
		(mid 175.857156 117.399781)
		(end 175.994376 117.068501)
		(width 0.114)
		(layer "In5.Cu")
		(net 353)
	)
	(arc
		(start 174.418501 115.118501)
		(mid 174.471661 114.990161)
		(end 174.600001 114.937001)
		(width 0.114)
		(layer "In5.Cu")
		(net 353)
	)
	(arc
		(start 175.994376 111.868501)
		(mid 175.857156 111.537221)
		(end 175.525876 111.400001)
		(width 0.114)
		(layer "In5.Cu")
		(net 353)
	)
	(arc
		(start 174.418501 117.718501)
		(mid 174.471661 117.590161)
		(end 174.600001 117.537001)
		(width 0.114)
		(layer "In5.Cu")
		(net 353)
	)
	(arc
		(start 174.600001 117.900001)
		(mid 174.471661 117.846841)
		(end 174.418501 117.718501)
		(width 0.114)
		(layer "In5.Cu")
		(net 353)
	)
	(arc
		(start 175.994376 113.168501)
		(mid 175.857156 112.837221)
		(end 175.525876 112.700001)
		(width 0.114)
		(layer "In5.Cu")
		(net 353)
	)
	(arc
		(start 174.600001 111.400001)
		(mid 174.471661 111.346841)
		(end 174.418501 111.218501)
		(width 0.114)
		(layer "In5.Cu")
		(net 353)
	)
	(arc
		(start 174.418501 119.018501)
		(mid 174.471661 118.890161)
		(end 174.600001 118.837001)
		(width 0.114)
		(layer "In5.Cu")
		(net 353)
	)
	(arc
		(start 174.418501 113.818501)
		(mid 174.471661 113.690161)
		(end 174.600001 113.637001)
		(width 0.114)
		(layer "In5.Cu")
		(net 353)
	)
	(arc
		(start 175.525876 112.337001)
		(mid 175.857156 112.199781)
		(end 175.994376 111.868501)
		(width 0.114)
		(layer "In5.Cu")
		(net 353)
	)
	(arc
		(start 175.525876 114.937001)
		(mid 175.857156 114.799781)
		(end 175.994376 114.468501)
		(width 0.114)
		(layer "In5.Cu")
		(net 353)
	)
	(arc
		(start 175.994376 118.368501)
		(mid 175.857156 118.037221)
		(end 175.525876 117.900001)
		(width 0.114)
		(layer "In5.Cu")
		(net 353)
	)
	(arc
		(start 174.418501 112.518501)
		(mid 174.471661 112.390161)
		(end 174.600001 112.337001)
		(width 0.114)
		(layer "In5.Cu")
		(net 353)
	)
	(arc
		(start 175.525876 118.837001)
		(mid 175.857156 118.699781)
		(end 175.994376 118.368501)
		(width 0.114)
		(layer "In5.Cu")
		(net 353)
	)
	(arc
		(start 174.600001 115.300001)
		(mid 174.471661 115.246841)
		(end 174.418501 115.118501)
		(width 0.114)
		(layer "In5.Cu")
		(net 353)
	)
	(arc
		(start 174.418501 116.418501)
		(mid 174.471661 116.290161)
		(end 174.600001 116.237001)
		(width 0.114)
		(layer "In5.Cu")
		(net 353)
	)
	(arc
		(start 174.600001 114.000001)
		(mid 174.471661 113.946841)
		(end 174.418501 113.818501)
		(width 0.114)
		(layer "In5.Cu")
		(net 353)
	)
	(arc
		(start 175.525876 113.637001)
		(mid 175.857156 113.499781)
		(end 175.994376 113.168501)
		(width 0.114)
		(layer "In5.Cu")
		(net 353)
	)
	(arc
		(start 175.994376 114.468501)
		(mid 175.857156 114.137221)
		(end 175.525876 114.000001)
		(width 0.114)
		(layer "In5.Cu")
		(net 353)
	)
	(arc
		(start 174.600001 112.700001)
		(mid 174.471661 112.646841)
		(end 174.418501 112.518501)
		(width 0.114)
		(layer "In5.Cu")
		(net 353)
	)
	(segment
		(start 158.045002 107.138)
		(end 157.876804 107.138001)
		(width 0.16)
		(layer "F.Cu")
		(net 354)
	)
	(segment
		(start 158.045002 107.138)
		(end 158.190001 106.993001)
		(width 0.16)
		(layer "F.Cu")
		(net 354)
	)
	(segment
		(start 197.5 121.5)
		(end 197 121)
		(width 0.256)
		(layer "F.Cu")
		(net 354)
	)
	(segment
		(start 157.555001 106.635001)
		(end 157.555001 106.816198)
		(width 0.16)
		(layer "F.Cu")
		(net 354)
	)
	(segment
		(start 157.555001 106.816198)
		(end 157.876804 107.138001)
		(width 0.16)
		(layer "F.Cu")
		(net 354)
	)
	(via
		(at 158.190001 106.993001)
		(size 0.45)
		(drill 0.2)
		(layers "F.Cu" "B.Cu")
		(net 354)
	)
	(via
		(at 171.239737 106.704737)
		(size 0.45)
		(drill 0.2)
		(layers "F.Cu" "B.Cu")
		(net 354)
	)
	(via
		(at 197 121)
		(size 0.45)
		(drill 0.2)
		(layers "F.Cu" "B.Cu")
		(net 354)
	)
	(segment
		(start 162.024441 106.156501)
		(end 159.540561 106.156501)
		(width 0.114)
		(layer "In3.Cu")
		(net 354)
	)
	(segment
		(start 170.425561 107.756501)
		(end 163.624441 107.756501)
		(width 0.114)
		(layer "In3.Cu")
		(net 354)
	)
	(segment
		(start 171.239737 106.942325)
		(end 170.425561 107.756501)
		(width 0.114)
		(layer "In3.Cu")
		(net 354)
	)
	(segment
		(start 159.540561 106.156501)
		(end 158.570561 107.126501)
		(width 0.114)
		(layer "In3.Cu")
		(net 354)
	)
	(segment
		(start 158.570561 107.126501)
		(end 158.323501 107.126501)
		(width 0.114)
		(layer "In3.Cu")
		(net 354)
	)
	(segment
		(start 158.323501 107.126501)
		(end 158.190001 106.993001)
		(width 0.114)
		(layer "In3.Cu")
		(net 354)
	)
	(segment
		(start 163.624441 107.756501)
		(end 162.024441 106.156501)
		(width 0.114)
		(layer "In3.Cu")
		(net 354)
	)
	(segment
		(start 171.239737 106.704737)
		(end 171.239737 106.942325)
		(width 0.114)
		(layer "In3.Cu")
		(net 354)
	)
	(segment
		(start 183.448501 120.100001)
		(end 183.405001 120.143501)
		(width 0.1)
		(layer "In5.Cu")
		(net 354)
	)
	(segment
		(start 174.131501 110.784441)
		(end 170.996501 107.649441)
		(width 0.114)
		(layer "In5.Cu")
		(net 354)
	)
	(segment
		(start 174.131501 111.218501)
		(end 174.131501 110.784441)
		(width 0.114)
		(layer "In5.Cu")
		(net 354)
	)
	(segment
		(start 174.600001 112.050001)
		(end 175.525876 112.050001)
		(width 0.114)
		(layer "In5.Cu")
		(net 354)
	)
	(segment
		(start 174.600001 114.650001)
		(end 175.525876 114.650001)
		(width 0.114)
		(layer "In5.Cu")
		(net 354)
	)
	(segment
		(start 183.405001 120.143501)
		(end 174.635561 120.143501)
		(width 0.114)
		(layer "In5.Cu")
		(net 354)
	)
	(segment
		(start 174.600001 113.350001)
		(end 175.525876 113.350001)
		(width 0.114)
		(layer "In5.Cu")
		(net 354)
	)
	(segment
		(start 174.131501 119.639441)
		(end 174.131501 119.018501)
		(width 0.114)
		(layer "In5.Cu")
		(net 354)
	)
	(segment
		(start 175.525876 116.887001)
		(end 174.600001 116.887001)
		(width 0.114)
		(layer "In5.Cu")
		(net 354)
	)
	(segment
		(start 196.600001 120.600001)
		(end 193.583579 120.600001)
		(width 0.1)
		(layer "In5.Cu")
		(net 354)
	)
	(segment
		(start 175.525876 114.287001)
		(end 174.600001 114.287001)
		(width 0.114)
		(layer "In5.Cu")
		(net 354)
	)
	(segment
		(start 174.600001 118.550001)
		(end 175.525876 118.550001)
		(width 0.114)
		(layer "In5.Cu")
		(net 354)
	)
	(segment
		(start 193.583579 120.600001)
		(end 193.083579 120.100001)
		(width 0.1)
		(layer "In5.Cu")
		(net 354)
	)
	(segment
		(start 197.000001 121.000001)
		(end 196.600001 120.600001)
		(width 0.1)
		(layer "In5.Cu")
		(net 354)
	)
	(segment
		(start 175.525876 112.987001)
		(end 174.600001 112.987001)
		(width 0.114)
		(layer "In5.Cu")
		(net 354)
	)
	(segment
		(start 174.635561 120.143501)
		(end 174.131501 119.639441)
		(width 0.114)
		(layer "In5.Cu")
		(net 354)
	)
	(segment
		(start 174.600001 115.950001)
		(end 175.525876 115.950001)
		(width 0.114)
		(layer "In5.Cu")
		(net 354)
	)
	(segment
		(start 170.996501 107.649441)
		(end 170.996501 107.185561)
		(width 0.114)
		(layer "In5.Cu")
		(net 354)
	)
	(segment
		(start 193.083579 120.100001)
		(end 183.448501 120.100001)
		(width 0.1)
		(layer "In5.Cu")
		(net 354)
	)
	(segment
		(start 174.600001 117.250001)
		(end 175.525876 117.250001)
		(width 0.114)
		(layer "In5.Cu")
		(net 354)
	)
	(segment
		(start 175.525876 111.687001)
		(end 174.600001 111.687001)
		(width 0.114)
		(layer "In5.Cu")
		(net 354)
	)
	(segment
		(start 175.525876 115.587001)
		(end 174.600001 115.587001)
		(width 0.114)
		(layer "In5.Cu")
		(net 354)
	)
	(segment
		(start 171.239737 106.942325)
		(end 171.239737 106.704737)
		(width 0.114)
		(layer "In5.Cu")
		(net 354)
	)
	(segment
		(start 175.525876 118.187001)
		(end 174.600001 118.187001)
		(width 0.114)
		(layer "In5.Cu")
		(net 354)
	)
	(segment
		(start 170.996501 107.185561)
		(end 171.239737 106.942325)
		(width 0.114)
		(layer "In5.Cu")
		(net 354)
	)
	(arc
		(start 175.707376 113.168501)
		(mid 175.654216 113.040161)
		(end 175.525876 112.987001)
		(width 0.114)
		(layer "In5.Cu")
		(net 354)
	)
	(arc
		(start 174.600001 114.287001)
		(mid 174.268721 114.149781)
		(end 174.131501 113.818501)
		(width 0.114)
		(layer "In5.Cu")
		(net 354)
	)
	(arc
		(start 175.707376 117.068501)
		(mid 175.654216 116.940161)
		(end 175.525876 116.887001)
		(width 0.114)
		(layer "In5.Cu")
		(net 354)
	)
	(arc
		(start 174.131501 116.418501)
		(mid 174.268721 116.087221)
		(end 174.600001 115.950001)
		(width 0.114)
		(layer "In5.Cu")
		(net 354)
	)
	(arc
		(start 175.707376 114.468501)
		(mid 175.654216 114.340161)
		(end 175.525876 114.287001)
		(width 0.114)
		(layer "In5.Cu")
		(net 354)
	)
	(arc
		(start 174.600001 112.987001)
		(mid 174.268721 112.849781)
		(end 174.131501 112.518501)
		(width 0.114)
		(layer "In5.Cu")
		(net 354)
	)
	(arc
		(start 175.525876 115.950001)
		(mid 175.654216 115.896841)
		(end 175.707376 115.768501)
		(width 0.114)
		(layer "In5.Cu")
		(net 354)
	)
	(arc
		(start 175.707376 111.868501)
		(mid 175.654216 111.740161)
		(end 175.525876 111.687001)
		(width 0.114)
		(layer "In5.Cu")
		(net 354)
	)
	(arc
		(start 174.600001 115.587001)
		(mid 174.268721 115.449781)
		(end 174.131501 115.118501)
		(width 0.114)
		(layer "In5.Cu")
		(net 354)
	)
	(arc
		(start 175.525876 117.250001)
		(mid 175.654216 117.196841)
		(end 175.707376 117.068501)
		(width 0.114)
		(layer "In5.Cu")
		(net 354)
	)
	(arc
		(start 175.525876 114.650001)
		(mid 175.654216 114.596841)
		(end 175.707376 114.468501)
		(width 0.114)
		(layer "In5.Cu")
		(net 354)
	)
	(arc
		(start 174.600001 116.887001)
		(mid 174.268721 116.749781)
		(end 174.131501 116.418501)
		(width 0.114)
		(layer "In5.Cu")
		(net 354)
	)
	(arc
		(start 174.131501 119.018501)
		(mid 174.268721 118.687221)
		(end 174.600001 118.550001)
		(width 0.114)
		(layer "In5.Cu")
		(net 354)
	)
	(arc
		(start 174.131501 115.118501)
		(mid 174.268721 114.787221)
		(end 174.600001 114.650001)
		(width 0.114)
		(layer "In5.Cu")
		(net 354)
	)
	(arc
		(start 174.131501 112.518501)
		(mid 174.268721 112.187221)
		(end 174.600001 112.050001)
		(width 0.114)
		(layer "In5.Cu")
		(net 354)
	)
	(arc
		(start 174.131501 113.818501)
		(mid 174.268721 113.487221)
		(end 174.600001 113.350001)
		(width 0.114)
		(layer "In5.Cu")
		(net 354)
	)
	(arc
		(start 175.707376 118.368501)
		(mid 175.654216 118.240161)
		(end 175.525876 118.187001)
		(width 0.114)
		(layer "In5.Cu")
		(net 354)
	)
	(arc
		(start 175.525876 112.050001)
		(mid 175.654216 111.996841)
		(end 175.707376 111.868501)
		(width 0.114)
		(layer "In5.Cu")
		(net 354)
	)
	(arc
		(start 175.525876 118.550001)
		(mid 175.654216 118.496841)
		(end 175.707376 118.368501)
		(width 0.114)
		(layer "In5.Cu")
		(net 354)
	)
	(arc
		(start 174.600001 118.187001)
		(mid 174.268721 118.049781)
		(end 174.131501 117.718501)
		(width 0.114)
		(layer "In5.Cu")
		(net 354)
	)
	(arc
		(start 175.707376 115.768501)
		(mid 175.654216 115.640161)
		(end 175.525876 115.587001)
		(width 0.114)
		(layer "In5.Cu")
		(net 354)
	)
	(arc
		(start 175.525876 113.350001)
		(mid 175.654216 113.296841)
		(end 175.707376 113.168501)
		(width 0.114)
		(layer "In5.Cu")
		(net 354)
	)
	(arc
		(start 174.131501 117.718501)
		(mid 174.268721 117.387221)
		(end 174.600001 117.250001)
		(width 0.114)
		(layer "In5.Cu")
		(net 354)
	)
	(arc
		(start 174.600001 111.687001)
		(mid 174.268721 111.549781)
		(end 174.131501 111.218501)
		(width 0.114)
		(layer "In5.Cu")
		(net 354)
	)
	(segment
		(start 225.565 163.68)
		(end 225.285 163.4)
		(width 0.1)
		(layer "F.Cu")
		(net 362)
	)
	(segment
		(start 226.47 163.68)
		(end 225.565 163.68)
		(width 0.1)
		(layer "F.Cu")
		(net 362)
	)
	(segment
		(start 198.095 177.81)
		(end 200.06 177.81)
		(width 0.1)
		(layer "B.Cu")
		(net 365)
	)
	(segment
		(start 198.085 177.8)
		(end 198.095 177.81)
		(width 0.1)
		(layer "B.Cu")
		(net 365)
	)
	(segment
		(start 238.05 131.8)
		(end 237.435 131.8)
		(width 0.177)
		(layer "F.Cu")
		(net 368)
	)
	(segment
		(start 237.435 131.8)
		(end 236.685 132.55)
		(width 0.177)
		(layer "F.Cu")
		(net 368)
	)
	(segment
		(start 238.05 131.3)
		(end 236.935 131.3)
		(width 0.177)
		(layer "F.Cu")
		(net 369)
	)
	(segment
		(start 236.935 131.3)
		(end 236.685 131.55)
		(width 0.177)
		(layer "F.Cu")
		(net 369)
	)
	(segment
		(start 236.935 130.8)
		(end 236.685 130.55)
		(width 0.177)
		(layer "F.Cu")
		(net 370)
	)
	(segment
		(start 238.05 130.8)
		(end 236.935 130.8)
		(width 0.177)
		(layer "F.Cu")
		(net 370)
	)
	(segment
		(start 238.05 130.3)
		(end 237.435 130.3)
		(width 0.177)
		(layer "F.Cu")
		(net 371)
	)
	(segment
		(start 237.435 130.3)
		(end 236.685 129.55)
		(width 0.177)
		(layer "F.Cu")
		(net 371)
	)
	(segment
		(start 237.65 142.185)
		(end 238.65 142.185)
		(width 0.1)
		(layer "F.Cu")
		(net 372)
	)
	(segment
		(start 239 143.2)
		(end 239 142.535)
		(width 0.1)
		(layer "F.Cu")
		(net 372)
	)
	(segment
		(start 239 142.535)
		(end 238.65 142.185)
		(width 0.1)
		(layer "F.Cu")
		(net 372)
	)
	(segment
		(start 196.5 121.5)
		(end 196 121)
		(width 0.256)
		(layer "F.Cu")
		(net 373)
	)
	(segment
		(start 160.175001 121.875001)
		(end 160.775001 121.275001)
		(width 0.198)
		(layer "F.Cu")
		(net 373)
	)
	(segment
		(start 160.095001 121.875001)
		(end 160.175001 121.875001)
		(width 0.198)
		(layer "F.Cu")
		(net 373)
	)
	(via
		(at 196 121)
		(size 0.45)
		(drill 0.2)
		(layers "F.Cu" "B.Cu")
		(net 373)
	)
	(via
		(at 160.775001 121.275001)
		(size 0.45)
		(drill 0.2)
		(layers "F.Cu" "B.Cu")
		(net 373)
	)
	(via
		(at 172.000001 122.750001)
		(size 0.45)
		(drill 0.2)
		(layers "F.Cu" "B.Cu")
		(net 373)
	)
	(segment
		(start 171.225001 121.275001)
		(end 172.000001 122.050001)
		(width 0.114)
		(layer "In3.Cu")
		(net 373)
	)
	(segment
		(start 160.775001 121.275001)
		(end 171.225001 121.275001)
		(width 0.114)
		(layer "In3.Cu")
		(net 373)
	)
	(segment
		(start 172.000001 122.050001)
		(end 172.000001 122.750001)
		(width 0.114)
		(layer "In3.Cu")
		(net 373)
	)
	(segment
		(start 172.000001 122.750001)
		(end 172.825001 121.925001)
		(width 0.1)
		(layer "In7.Cu")
		(net 373)
	)
	(segment
		(start 172.825001 121.925001)
		(end 193.225001 121.925001)
		(width 0.1)
		(layer "In7.Cu")
		(net 373)
	)
	(segment
		(start 193.750002 121.4)
		(end 195.600002 121.4)
		(width 0.1)
		(layer "In7.Cu")
		(net 373)
	)
	(segment
		(start 195.600002 121.4)
		(end 196.000001 121.000001)
		(width 0.1)
		(layer "In7.Cu")
		(net 373)
	)
	(segment
		(start 193.225001 121.925001)
		(end 193.750002 121.4)
		(width 0.1)
		(layer "In7.Cu")
		(net 373)
	)
	(segment
		(start 237.585 145.7)
		(end 236.835 146.45)
		(width 0.177)
		(layer "F.Cu")
		(net 374)
	)
	(segment
		(start 238.2 145.7)
		(end 237.585 145.7)
		(width 0.177)
		(layer "F.Cu")
		(net 374)
	)
	(segment
		(start 237.085 145.2)
		(end 236.835 145.45)
		(width 0.177)
		(layer "F.Cu")
		(net 375)
	)
	(segment
		(start 238.2 145.2)
		(end 237.085 145.2)
		(width 0.177)
		(layer "F.Cu")
		(net 375)
	)
	(segment
		(start 238.2 144.7)
		(end 237.085 144.7)
		(width 0.177)
		(layer "F.Cu")
		(net 376)
	)
	(segment
		(start 237.085 144.7)
		(end 236.835 144.45)
		(width 0.177)
		(layer "F.Cu")
		(net 376)
	)
	(segment
		(start 160.416804 118.832001)
		(end 160.095001 119.153804)
		(width 0.16)
		(layer "F.Cu")
		(net 377)
	)
	(segment
		(start 200.5 122.5)
		(end 200.93 122.07)
		(width 0.256)
		(layer "F.Cu")
		(net 377)
	)
	(segment
		(start 160.585002 118.832002)
		(end 160.730001 118.977001)
		(width 0.16)
		(layer "F.Cu")
		(net 377)
	)
	(segment
		(start 200.93 122.07)
		(end 200.98 122.07)
		(width 0.256)
		(layer "F.Cu")
		(net 377)
	)
	(segment
		(start 160.095001 119.153804)
		(end 160.095001 119.335001)
		(width 0.16)
		(layer "F.Cu")
		(net 377)
	)
	(segment
		(start 160.585002 118.832002)
		(end 160.416804 118.832001)
		(width 0.16)
		(layer "F.Cu")
		(net 377)
	)
	(via
		(at 200.98 122.07)
		(size 0.45)
		(drill 0.2)
		(layers "F.Cu" "B.Cu")
		(net 377)
	)
	(via
		(at 160.730001 118.977001)
		(size 0.45)
		(drill 0.2)
		(layers "F.Cu" "B.Cu")
		(net 377)
	)
	(segment
		(start 202.600001 122.733579)
		(end 202.600001 128.341423)
		(width 0.1)
		(layer "In5.Cu")
		(net 377)
	)
	(segment
		(start 192.833579 128.100001)
		(end 183.448501 128.100001)
		(width 0.1)
		(layer "In5.Cu")
		(net 377)
	)
	(segment
		(start 162.491501 122.291501)
		(end 162.491501 123.008501)
		(width 0.114)
		(layer "In5.Cu")
		(net 377)
	)
	(segment
		(start 202.341423 128.600001)
		(end 193.333579 128.600001)
		(width 0.1)
		(layer "In5.Cu")
		(net 377)
	)
	(segment
		(start 162.260001 123.240001)
		(end 161.266501 123.240001)
		(width 0.114)
		(layer "In5.Cu")
		(net 377)
	)
	(segment
		(start 201.400001 122.400001)
		(end 202.266423 122.400001)
		(width 0.1)
		(layer "In5.Cu")
		(net 377)
	)
	(segment
		(start 161.469563 126.602001)
		(end 162.285001 126.602001)
		(width 0.114)
		(layer "In5.Cu")
		(net 377)
	)
	(segment
		(start 183.448501 128.100001)
		(end 183.405001 128.143501)
		(width 0.1)
		(layer "In5.Cu")
		(net 377)
	)
	(segment
		(start 161.641501 122.085001)
		(end 162.285001 122.085001)
		(width 0.114)
		(layer "In5.Cu")
		(net 377)
	)
	(segment
		(start 162.285001 119.698001)
		(end 161.641501 119.698001)
		(width 0.114)
		(layer "In5.Cu")
		(net 377)
	)
	(segment
		(start 181.080441 128.143501)
		(end 183.405001 128.143501)
		(width 0.114)
		(layer "In5.Cu")
		(net 377)
	)
	(segment
		(start 160.863501 118.843501)
		(end 162.075561 118.843501)
		(width 0.114)
		(layer "In5.Cu")
		(net 377)
	)
	(segment
		(start 201.000001 122.000001)
		(end 201.400001 122.400001)
		(width 0.1)
		(layer "In5.Cu")
		(net 377)
	)
	(segment
		(start 162.285001 121.098001)
		(end 161.641501 121.098001)
		(width 0.114)
		(layer "In5.Cu")
		(net 377)
	)
	(segment
		(start 202.266423 122.400001)
		(end 202.600001 122.733579)
		(width 0.1)
		(layer "In5.Cu")
		(net 377)
	)
	(segment
		(start 161.266501 124.277001)
		(end 162.260001 124.277001)
		(width 0.114)
		(layer "In5.Cu")
		(net 377)
	)
	(segment
		(start 180.855441 128.368501)
		(end 181.080441 128.143501)
		(width 0.114)
		(layer "In5.Cu")
		(net 377)
	)
	(segment
		(start 162.285001 125.615001)
		(end 161.469563 125.615001)
		(width 0.114)
		(layer "In5.Cu")
		(net 377)
	)
	(segment
		(start 162.491501 127.844441)
		(end 163.015561 128.368501)
		(width 0.114)
		(layer "In5.Cu")
		(net 377)
	)
	(segment
		(start 162.491501 124.550147)
		(end 162.491501 125.408501)
		(width 0.114)
		(layer "In5.Cu")
		(net 377)
	)
	(segment
		(start 162.491501 126.871389)
		(end 162.491501 127.844441)
		(width 0.114)
		(layer "In5.Cu")
		(net 377)
	)
	(segment
		(start 160.730001 118.977001)
		(end 160.863501 118.843501)
		(width 0.114)
		(layer "In5.Cu")
		(net 377)
	)
	(segment
		(start 162.075561 118.843501)
		(end 162.491501 119.259441)
		(width 0.114)
		(layer "In5.Cu")
		(net 377)
	)
	(segment
		(start 161.641501 120.685001)
		(end 162.285001 120.685001)
		(width 0.114)
		(layer "In5.Cu")
		(net 377)
	)
	(segment
		(start 202.600001 128.341423)
		(end 202.341423 128.600001)
		(width 0.1)
		(layer "In5.Cu")
		(net 377)
	)
	(segment
		(start 163.015561 128.368501)
		(end 180.855441 128.368501)
		(width 0.114)
		(layer "In5.Cu")
		(net 377)
	)
	(segment
		(start 162.491501 119.259441)
		(end 162.491501 119.491501)
		(width 0.114)
		(layer "In5.Cu")
		(net 377)
	)
	(segment
		(start 162.491501 124.508501)
		(end 162.491501 124.550147)
		(width 0.114)
		(layer "In5.Cu")
		(net 377)
	)
	(segment
		(start 193.333579 128.600001)
		(end 192.833579 128.100001)
		(width 0.1)
		(layer "In5.Cu")
		(net 377)
	)
	(segment
		(start 162.491501 126.808501)
		(end 162.491501 126.871389)
		(width 0.114)
		(layer "In5.Cu")
		(net 377)
	)
	(arc
		(start 162.285001 120.685001)
		(mid 162.431019 120.745483)
		(end 162.491501 120.891501)
		(width 0.114)
		(layer "In5.Cu")
		(net 377)
	)
	(arc
		(start 162.491501 123.008501)
		(mid 162.423696 123.172196)
		(end 162.260001 123.240001)
		(width 0.114)
		(layer "In5.Cu")
		(net 377)
	)
	(arc
		(start 161.641501 119.698001)
		(mid 161.292544 119.842544)
		(end 161.148001 120.191501)
		(width 0.114)
		(layer "In5.Cu")
		(net 377)
	)
	(arc
		(start 162.491501 120.891501)
		(mid 162.431019 121.037519)
		(end 162.285001 121.098001)
		(width 0.114)
		(layer "In5.Cu")
		(net 377)
	)
	(arc
		(start 162.285001 126.602001)
		(mid 162.431019 126.662483)
		(end 162.491501 126.808501)
		(width 0.114)
		(layer "In5.Cu")
		(net 377)
	)
	(arc
		(start 162.491501 125.408501)
		(mid 162.431019 125.554519)
		(end 162.285001 125.615001)
		(width 0.114)
		(layer "In5.Cu")
		(net 377)
	)
	(arc
		(start 161.148001 120.191501)
		(mid 161.292544 120.540458)
		(end 161.641501 120.685001)
		(width 0.114)
		(layer "In5.Cu")
		(net 377)
	)
	(arc
		(start 161.469563 125.615001)
		(mid 161.120606 125.759544)
		(end 160.976063 126.108501)
		(width 0.114)
		(layer "In5.Cu")
		(net 377)
	)
	(arc
		(start 160.748001 123.758501)
		(mid 160.899866 124.125136)
		(end 161.266501 124.277001)
		(width 0.114)
		(layer "In5.Cu")
		(net 377)
	)
	(arc
		(start 160.976063 126.108501)
		(mid 161.120606 126.457458)
		(end 161.469563 126.602001)
		(width 0.114)
		(layer "In5.Cu")
		(net 377)
	)
	(arc
		(start 161.148001 121.591501)
		(mid 161.292544 121.940458)
		(end 161.641501 122.085001)
		(width 0.114)
		(layer "In5.Cu")
		(net 377)
	)
	(arc
		(start 161.266501 123.240001)
		(mid 160.899866 123.391866)
		(end 160.748001 123.758501)
		(width 0.114)
		(layer "In5.Cu")
		(net 377)
	)
	(arc
		(start 162.260001 124.277001)
		(mid 162.423696 124.344806)
		(end 162.491501 124.508501)
		(width 0.114)
		(layer "In5.Cu")
		(net 377)
	)
	(arc
		(start 162.285001 122.085001)
		(mid 162.431019 122.145483)
		(end 162.491501 122.291501)
		(width 0.114)
		(layer "In5.Cu")
		(net 377)
	)
	(arc
		(start 161.641501 121.098001)
		(mid 161.292544 121.242544)
		(end 161.148001 121.591501)
		(width 0.114)
		(layer "In5.Cu")
		(net 377)
	)
	(arc
		(start 162.491501 119.491501)
		(mid 162.431019 119.637519)
		(end 162.285001 119.698001)
		(width 0.114)
		(layer "In5.Cu")
		(net 377)
	)
	(segment
		(start 237.585 144.2)
		(end 236.835 143.45)
		(width 0.177)
		(layer "F.Cu")
		(net 378)
	)
	(segment
		(start 238.2 144.2)
		(end 237.585 144.2)
		(width 0.177)
		(layer "F.Cu")
		(net 378)
	)
	(segment
		(start 239.35 135.535)
		(end 239.35 136.2)
		(width 0.1)
		(layer "F.Cu")
		(net 379)
	)
	(segment
		(start 239 135.185)
		(end 239.35 135.535)
		(width 0.1)
		(layer "F.Cu")
		(net 379)
	)
	(segment
		(start 238 135.185)
		(end 239 135.185)
		(width 0.1)
		(layer "F.Cu")
		(net 379)
	)
	(segment
		(start 165.175001 119.335001)
		(end 165.200001 119.335001)
		(width 0.1)
		(layer "F.Cu")
		(net 380)
	)
	(via
		(at 165.200001 119.335001)
		(size 0.45)
		(drill 0.2)
		(layers "F.Cu" "B.Cu")
		(net 380)
	)
	(segment
		(start 160.095001 118.246198)
		(end 160.416804 118.568001)
		(width 0.16)
		(layer "F.Cu")
		(net 381)
	)
	(segment
		(start 160.095001 118.065001)
		(end 160.095001 118.246198)
		(width 0.16)
		(layer "F.Cu")
		(net 381)
	)
	(segment
		(start 200.5 123.5)
		(end 201 123)
		(width 0.256)
		(layer "F.Cu")
		(net 381)
	)
	(segment
		(start 160.585002 118.568)
		(end 160.416804 118.568001)
		(width 0.16)
		(layer "F.Cu")
		(net 381)
	)
	(segment
		(start 160.585002 118.568)
		(end 160.730001 118.423001)
		(width 0.16)
		(layer "F.Cu")
		(net 381)
	)
	(via
		(at 201 123)
		(size 0.45)
		(drill 0.2)
		(layers "F.Cu" "B.Cu")
		(net 381)
	)
	(via
		(at 160.730001 118.423001)
		(size 0.45)
		(drill 0.2)
		(layers "F.Cu" "B.Cu")
		(net 381)
	)
	(segment
		(start 160.730001 118.423001)
		(end 160.863501 118.556501)
		(width 0.114)
		(layer "In5.Cu")
		(net 381)
	)
	(segment
		(start 161.266501 123.990001)
		(end 162.260001 123.990001)
		(width 0.114)
		(layer "In5.Cu")
		(net 381)
	)
	(segment
		(start 161.745501 118.556501)
		(end 162.194441 118.556501)
		(width 0.114)
		(layer "In5.Cu")
		(net 381)
	)
	(segment
		(start 162.778501 127.725561)
		(end 163.134441 128.081501)
		(width 0.114)
		(layer "In5.Cu")
		(net 381)
	)
	(segment
		(start 163.134441 128.081501)
		(end 180.736561 128.081501)
		(width 0.114)
		(layer "In5.Cu")
		(net 381)
	)
	(segment
		(start 162.260001 123.527001)
		(end 161.266501 123.527001)
		(width 0.114)
		(layer "In5.Cu")
		(net 381)
	)
	(segment
		(start 160.863501 118.556501)
		(end 161.167501 118.556501)
		(width 0.114)
		(layer "In5.Cu")
		(net 381)
	)
	(segment
		(start 201.000001 123.000001)
		(end 201.400001 122.600001)
		(width 0.1)
		(layer "In5.Cu")
		(net 381)
	)
	(segment
		(start 162.778501 124.508501)
		(end 162.778501 124.550147)
		(width 0.114)
		(layer "In5.Cu")
		(net 381)
	)
	(segment
		(start 161.641501 120.398001)
		(end 162.285001 120.398001)
		(width 0.114)
		(layer "In5.Cu")
		(net 381)
	)
	(segment
		(start 162.285001 125.902001)
		(end 161.469563 125.902001)
		(width 0.114)
		(layer "In5.Cu")
		(net 381)
	)
	(segment
		(start 162.778501 119.140561)
		(end 162.778501 119.491501)
		(width 0.114)
		(layer "In5.Cu")
		(net 381)
	)
	(segment
		(start 180.961561 127.856501)
		(end 183.405001 127.856501)
		(width 0.114)
		(layer "In5.Cu")
		(net 381)
	)
	(segment
		(start 162.778501 124.550147)
		(end 162.778501 125.408501)
		(width 0.114)
		(layer "In5.Cu")
		(net 381)
	)
	(segment
		(start 202.258579 128.400001)
		(end 193.416423 128.400001)
		(width 0.1)
		(layer "In5.Cu")
		(net 381)
	)
	(segment
		(start 161.469563 126.315001)
		(end 162.285001 126.315001)
		(width 0.114)
		(layer "In5.Cu")
		(net 381)
	)
	(segment
		(start 202.400001 122.816423)
		(end 202.400001 128.258579)
		(width 0.1)
		(layer "In5.Cu")
		(net 381)
	)
	(segment
		(start 192.916423 127.900001)
		(end 183.448501 127.900001)
		(width 0.1)
		(layer "In5.Cu")
		(net 381)
	)
	(segment
		(start 161.695501 118.556501)
		(end 161.745501 118.556501)
		(width 0.114)
		(layer "In5.Cu")
		(net 381)
	)
	(segment
		(start 162.285001 119.985001)
		(end 161.641501 119.985001)
		(width 0.114)
		(layer "In5.Cu")
		(net 381)
	)
	(segment
		(start 161.299501 118.424501)
		(end 161.299501 118.225319)
		(width 0.114)
		(layer "In5.Cu")
		(net 381)
	)
	(segment
		(start 161.563501 118.225319)
		(end 161.563501 118.424501)
		(width 0.114)
		(layer "In5.Cu")
		(net 381)
	)
	(segment
		(start 180.736561 128.081501)
		(end 180.961561 127.856501)
		(width 0.114)
		(layer "In5.Cu")
		(net 381)
	)
	(segment
		(start 193.416423 128.400001)
		(end 192.916423 127.900001)
		(width 0.1)
		(layer "In5.Cu")
		(net 381)
	)
	(segment
		(start 162.778501 126.871389)
		(end 162.778501 127.725561)
		(width 0.114)
		(layer "In5.Cu")
		(net 381)
	)
	(segment
		(start 162.194441 118.556501)
		(end 162.778501 119.140561)
		(width 0.114)
		(layer "In5.Cu")
		(net 381)
	)
	(segment
		(start 202.400001 128.258579)
		(end 202.258579 128.400001)
		(width 0.1)
		(layer "In5.Cu")
		(net 381)
	)
	(segment
		(start 201.400001 122.600001)
		(end 202.183579 122.600001)
		(width 0.1)
		(layer "In5.Cu")
		(net 381)
	)
	(segment
		(start 202.183579 122.600001)
		(end 202.400001 122.816423)
		(width 0.1)
		(layer "In5.Cu")
		(net 381)
	)
	(segment
		(start 161.641501 121.798001)
		(end 162.285001 121.798001)
		(width 0.114)
		(layer "In5.Cu")
		(net 381)
	)
	(segment
		(start 183.448501 127.900001)
		(end 183.405001 127.856501)
		(width 0.1)
		(layer "In5.Cu")
		(net 381)
	)
	(segment
		(start 162.778501 122.291501)
		(end 162.778501 123.008501)
		(width 0.114)
		(layer "In5.Cu")
		(net 381)
	)
	(segment
		(start 162.778501 126.808501)
		(end 162.778501 126.871389)
		(width 0.114)
		(layer "In5.Cu")
		(net 381)
	)
	(segment
		(start 162.285001 121.385001)
		(end 161.641501 121.385001)
		(width 0.114)
		(layer "In5.Cu")
		(net 381)
	)
	(arc
		(start 161.035001 123.758501)
		(mid 161.102806 123.922196)
		(end 161.266501 123.990001)
		(width 0.114)
		(layer "In5.Cu")
		(net 381)
	)
	(arc
		(start 162.260001 123.990001)
		(mid 162.626636 124.141866)
		(end 162.778501 124.508501)
		(width 0.114)
		(layer "In5.Cu")
		(net 381)
	)
	(arc
		(start 161.641501 119.985001)
		(mid 161.495483 120.045483)
		(end 161.435001 120.191501)
		(width 0.114)
		(layer "In5.Cu")
		(net 381)
	)
	(arc
		(start 162.285001 121.798001)
		(mid 162.633958 121.942544)
		(end 162.778501 122.291501)
		(width 0.114)
		(layer "In5.Cu")
		(net 381)
	)
	(arc
		(start 161.266501 123.527001)
		(mid 161.102806 123.594806)
		(end 161.035001 123.758501)
		(width 0.114)
		(layer "In5.Cu")
		(net 381)
	)
	(arc
		(start 161.299501 118.225319)
		(mid 161.338163 118.131981)
		(end 161.431501 118.093319)
		(width 0.114)
		(layer "In5.Cu")
		(net 381)
	)
	(arc
		(start 162.778501 125.408501)
		(mid 162.633958 125.757458)
		(end 162.285001 125.902001)
		(width 0.114)
		(layer "In5.Cu")
		(net 381)
	)
	(arc
		(start 161.435001 120.191501)
		(mid 161.495483 120.337519)
		(end 161.641501 120.398001)
		(width 0.114)
		(layer "In5.Cu")
		(net 381)
	)
	(arc
		(start 162.778501 120.891501)
		(mid 162.633958 121.240458)
		(end 162.285001 121.385001)
		(width 0.114)
		(layer "In5.Cu")
		(net 381)
	)
	(arc
		(start 161.263063 126.108501)
		(mid 161.323545 126.254519)
		(end 161.469563 126.315001)
		(width 0.114)
		(layer "In5.Cu")
		(net 381)
	)
	(arc
		(start 161.563501 118.424501)
		(mid 161.602163 118.517839)
		(end 161.695501 118.556501)
		(width 0.114)
		(layer "In5.Cu")
		(net 381)
	)
	(arc
		(start 162.778501 123.008501)
		(mid 162.626636 123.375136)
		(end 162.260001 123.527001)
		(width 0.114)
		(layer "In5.Cu")
		(net 381)
	)
	(arc
		(start 162.778501 119.491501)
		(mid 162.633958 119.840458)
		(end 162.285001 119.985001)
		(width 0.114)
		(layer "In5.Cu")
		(net 381)
	)
	(arc
		(start 162.285001 120.398001)
		(mid 162.633958 120.542544)
		(end 162.778501 120.891501)
		(width 0.114)
		(layer "In5.Cu")
		(net 381)
	)
	(arc
		(start 161.469563 125.902001)
		(mid 161.323545 125.962483)
		(end 161.263063 126.108501)
		(width 0.114)
		(layer "In5.Cu")
		(net 381)
	)
	(arc
		(start 161.641501 121.385001)
		(mid 161.495483 121.445483)
		(end 161.435001 121.591501)
		(width 0.114)
		(layer "In5.Cu")
		(net 381)
	)
	(arc
		(start 161.435001 121.591501)
		(mid 161.495483 121.737519)
		(end 161.641501 121.798001)
		(width 0.114)
		(layer "In5.Cu")
		(net 381)
	)
	(arc
		(start 162.285001 126.315001)
		(mid 162.633958 126.459544)
		(end 162.778501 126.808501)
		(width 0.114)
		(layer "In5.Cu")
		(net 381)
	)
	(arc
		(start 161.431501 118.093319)
		(mid 161.524839 118.131981)
		(end 161.563501 118.225319)
		(width 0.114)
		(layer "In5.Cu")
		(net 381)
	)
	(arc
		(start 161.167501 118.556501)
		(mid 161.260839 118.517839)
		(end 161.299501 118.424501)
		(width 0.114)
		(layer "In5.Cu")
		(net 381)
	)
	(segment
		(start 250.915 98.5)
		(end 250.4 99.015)
		(width 0.182)
		(layer "F.Cu")
		(net 382)
	)
	(segment
		(start 251.7 98.5)
		(end 250.915 98.5)
		(width 0.182)
		(layer "F.Cu")
		(net 382)
	)
	(segment
		(start 165.175001 118.065001)
		(end 165.200001 118.065001)
		(width 0.1)
		(layer "F.Cu")
		(net 383)
	)
	(via
		(at 165.200001 118.065001)
		(size 0.45)
		(drill 0.2)
		(layers "F.Cu" "B.Cu")
		(net 383)
	)
	(segment
		(start 159.315002 116.292002)
		(end 159.146804 116.292001)
		(width 0.16)
		(layer "F.Cu")
		(net 384)
	)
	(segment
		(start 159.315002 116.292002)
		(end 159.460001 116.437001)
		(width 0.16)
		(layer "F.Cu")
		(net 384)
	)
	(segment
		(start 159.146804 116.292001)
		(end 158.825001 116.613804)
		(width 0.16)
		(layer "F.Cu")
		(net 384)
	)
	(segment
		(start 158.825001 116.613804)
		(end 158.825001 116.795001)
		(width 0.16)
		(layer "F.Cu")
		(net 384)
	)
	(segment
		(start 199.5 121.5)
		(end 199 121)
		(width 0.256)
		(layer "F.Cu")
		(net 384)
	)
	(via
		(at 199 121)
		(size 0.45)
		(drill 0.2)
		(layers "F.Cu" "B.Cu")
		(net 384)
	)
	(via
		(at 159.460001 116.437001)
		(size 0.45)
		(drill 0.2)
		(layers "F.Cu" "B.Cu")
		(net 384)
	)
	(segment
		(start 203.241423 129.600001)
		(end 193.258579 129.600001)
		(width 0.1)
		(layer "In5.Cu")
		(net 384)
	)
	(segment
		(start 159.956501 126.459441)
		(end 163.135561 129.638501)
		(width 0.114)
		(layer "In5.Cu")
		(net 384)
	)
	(segment
		(start 159.956501 124.543501)
		(end 159.956501 124.551971)
		(width 0.114)
		(layer "In5.Cu")
		(net 384)
	)
	(segment
		(start 203.600001 129.241423)
		(end 203.241423 129.600001)
		(width 0.1)
		(layer "In5.Cu")
		(net 384)
	)
	(segment
		(start 160.275561 116.303501)
		(end 160.616501 116.644441)
		(width 0.114)
		(layer "In5.Cu")
		(net 384)
	)
	(segment
		(start 199.400001 121.400001)
		(end 203.241423 121.400001)
		(width 0.1)
		(layer "In5.Cu")
		(net 384)
	)
	(segment
		(start 159.956501 124.551971)
		(end 159.956501 126.459441)
		(width 0.114)
		(layer "In5.Cu")
		(net 384)
	)
	(segment
		(start 192.758579 129.100001)
		(end 183.448501 129.100001)
		(width 0.1)
		(layer "In5.Cu")
		(net 384)
	)
	(segment
		(start 199.000001 121.000001)
		(end 199.400001 121.400001)
		(width 0.1)
		(layer "In5.Cu")
		(net 384)
	)
	(segment
		(start 203.241423 121.400001)
		(end 203.600001 121.758579)
		(width 0.1)
		(layer "In5.Cu")
		(net 384)
	)
	(segment
		(start 160.616501 116.644441)
		(end 160.616501 117.250719)
		(width 0.114)
		(layer "In5.Cu")
		(net 384)
	)
	(segment
		(start 193.258579 129.600001)
		(end 192.758579 129.100001)
		(width 0.1)
		(layer "In5.Cu")
		(net 384)
	)
	(segment
		(start 183.448501 129.100001)
		(end 183.405001 129.143501)
		(width 0.1)
		(layer "In5.Cu")
		(net 384)
	)
	(segment
		(start 159.956501 117.910719)
		(end 159.956501 123.143501)
		(width 0.114)
		(layer "In5.Cu")
		(net 384)
	)
	(segment
		(start 163.135561 129.638501)
		(end 181.998441 129.638501)
		(width 0.114)
		(layer "In5.Cu")
		(net 384)
	)
	(segment
		(start 159.593501 116.303501)
		(end 160.275561 116.303501)
		(width 0.114)
		(layer "In5.Cu")
		(net 384)
	)
	(segment
		(start 160.616501 117.250719)
		(end 159.956501 117.910719)
		(width 0.114)
		(layer "In5.Cu")
		(net 384)
	)
	(segment
		(start 159.313728 124.337001)
		(end 159.750001 124.337001)
		(width 0.114)
		(layer "In5.Cu")
		(net 384)
	)
	(segment
		(start 203.600001 121.758579)
		(end 203.600001 129.241423)
		(width 0.1)
		(layer "In5.Cu")
		(net 384)
	)
	(segment
		(start 159.460001 116.437001)
		(end 159.593501 116.303501)
		(width 0.114)
		(layer "In5.Cu")
		(net 384)
	)
	(segment
		(start 182.493441 129.143501)
		(end 183.405001 129.143501)
		(width 0.114)
		(layer "In5.Cu")
		(net 384)
	)
	(segment
		(start 181.998441 129.638501)
		(end 182.493441 129.143501)
		(width 0.114)
		(layer "In5.Cu")
		(net 384)
	)
	(segment
		(start 159.750001 123.350001)
		(end 159.313728 123.350001)
		(width 0.114)
		(layer "In5.Cu")
		(net 384)
	)
	(arc
		(start 159.313728 123.350001)
		(mid 158.964771 123.494544)
		(end 158.820228 123.843501)
		(width 0.114)
		(layer "In5.Cu")
		(net 384)
	)
	(arc
		(start 158.820228 123.843501)
		(mid 158.964771 124.192458)
		(end 159.313728 124.337001)
		(width 0.114)
		(layer "In5.Cu")
		(net 384)
	)
	(arc
		(start 159.956501 123.143501)
		(mid 159.896019 123.289519)
		(end 159.750001 123.350001)
		(width 0.114)
		(layer "In5.Cu")
		(net 384)
	)
	(arc
		(start 159.750001 124.337001)
		(mid 159.896019 124.397483)
		(end 159.956501 124.543501)
		(width 0.114)
		(layer "In5.Cu")
		(net 384)
	)
	(segment
		(start 244.515 113.9)
		(end 244.515 114.085)
		(width 0.1)
		(layer "F.Cu")
		(net 385)
	)
	(segment
		(start 242.615 114.9)
		(end 242.6 114.915)
		(width 0.1)
		(layer "F.Cu")
		(net 385)
	)
	(segment
		(start 242.665 114.915)
		(end 242.6 114.915)
		(width 0.1)
		(layer "F.Cu")
		(net 385)
	)
	(segment
		(start 243.9 114.7)
		(end 243.9 115.45)
		(width 0.1)
		(layer "F.Cu")
		(net 385)
	)
	(segment
		(start 244.515 114.085)
		(end 243.9 114.7)
		(width 0.1)
		(layer "F.Cu")
		(net 385)
	)
	(segment
		(start 243.9 115.45)
		(end 243.2 115.45)
		(width 0.1)
		(layer "F.Cu")
		(net 385)
	)
	(segment
		(start 242.615 113.9)
		(end 242.615 114.9)
		(width 0.1)
		(layer "F.Cu")
		(net 385)
	)
	(segment
		(start 243.2 115.45)
		(end 242.665 114.915)
		(width 0.1)
		(layer "F.Cu")
		(net 385)
	)
	(segment
		(start 247.485 114.665)
		(end 247.485 113.9)
		(width 0.1)
		(layer "F.Cu")
		(net 386)
	)
	(segment
		(start 246.5 115.45)
		(end 246.7 115.45)
		(width 0.1)
		(layer "F.Cu")
		(net 386)
	)
	(segment
		(start 246.7 115.45)
		(end 247.485 114.665)
		(width 0.1)
		(layer "F.Cu")
		(net 386)
	)
	(segment
		(start 199.5 122.5)
		(end 199 122)
		(width 0.256)
		(layer "F.Cu")
		(net 387)
	)
	(segment
		(start 158.825001 115.525001)
		(end 158.825001 115.706198)
		(width 0.16)
		(layer "F.Cu")
		(net 387)
	)
	(segment
		(start 158.825001 115.706198)
		(end 159.146804 116.028001)
		(width 0.16)
		(layer "F.Cu")
		(net 387)
	)
	(segment
		(start 159.315002 116.028)
		(end 159.460001 115.883001)
		(width 0.16)
		(layer "F.Cu")
		(net 387)
	)
	(segment
		(start 159.315002 116.028)
		(end 159.146804 116.028001)
		(width 0.16)
		(layer "F.Cu")
		(net 387)
	)
	(via
		(at 159.460001 115.883001)
		(size 0.45)
		(drill 0.2)
		(layers "F.Cu" "B.Cu")
		(net 387)
	)
	(via
		(at 199 122)
		(size 0.45)
		(drill 0.2)
		(layers "F.Cu" "B.Cu")
		(net 387)
	)
	(segment
		(start 160.805323 116.427383)
		(end 160.903501 116.525561)
		(width 0.114)
		(layer "In5.Cu")
		(net 387)
	)
	(segment
		(start 193.341423 129.400001)
		(end 192.841423 128.900001)
		(width 0.1)
		(layer "In5.Cu")
		(net 387)
	)
	(segment
		(start 160.903501 116.525561)
		(end 160.903501 117.369599)
		(width 0.114)
		(layer "In5.Cu")
		(net 387)
	)
	(segment
		(start 183.448501 128.900001)
		(end 183.405001 128.856501)
		(width 0.1)
		(layer "In5.Cu")
		(net 387)
	)
	(segment
		(start 163.254441 129.351501)
		(end 181.879561 129.351501)
		(width 0.114)
		(layer "In5.Cu")
		(net 387)
	)
	(segment
		(start 160.618648 116.05403)
		(end 160.618647 116.054031)
		(width 0.114)
		(layer "In5.Cu")
		(net 387)
	)
	(segment
		(start 160.903501 117.369599)
		(end 160.243501 118.029599)
		(width 0.114)
		(layer "In5.Cu")
		(net 387)
	)
	(segment
		(start 199.000001 122.000001)
		(end 199.400001 121.600001)
		(width 0.1)
		(layer "In5.Cu")
		(net 387)
	)
	(segment
		(start 160.243501 124.551971)
		(end 160.243501 126.340561)
		(width 0.114)
		(layer "In5.Cu")
		(net 387)
	)
	(segment
		(start 159.593501 116.016501)
		(end 160.394441 116.016501)
		(width 0.114)
		(layer "In5.Cu")
		(net 387)
	)
	(segment
		(start 159.313728 124.050001)
		(end 159.750001 124.050001)
		(width 0.114)
		(layer "In5.Cu")
		(net 387)
	)
	(segment
		(start 160.805322 116.427382)
		(end 160.805323 116.427383)
		(width 0.114)
		(layer "In5.Cu")
		(net 387)
	)
	(segment
		(start 181.879561 129.351501)
		(end 182.374561 128.856501)
		(width 0.114)
		(layer "In5.Cu")
		(net 387)
	)
	(segment
		(start 160.243501 118.029599)
		(end 160.243501 123.143501)
		(width 0.114)
		(layer "In5.Cu")
		(net 387)
	)
	(segment
		(start 203.400001 121.841423)
		(end 203.400001 129.158579)
		(width 0.1)
		(layer "In5.Cu")
		(net 387)
	)
	(segment
		(start 160.618647 116.054031)
		(end 160.706851 115.965828)
		(width 0.114)
		(layer "In5.Cu")
		(net 387)
	)
	(segment
		(start 160.893526 116.152505)
		(end 160.893527 116.152504)
		(width 0.114)
		(layer "In5.Cu")
		(net 387)
	)
	(segment
		(start 160.243501 124.543501)
		(end 160.243501 124.551971)
		(width 0.114)
		(layer "In5.Cu")
		(net 387)
	)
	(segment
		(start 203.158579 129.400001)
		(end 193.341423 129.400001)
		(width 0.1)
		(layer "In5.Cu")
		(net 387)
	)
	(segment
		(start 159.750001 123.637001)
		(end 159.313728 123.637001)
		(width 0.114)
		(layer "In5.Cu")
		(net 387)
	)
	(segment
		(start 160.893527 116.152504)
		(end 160.805322 116.240706)
		(width 0.114)
		(layer "In5.Cu")
		(net 387)
	)
	(segment
		(start 160.243501 126.340561)
		(end 163.254441 129.351501)
		(width 0.114)
		(layer "In5.Cu")
		(net 387)
	)
	(segment
		(start 192.841423 128.900001)
		(end 183.448501 128.900001)
		(width 0.1)
		(layer "In5.Cu")
		(net 387)
	)
	(segment
		(start 182.374561 128.856501)
		(end 183.405001 128.856501)
		(width 0.114)
		(layer "In5.Cu")
		(net 387)
	)
	(segment
		(start 203.158579 121.600001)
		(end 203.400001 121.841423)
		(width 0.1)
		(layer "In5.Cu")
		(net 387)
	)
	(segment
		(start 203.400001 129.158579)
		(end 203.158579 129.400001)
		(width 0.1)
		(layer "In5.Cu")
		(net 387)
	)
	(segment
		(start 159.460001 115.883001)
		(end 159.593501 116.016501)
		(width 0.114)
		(layer "In5.Cu")
		(net 387)
	)
	(segment
		(start 199.400001 121.600001)
		(end 203.158579 121.600001)
		(width 0.1)
		(layer "In5.Cu")
		(net 387)
	)
	(segment
		(start 160.394441 116.016501)
		(end 160.431971 116.054031)
		(width 0.114)
		(layer "In5.Cu")
		(net 387)
	)
	(arc
		(start 159.750001 124.050001)
		(mid 160.098958 124.194544)
		(end 160.243501 124.543501)
		(width 0.114)
		(layer "In5.Cu")
		(net 387)
	)
	(arc
		(start 159.313728 123.637001)
		(mid 159.16771 123.697483)
		(end 159.107228 123.843501)
		(width 0.114)
		(layer "In5.Cu")
		(net 387)
	)
	(arc
		(start 160.706851 115.965828)
		(mid 160.800189 115.927166)
		(end 160.893527 115.965828)
		(width 0.114)
		(layer "In5.Cu")
		(net 387)
	)
	(arc
		(start 160.243501 123.143501)
		(mid 160.098958 123.492458)
		(end 159.750001 123.637001)
		(width 0.114)
		(layer "In5.Cu")
		(net 387)
	)
	(arc
		(start 160.893527 115.965828)
		(mid 160.932188 116.059166)
		(end 160.893526 116.152505)
		(width 0.114)
		(layer "In5.Cu")
		(net 387)
	)
	(arc
		(start 160.805322 116.240706)
		(mid 160.76666 116.334044)
		(end 160.805322 116.427382)
		(width 0.114)
		(layer "In5.Cu")
		(net 387)
	)
	(arc
		(start 159.107228 123.843501)
		(mid 159.16771 123.989519)
		(end 159.313728 124.050001)
		(width 0.114)
		(layer "In5.Cu")
		(net 387)
	)
	(arc
		(start 160.431971 116.054031)
		(mid 160.525311 116.092694)
		(end 160.618648 116.05403)
		(width 0.114)
		(layer "In5.Cu")
		(net 387)
	)
	(segment
		(start 160.585002 115.022002)
		(end 160.730001 115.167001)
		(width 0.16)
		(layer "F.Cu")
		(net 388)
	)
	(segment
		(start 160.095001 115.343804)
		(end 160.095001 115.525001)
		(width 0.16)
		(layer "F.Cu")
		(net 388)
	)
	(segment
		(start 196.5 123.5)
		(end 196 123)
		(width 0.256)
		(layer "F.Cu")
		(net 388)
	)
	(segment
		(start 160.585002 115.022002)
		(end 160.416804 115.022001)
		(width 0.16)
		(layer "F.Cu")
		(net 388)
	)
	(segment
		(start 160.416804 115.022001)
		(end 160.095001 115.343804)
		(width 0.16)
		(layer "F.Cu")
		(net 388)
	)
	(via
		(at 196 123)
		(size 0.45)
		(drill 0.2)
		(layers "F.Cu" "B.Cu")
		(net 388)
	)
	(via
		(at 160.730001 115.167001)
		(size 0.45)
		(drill 0.2)
		(layers "F.Cu" "B.Cu")
		(net 388)
	)
	(segment
		(start 161.639469 116.104257)
		(end 161.725938 116.017787)
		(width 0.114)
		(layer "In7.Cu")
		(net 388)
	)
	(segment
		(start 173.460001 126.486096)
		(end 173.460001 126.010001)
		(width 0.114)
		(layer "In7.Cu")
		(net 388)
	)
	(segment
		(start 168.260001 126.486096)
		(end 168.260001 126.010001)
		(width 0.114)
		(layer "In7.Cu")
		(net 388)
	)
	(segment
		(start 162.114847 116.017786)
		(end 162.114847 116.017787)
		(width 0.114)
		(layer "In7.Cu")
		(net 388)
	)
	(segment
		(start 174.941501 125.828501)
		(end 181.579441 125.828501)
		(width 0.114)
		(layer "In7.Cu")
		(net 388)
	)
	(segment
		(start 182.271441 125.136501)
		(end 183.442001 125.136501)
		(width 0.114)
		(layer "In7.Cu")
		(net 388)
	)
	(segment
		(start 172.523001 126.010001)
		(end 172.523001 126.486096)
		(width 0.114)
		(layer "In7.Cu")
		(net 388)
	)
	(segment
		(start 193.623579 125.605001)
		(end 193.118579 125.100001)
		(width 0.1)
		(layer "In7.Cu")
		(net 388)
	)
	(segment
		(start 195.266423 125.605001)
		(end 193.623579 125.605001)
		(width 0.1)
		(layer "In7.Cu")
		(net 388)
	)
	(segment
		(start 167.323001 126.010001)
		(end 167.323001 126.486096)
		(width 0.114)
		(layer "In7.Cu")
		(net 388)
	)
	(segment
		(start 161.25056 116.104257)
		(end 161.250561 116.104257)
		(width 0.114)
		(layer "In7.Cu")
		(net 388)
	)
	(segment
		(start 168.623001 126.010001)
		(end 168.623001 126.486096)
		(width 0.114)
		(layer "In7.Cu")
		(net 388)
	)
	(segment
		(start 171.223001 126.010001)
		(end 171.223001 126.486096)
		(width 0.114)
		(layer "In7.Cu")
		(net 388)
	)
	(segment
		(start 160.863501 115.033501)
		(end 161.130561 115.033501)
		(width 0.114)
		(layer "In7.Cu")
		(net 388)
	)
	(segment
		(start 162.310001 120.703001)
		(end 161.666501 120.703001)
		(width 0.114)
		(layer "In7.Cu")
		(net 388)
	)
	(segment
		(start 183.478501 125.100001)
		(end 183.442001 125.136501)
		(width 0.1)
		(layer "In7.Cu")
		(net 388)
	)
	(segment
		(start 166.960001 126.486096)
		(end 166.960001 126.010001)
		(width 0.114)
		(layer "In7.Cu")
		(net 388)
	)
	(segment
		(start 162.491501 121.821501)
		(end 162.491501 124.474441)
		(width 0.114)
		(layer "In7.Cu")
		(net 388)
	)
	(segment
		(start 169.923001 126.010001)
		(end 169.923001 126.486096)
		(width 0.114)
		(layer "In7.Cu")
		(net 388)
	)
	(segment
		(start 161.616501 120.340001)
		(end 162.310001 120.340001)
		(width 0.114)
		(layer "In7.Cu")
		(net 388)
	)
	(segment
		(start 195.600001 123.400001)
		(end 196.000001 123.000001)
		(width 0.1)
		(layer "In7.Cu")
		(net 388)
	)
	(segment
		(start 166.023001 126.010001)
		(end 166.023001 126.486096)
		(width 0.114)
		(layer "In7.Cu")
		(net 388)
	)
	(segment
		(start 162.491501 124.474441)
		(end 163.845561 125.828501)
		(width 0.114)
		(layer "In7.Cu")
		(net 388)
	)
	(segment
		(start 170.860001 126.486096)
		(end 170.860001 126.010001)
		(width 0.114)
		(layer "In7.Cu")
		(net 388)
	)
	(segment
		(start 195.600001 125.271423)
		(end 195.266423 125.605001)
		(width 0.1)
		(layer "In7.Cu")
		(net 388)
	)
	(segment
		(start 173.823001 126.010001)
		(end 173.823001 126.486096)
		(width 0.114)
		(layer "In7.Cu")
		(net 388)
	)
	(segment
		(start 193.118579 125.100001)
		(end 183.478501 125.100001)
		(width 0.1)
		(layer "In7.Cu")
		(net 388)
	)
	(segment
		(start 162.310001 118.103001)
		(end 161.616501 118.103001)
		(width 0.114)
		(layer "In7.Cu")
		(net 388)
	)
	(segment
		(start 161.63947 116.104256)
		(end 161.639469 116.104257)
		(width 0.114)
		(layer "In7.Cu")
		(net 388)
	)
	(segment
		(start 161.33703 115.62888)
		(end 161.337031 115.628879)
		(width 0.114)
		(layer "In7.Cu")
		(net 388)
	)
	(segment
		(start 161.666501 121.640001)
		(end 162.310001 121.640001)
		(width 0.114)
		(layer "In7.Cu")
		(net 388)
	)
	(segment
		(start 161.337031 115.628879)
		(end 161.250561 115.715348)
		(width 0.114)
		(layer "In7.Cu")
		(net 388)
	)
	(segment
		(start 160.730001 115.167001)
		(end 160.863501 115.033501)
		(width 0.114)
		(layer "In7.Cu")
		(net 388)
	)
	(segment
		(start 162.491501 116.394441)
		(end 162.491501 117.921501)
		(width 0.114)
		(layer "In7.Cu")
		(net 388)
	)
	(segment
		(start 162.114847 116.017787)
		(end 162.491501 116.394441)
		(width 0.114)
		(layer "In7.Cu")
		(net 388)
	)
	(segment
		(start 161.130561 115.033501)
		(end 161.337031 115.239971)
		(width 0.114)
		(layer "In7.Cu")
		(net 388)
	)
	(segment
		(start 162.310001 119.403001)
		(end 161.616501 119.403001)
		(width 0.114)
		(layer "In7.Cu")
		(net 388)
	)
	(segment
		(start 195.600001 123.400001)
		(end 195.600001 125.271423)
		(width 0.1)
		(layer "In7.Cu")
		(net 388)
	)
	(segment
		(start 172.160001 126.486096)
		(end 172.160001 126.010001)
		(width 0.114)
		(layer "In7.Cu")
		(net 388)
	)
	(segment
		(start 163.845561 125.828501)
		(end 165.841501 125.828501)
		(width 0.114)
		(layer "In7.Cu")
		(net 388)
	)
	(segment
		(start 174.760001 126.486096)
		(end 174.760001 126.010001)
		(width 0.114)
		(layer "In7.Cu")
		(net 388)
	)
	(segment
		(start 181.579441 125.828501)
		(end 182.271441 125.136501)
		(width 0.114)
		(layer "In7.Cu")
		(net 388)
	)
	(segment
		(start 161.616501 119.040001)
		(end 162.310001 119.040001)
		(width 0.114)
		(layer "In7.Cu")
		(net 388)
	)
	(segment
		(start 169.560001 126.486096)
		(end 169.560001 126.010001)
		(width 0.114)
		(layer "In7.Cu")
		(net 388)
	)
	(arc
		(start 172.341501 125.828501)
		(mid 172.469841 125.881661)
		(end 172.523001 126.010001)
		(width 0.114)
		(layer "In7.Cu")
		(net 388)
	)
	(arc
		(start 169.923001 126.486096)
		(mid 170.060221 126.817376)
		(end 170.391501 126.954596)
		(width 0.114)
		(layer "In7.Cu")
		(net 388)
	)
	(arc
		(start 162.491501 117.921501)
		(mid 162.438341 118.049841)
		(end 162.310001 118.103001)
		(width 0.114)
		(layer "In7.Cu")
		(net 388)
	)
	(arc
		(start 174.760001 126.010001)
		(mid 174.813161 125.881661)
		(end 174.941501 125.828501)
		(width 0.114)
		(layer "In7.Cu")
		(net 388)
	)
	(arc
		(start 167.141501 125.828501)
		(mid 167.269841 125.881661)
		(end 167.323001 126.010001)
		(width 0.114)
		(layer "In7.Cu")
		(net 388)
	)
	(arc
		(start 162.310001 119.040001)
		(mid 162.438341 119.093161)
		(end 162.491501 119.221501)
		(width 0.114)
		(layer "In7.Cu")
		(net 388)
	)
	(arc
		(start 161.148001 118.571501)
		(mid 161.285221 118.902781)
		(end 161.616501 119.040001)
		(width 0.114)
		(layer "In7.Cu")
		(net 388)
	)
	(arc
		(start 168.441501 125.828501)
		(mid 168.569841 125.881661)
		(end 168.623001 126.010001)
		(width 0.114)
		(layer "In7.Cu")
		(net 388)
	)
	(arc
		(start 173.823001 126.486096)
		(mid 173.960221 126.817376)
		(end 174.291501 126.954596)
		(width 0.114)
		(layer "In7.Cu")
		(net 388)
	)
	(arc
		(start 162.310001 121.640001)
		(mid 162.438341 121.693161)
		(end 162.491501 121.821501)
		(width 0.114)
		(layer "In7.Cu")
		(net 388)
	)
	(arc
		(start 161.666501 120.703001)
		(mid 161.335221 120.840221)
		(end 161.198001 121.171501)
		(width 0.114)
		(layer "In7.Cu")
		(net 388)
	)
	(arc
		(start 168.623001 126.486096)
		(mid 168.760221 126.817376)
		(end 169.091501 126.954596)
		(width 0.114)
		(layer "In7.Cu")
		(net 388)
	)
	(arc
		(start 166.960001 126.010001)
		(mid 167.013161 125.881661)
		(end 167.141501 125.828501)
		(width 0.114)
		(layer "In7.Cu")
		(net 388)
	)
	(arc
		(start 169.091501 126.954596)
		(mid 169.422781 126.817376)
		(end 169.560001 126.486096)
		(width 0.114)
		(layer "In7.Cu")
		(net 388)
	)
	(arc
		(start 166.023001 126.486096)
		(mid 166.160221 126.817376)
		(end 166.491501 126.954596)
		(width 0.114)
		(layer "In7.Cu")
		(net 388)
	)
	(arc
		(start 162.491501 119.221501)
		(mid 162.438341 119.349841)
		(end 162.310001 119.403001)
		(width 0.114)
		(layer "In7.Cu")
		(net 388)
	)
	(arc
		(start 173.641501 125.828501)
		(mid 173.769841 125.881661)
		(end 173.823001 126.010001)
		(width 0.114)
		(layer "In7.Cu")
		(net 388)
	)
	(arc
		(start 161.250561 116.104257)
		(mid 161.445016 116.184802)
		(end 161.63947 116.104256)
		(width 0.114)
		(layer "In7.Cu")
		(net 388)
	)
	(arc
		(start 174.291501 126.954596)
		(mid 174.622781 126.817376)
		(end 174.760001 126.486096)
		(width 0.114)
		(layer "In7.Cu")
		(net 388)
	)
	(arc
		(start 173.460001 126.010001)
		(mid 173.513161 125.881661)
		(end 173.641501 125.828501)
		(width 0.114)
		(layer "In7.Cu")
		(net 388)
	)
	(arc
		(start 172.991501 126.954596)
		(mid 173.322781 126.817376)
		(end 173.460001 126.486096)
		(width 0.114)
		(layer "In7.Cu")
		(net 388)
	)
	(arc
		(start 162.491501 120.521501)
		(mid 162.438341 120.649841)
		(end 162.310001 120.703001)
		(width 0.114)
		(layer "In7.Cu")
		(net 388)
	)
	(arc
		(start 167.791501 126.954596)
		(mid 168.122781 126.817376)
		(end 168.260001 126.486096)
		(width 0.114)
		(layer "In7.Cu")
		(net 388)
	)
	(arc
		(start 172.523001 126.486096)
		(mid 172.660221 126.817376)
		(end 172.991501 126.954596)
		(width 0.114)
		(layer "In7.Cu")
		(net 388)
	)
	(arc
		(start 161.616501 118.103001)
		(mid 161.285221 118.240221)
		(end 161.148001 118.571501)
		(width 0.114)
		(layer "In7.Cu")
		(net 388)
	)
	(arc
		(start 161.148001 119.871501)
		(mid 161.285221 120.202781)
		(end 161.616501 120.340001)
		(width 0.114)
		(layer "In7.Cu")
		(net 388)
	)
	(arc
		(start 167.323001 126.486096)
		(mid 167.460221 126.817376)
		(end 167.791501 126.954596)
		(width 0.114)
		(layer "In7.Cu")
		(net 388)
	)
	(arc
		(start 161.250561 115.715348)
		(mid 161.170015 115.909802)
		(end 161.25056 116.104257)
		(width 0.114)
		(layer "In7.Cu")
		(net 388)
	)
	(arc
		(start 169.560001 126.010001)
		(mid 169.613161 125.881661)
		(end 169.741501 125.828501)
		(width 0.114)
		(layer "In7.Cu")
		(net 388)
	)
	(arc
		(start 161.616501 119.403001)
		(mid 161.285221 119.540221)
		(end 161.148001 119.871501)
		(width 0.114)
		(layer "In7.Cu")
		(net 388)
	)
	(arc
		(start 171.691501 126.954596)
		(mid 172.022781 126.817376)
		(end 172.160001 126.486096)
		(width 0.114)
		(layer "In7.Cu")
		(net 388)
	)
	(arc
		(start 161.337031 115.239971)
		(mid 161.417576 115.434426)
		(end 161.33703 115.62888)
		(width 0.114)
		(layer "In7.Cu")
		(net 388)
	)
	(arc
		(start 162.310001 120.340001)
		(mid 162.438341 120.393161)
		(end 162.491501 120.521501)
		(width 0.114)
		(layer "In7.Cu")
		(net 388)
	)
	(arc
		(start 171.041501 125.828501)
		(mid 171.169841 125.881661)
		(end 171.223001 126.010001)
		(width 0.114)
		(layer "In7.Cu")
		(net 388)
	)
	(arc
		(start 171.223001 126.486096)
		(mid 171.360221 126.817376)
		(end 171.691501 126.954596)
		(width 0.114)
		(layer "In7.Cu")
		(net 388)
	)
	(arc
		(start 168.260001 126.010001)
		(mid 168.313161 125.881661)
		(end 168.441501 125.828501)
		(width 0.114)
		(layer "In7.Cu")
		(net 388)
	)
	(arc
		(start 170.860001 126.010001)
		(mid 170.913161 125.881661)
		(end 171.041501 125.828501)
		(width 0.114)
		(layer "In7.Cu")
		(net 388)
	)
	(arc
		(start 165.841501 125.828501)
		(mid 165.969841 125.881661)
		(end 166.023001 126.010001)
		(width 0.114)
		(layer "In7.Cu")
		(net 388)
	)
	(arc
		(start 161.198001 121.171501)
		(mid 161.335221 121.502781)
		(end 161.666501 121.640001)
		(width 0.114)
		(layer "In7.Cu")
		(net 388)
	)
	(arc
		(start 169.741501 125.828501)
		(mid 169.869841 125.881661)
		(end 169.923001 126.010001)
		(width 0.114)
		(layer "In7.Cu")
		(net 388)
	)
	(arc
		(start 161.725938 116.017787)
		(mid 161.920392 115.937241)
		(end 162.114847 116.017786)
		(width 0.114)
		(layer "In7.Cu")
		(net 388)
	)
	(arc
		(start 172.160001 126.010001)
		(mid 172.213161 125.881661)
		(end 172.341501 125.828501)
		(width 0.114)
		(layer "In7.Cu")
		(net 388)
	)
	(arc
		(start 166.491501 126.954596)
		(mid 166.822781 126.817376)
		(end 166.960001 126.486096)
		(width 0.114)
		(layer "In7.Cu")
		(net 388)
	)
	(arc
		(start 170.391501 126.954596)
		(mid 170.722781 126.817376)
		(end 170.860001 126.486096)
		(width 0.114)
		(layer "In7.Cu")
		(net 388)
	)
	(segment
		(start 243.9 116.4)
		(end 243.115 116.4)
		(width 0.182)
		(layer "F.Cu")
		(net 389)
	)
	(segment
		(start 243.115 116.4)
		(end 242.6 116.915)
		(width 0.182)
		(layer "F.Cu")
		(net 389)
	)
	(segment
		(start 193.5 139.5)
		(end 193 140)
		(width 0.256)
		(layer "F.Cu")
		(net 390)
	)
	(via
		(at 251.075 140.775)
		(size 0.45)
		(drill 0.2)
		(layers "F.Cu" "B.Cu")
		(net 390)
	)
	(via
		(at 193 140)
		(size 0.45)
		(drill 0.2)
		(layers "F.Cu" "B.Cu")
		(net 390)
	)
	(segment
		(start 251.3 139.3)
		(end 250.95 138.95)
		(width 0.184)
		(layer "B.Cu")
		(net 390)
	)
	(segment
		(start 251.3 140.765)
		(end 251.3 139.3)
		(width 0.184)
		(layer "B.Cu")
		(net 390)
	)
	(segment
		(start 251.29 140.775)
		(end 251.3 140.765)
		(width 0.184)
		(layer "B.Cu")
		(net 390)
	)
	(segment
		(start 251.075 140.775)
		(end 251.29 140.775)
		(width 0.184)
		(layer "B.Cu")
		(net 390)
	)
	(segment
		(start 250.95 138.95)
		(end 250.95 138.3)
		(width 0.184)
		(layer "B.Cu")
		(net 390)
	)
	(segment
		(start 193.3 140)
		(end 193 140)
		(width 0.1)
		(layer "In5.Cu")
		(net 390)
	)
	(segment
		(start 251.075 139.05)
		(end 251.85 138.275)
		(width 0.1)
		(layer "In5.Cu")
		(net 390)
	)
	(segment
		(start 250.806809 137.45)
		(end 251.625 137.45)
		(width 0.1)
		(layer "In5.Cu")
		(net 390)
	)
	(segment
		(start 251 130.625)
		(end 250.65 130.975)
		(width 0.1)
		(layer "In5.Cu")
		(net 390)
	)
	(segment
		(start 251.625 136.1)
		(end 250.806809 136.1)
		(width 0.1)
		(layer "In5.Cu")
		(net 390)
	)
	(segment
		(start 199.075 161.95)
		(end 199.075 156.075)
		(width 0.1)
		(layer "In5.Cu")
		(net 390)
	)
	(segment
		(start 250.65 132.25)
		(end 241.698527 141.201473)
		(width 0.1)
		(layer "In5.Cu")
		(net 390)
	)
	(segment
		(start 251.85 135.425)
		(end 251.85 130.925)
		(width 0.1)
		(layer "In5.Cu")
		(net 390)
	)
	(segment
		(start 251.85 138.275)
		(end 251.85 138.125)
		(width 0.1)
		(layer "In5.Cu")
		(net 390)
	)
	(segment
		(start 251.075 140.775)
		(end 251.075 139.05)
		(width 0.1)
		(layer "In5.Cu")
		(net 390)
	)
	(segment
		(start 250.65 130.975)
		(end 250.65 132.25)
		(width 0.1)
		(layer "In5.Cu")
		(net 390)
	)
	(segment
		(start 210.8 162.4)
		(end 199.525 162.4)
		(width 0.1)
		(layer "In5.Cu")
		(net 390)
	)
	(segment
		(start 195.825 146.6)
		(end 197.6 144.825)
		(width 0.1)
		(layer "In5.Cu")
		(net 390)
	)
	(segment
		(start 193.7 140.4)
		(end 193.3 140)
		(width 0.1)
		(layer "In5.Cu")
		(net 390)
	)
	(segment
		(start 199.075 156.075)
		(end 195.825 152.825)
		(width 0.1)
		(layer "In5.Cu")
		(net 390)
	)
	(segment
		(start 250.806809 136.55)
		(end 251.625 136.55)
		(width 0.1)
		(layer "In5.Cu")
		(net 390)
	)
	(segment
		(start 221.3 151.9)
		(end 210.8 162.4)
		(width 0.1)
		(layer "In5.Cu")
		(net 390)
	)
	(segment
		(start 224.5 151.9)
		(end 221.3 151.9)
		(width 0.1)
		(layer "In5.Cu")
		(net 390)
	)
	(segment
		(start 197.213173 140.4)
		(end 193.7 140.4)
		(width 0.1)
		(layer "In5.Cu")
		(net 390)
	)
	(segment
		(start 241.698527 141.201473)
		(end 235.198527 141.201473)
		(width 0.1)
		(layer "In5.Cu")
		(net 390)
	)
	(segment
		(start 251.625 137)
		(end 250.806809 137)
		(width 0.1)
		(layer "In5.Cu")
		(net 390)
	)
	(segment
		(start 250.806809 135.65)
		(end 251.625 135.65)
		(width 0.1)
		(layer "In5.Cu")
		(net 390)
	)
	(segment
		(start 235.198527 141.201473)
		(end 224.5 151.9)
		(width 0.1)
		(layer "In5.Cu")
		(net 390)
	)
	(segment
		(start 195.825 152.825)
		(end 195.825 146.6)
		(width 0.1)
		(layer "In5.Cu")
		(net 390)
	)
	(segment
		(start 197.6 140.786827)
		(end 197.213173 140.4)
		(width 0.1)
		(layer "In5.Cu")
		(net 390)
	)
	(segment
		(start 251.85 130.925)
		(end 251.55 130.625)
		(width 0.1)
		(layer "In5.Cu")
		(net 390)
	)
	(segment
		(start 251.55 130.625)
		(end 251 130.625)
		(width 0.1)
		(layer "In5.Cu")
		(net 390)
	)
	(segment
		(start 251.625 137.9)
		(end 250.806809 137.9)
		(width 0.1)
		(layer "In5.Cu")
		(net 390)
	)
	(segment
		(start 199.525 162.4)
		(end 199.075 161.95)
		(width 0.1)
		(layer "In5.Cu")
		(net 390)
	)
	(segment
		(start 197.6 144.825)
		(end 197.6 140.786827)
		(width 0.1)
		(layer "In5.Cu")
		(net 390)
	)
	(arc
		(start 250.806809 137)
		(mid 250.64771 136.934099)
		(end 250.581809 136.775)
		(width 0.1)
		(layer "In5.Cu")
		(net 390)
	)
	(arc
		(start 251.625 137.45)
		(mid 251.784099 137.384099)
		(end 251.85 137.225)
		(width 0.1)
		(layer "In5.Cu")
		(net 390)
	)
	(arc
		(start 251.85 138.125)
		(mid 251.784099 137.965901)
		(end 251.625 137.9)
		(width 0.1)
		(layer "In5.Cu")
		(net 390)
	)
	(arc
		(start 251.85 136.325)
		(mid 251.784099 136.165901)
		(end 251.625 136.1)
		(width 0.1)
		(layer "In5.Cu")
		(net 390)
	)
	(arc
		(start 251.625 136.55)
		(mid 251.784099 136.484099)
		(end 251.85 136.325)
		(width 0.1)
		(layer "In5.Cu")
		(net 390)
	)
	(arc
		(start 250.581809 135.875)
		(mid 250.64771 135.715901)
		(end 250.806809 135.65)
		(width 0.1)
		(layer "In5.Cu")
		(net 390)
	)
	(arc
		(start 250.806809 137.9)
		(mid 250.64771 137.834099)
		(end 250.581809 137.675)
		(width 0.1)
		(layer "In5.Cu")
		(net 390)
	)
	(arc
		(start 251.625 135.65)
		(mid 251.784099 135.584099)
		(end 251.85 135.425)
		(width 0.1)
		(layer "In5.Cu")
		(net 390)
	)
	(arc
		(start 250.581809 137.675)
		(mid 250.64771 137.515901)
		(end 250.806809 137.45)
		(width 0.1)
		(layer "In5.Cu")
		(net 390)
	)
	(arc
		(start 250.581809 136.775)
		(mid 250.64771 136.615901)
		(end 250.806809 136.55)
		(width 0.1)
		(layer "In5.Cu")
		(net 390)
	)
	(arc
		(start 251.85 137.225)
		(mid 251.784099 137.065901)
		(end 251.625 137)
		(width 0.1)
		(layer "In5.Cu")
		(net 390)
	)
	(arc
		(start 250.806809 136.1)
		(mid 250.64771 136.034099)
		(end 250.581809 135.875)
		(width 0.1)
		(layer "In5.Cu")
		(net 390)
	)
	(segment
		(start 194.5 136.5)
		(end 194 137)
		(width 0.256)
		(layer "F.Cu")
		(net 391)
	)
	(via
		(at 249.95 140.7)
		(size 0.45)
		(drill 0.2)
		(layers "F.Cu" "B.Cu")
		(net 391)
	)
	(via
		(at 194 137)
		(size 0.45)
		(drill 0.2)
		(layers "F.Cu" "B.Cu")
		(net 391)
	)
	(segment
		(start 250.15 138.2)
		(end 250.45 137.9)
		(width 0.184)
		(layer "B.Cu")
		(net 391)
	)
	(segment
		(start 249.95 139)
		(end 250.15 138.8)
		(width 0.184)
		(layer "B.Cu")
		(net 391)
	)
	(segment
		(start 250.45 137.9)
		(end 250.95 137.9)
		(width 0.184)
		(layer "B.Cu")
		(net 391)
	)
	(segment
		(start 250.015 140.765)
		(end 249.95 140.7)
		(width 0.184)
		(layer "B.Cu")
		(net 391)
	)
	(segment
		(start 250.15 138.8)
		(end 250.15 138.2)
		(width 0.184)
		(layer "B.Cu")
		(net 391)
	)
	(segment
		(start 249.95 140.7)
		(end 249.95 139)
		(width 0.184)
		(layer "B.Cu")
		(net 391)
	)
	(segment
		(start 250.3 140.765)
		(end 250.015 140.765)
		(width 0.184)
		(layer "B.Cu")
		(net 391)
	)
	(segment
		(start 241.1 132.725)
		(end 241.1 133.475)
		(width 0.1)
		(layer "In5.Cu")
		(net 391)
	)
	(segment
		(start 241.1 133.475)
		(end 239.875 134.7)
		(width 0.1)
		(layer "In5.Cu")
		(net 391)
	)
	(segment
		(start 249.95 141.55)
		(end 250.675 142.275)
		(width 0.1)
		(layer "In5.Cu")
		(net 391)
	)
	(segment
		(start 220.3 150.4)
		(end 211.425 159.275)
		(width 0.1)
		(layer "In5.Cu")
		(net 391)
	)
	(segment
		(start 223.4 150.4)
		(end 220.3 150.4)
		(width 0.1)
		(layer "In5.Cu")
		(net 391)
	)
	(segment
		(start 207.95 159.1)
		(end 207.95 158.64715)
		(width 0.1)
		(layer "In5.Cu")
		(net 391)
	)
	(segment
		(start 250.675 142.275)
		(end 252.175 142.275)
		(width 0.1)
		(layer "In5.Cu")
		(net 391)
	)
	(segment
		(start 210.05 159.1)
		(end 210.05 158.64715)
		(width 0.1)
		(layer "In5.Cu")
		(net 391)
	)
	(segment
		(start 252.175 142.275)
		(end 252.525 141.925)
		(width 0.1)
		(layer "In5.Cu")
		(net 391)
	)
	(segment
		(start 197.6 139.25)
		(end 197.6 137.7)
		(width 0.1)
		(layer "In5.Cu")
		(net 391)
	)
	(segment
		(start 210.4 158.64715)
		(end 210.4 159.1)
		(width 0.1)
		(layer "In5.Cu")
		(net 391)
	)
	(segment
		(start 208.65 159.1)
		(end 208.65 158.64715)
		(width 0.1)
		(layer "In5.Cu")
		(net 391)
	)
	(segment
		(start 249.95 140.7)
		(end 249.95 141.55)
		(width 0.1)
		(layer "In5.Cu")
		(net 391)
	)
	(segment
		(start 209.35 159.1)
		(end 209.35 158.64715)
		(width 0.1)
		(layer "In5.Cu")
		(net 391)
	)
	(segment
		(start 199.6 139.7)
		(end 199.275 139.375)
		(width 0.1)
		(layer "In5.Cu")
		(net 391)
	)
	(segment
		(start 200.675 157.5)
		(end 200.675 154.275)
		(width 0.1)
		(layer "In5.Cu")
		(net 391)
	)
	(segment
		(start 252.525 130.025)
		(end 251.825 129.325)
		(width 0.1)
		(layer "In5.Cu")
		(net 391)
	)
	(segment
		(start 199.6 145.425)
		(end 199.6 139.7)
		(width 0.1)
		(layer "In5.Cu")
		(net 391)
	)
	(segment
		(start 207.6 158.64715)
		(end 207.6 159.1)
		(width 0.1)
		(layer "In5.Cu")
		(net 391)
	)
	(segment
		(start 210.75 159.1)
		(end 210.75 158.64715)
		(width 0.1)
		(layer "In5.Cu")
		(net 391)
	)
	(segment
		(start 207.25 159.1)
		(end 207.25 158.64715)
		(width 0.1)
		(layer "In5.Cu")
		(net 391)
	)
	(segment
		(start 209 158.64715)
		(end 209 159.1)
		(width 0.1)
		(layer "In5.Cu")
		(net 391)
	)
	(segment
		(start 239.875 134.7)
		(end 239.1 134.7)
		(width 0.1)
		(layer "In5.Cu")
		(net 391)
	)
	(segment
		(start 251.825 129.325)
		(end 244.5 129.325)
		(width 0.1)
		(layer "In5.Cu")
		(net 391)
	)
	(segment
		(start 244.5 129.325)
		(end 241.1 132.725)
		(width 0.1)
		(layer "In5.Cu")
		(net 391)
	)
	(segment
		(start 208.3 158.64715)
		(end 208.3 159.1)
		(width 0.1)
		(layer "In5.Cu")
		(net 391)
	)
	(segment
		(start 199.275 139.375)
		(end 197.725 139.375)
		(width 0.1)
		(layer "In5.Cu")
		(net 391)
	)
	(segment
		(start 206.725 159.275)
		(end 202.45 159.275)
		(width 0.1)
		(layer "In5.Cu")
		(net 391)
	)
	(segment
		(start 197.325 150.925)
		(end 197.325 147.7)
		(width 0.1)
		(layer "In5.Cu")
		(net 391)
	)
	(segment
		(start 252.525 141.925)
		(end 252.525 130.025)
		(width 0.1)
		(layer "In5.Cu")
		(net 391)
	)
	(segment
		(start 197.725 139.375)
		(end 197.6 139.25)
		(width 0.1)
		(layer "In5.Cu")
		(net 391)
	)
	(segment
		(start 197.325 147.7)
		(end 199.6 145.425)
		(width 0.1)
		(layer "In5.Cu")
		(net 391)
	)
	(segment
		(start 202.45 159.275)
		(end 200.675 157.5)
		(width 0.1)
		(layer "In5.Cu")
		(net 391)
	)
	(segment
		(start 194.4 137.4)
		(end 194 137)
		(width 0.1)
		(layer "In5.Cu")
		(net 391)
	)
	(segment
		(start 200.675 154.275)
		(end 197.325 150.925)
		(width 0.1)
		(layer "In5.Cu")
		(net 391)
	)
	(segment
		(start 211.425 159.275)
		(end 210.925 159.275)
		(width 0.1)
		(layer "In5.Cu")
		(net 391)
	)
	(segment
		(start 209.7 158.64715)
		(end 209.7 159.1)
		(width 0.1)
		(layer "In5.Cu")
		(net 391)
	)
	(segment
		(start 197.3 137.4)
		(end 194.4 137.4)
		(width 0.1)
		(layer "In5.Cu")
		(net 391)
	)
	(segment
		(start 239.1 134.7)
		(end 223.4 150.4)
		(width 0.1)
		(layer "In5.Cu")
		(net 391)
	)
	(segment
		(start 197.6 137.7)
		(end 197.3 137.4)
		(width 0.1)
		(layer "In5.Cu")
		(net 391)
	)
	(segment
		(start 206.9 158.64715)
		(end 206.9 159.1)
		(width 0.1)
		(layer "In5.Cu")
		(net 391)
	)
	(arc
		(start 207.425 159.275)
		(mid 207.301256 159.223744)
		(end 207.25 159.1)
		(width 0.1)
		(layer "In5.Cu")
		(net 391)
	)
	(arc
		(start 210.75 158.64715)
		(mid 210.698744 158.523406)
		(end 210.575 158.47215)
		(width 0.1)
		(layer "In5.Cu")
		(net 391)
	)
	(arc
		(start 209 159.1)
		(mid 208.948744 159.223744)
		(end 208.825 159.275)
		(width 0.1)
		(layer "In5.Cu")
		(net 391)
	)
	(arc
		(start 210.4 159.1)
		(mid 210.348744 159.223744)
		(end 210.225 159.275)
		(width 0.1)
		(layer "In5.Cu")
		(net 391)
	)
	(arc
		(start 209.875 158.47215)
		(mid 209.751256 158.523406)
		(end 209.7 158.64715)
		(width 0.1)
		(layer "In5.Cu")
		(net 391)
	)
	(arc
		(start 207.775 158.47215)
		(mid 207.651256 158.523406)
		(end 207.6 158.64715)
		(width 0.1)
		(layer "In5.Cu")
		(net 391)
	)
	(arc
		(start 208.475 158.47215)
		(mid 208.351256 158.523406)
		(end 208.3 158.64715)
		(width 0.1)
		(layer "In5.Cu")
		(net 391)
	)
	(arc
		(start 208.825 159.275)
		(mid 208.701256 159.223744)
		(end 208.65 159.1)
		(width 0.1)
		(layer "In5.Cu")
		(net 391)
	)
	(arc
		(start 207.25 158.64715)
		(mid 207.198744 158.523406)
		(end 207.075 158.47215)
		(width 0.1)
		(layer "In5.Cu")
		(net 391)
	)
	(arc
		(start 210.575 158.47215)
		(mid 210.451256 158.523406)
		(end 210.4 158.64715)
		(width 0.1)
		(layer "In5.Cu")
		(net 391)
	)
	(arc
		(start 209.175 158.47215)
		(mid 209.051256 158.523406)
		(end 209 158.64715)
		(width 0.1)
		(layer "In5.Cu")
		(net 391)
	)
	(arc
		(start 207.075 158.47215)
		(mid 206.951256 158.523406)
		(end 206.9 158.64715)
		(width 0.1)
		(layer "In5.Cu")
		(net 391)
	)
	(arc
		(start 208.65 158.64715)
		(mid 208.598744 158.523406)
		(end 208.475 158.47215)
		(width 0.1)
		(layer "In5.Cu")
		(net 391)
	)
	(arc
		(start 207.6 159.1)
		(mid 207.548744 159.223744)
		(end 207.425 159.275)
		(width 0.1)
		(layer "In5.Cu")
		(net 391)
	)
	(arc
		(start 210.05 158.64715)
		(mid 209.998744 158.523406)
		(end 209.875 158.47215)
		(width 0.1)
		(layer "In5.Cu")
		(net 391)
	)
	(arc
		(start 206.9 159.1)
		(mid 206.848744 159.223744)
		(end 206.725 159.275)
		(width 0.1)
		(layer "In5.Cu")
		(net 391)
	)
	(arc
		(start 210.225 159.275)
		(mid 210.101256 159.223744)
		(end 210.05 159.1)
		(width 0.1)
		(layer "In5.Cu")
		(net 391)
	)
	(arc
		(start 209.35 158.64715)
		(mid 209.298744 158.523406)
		(end 209.175 158.47215)
		(width 0.1)
		(layer "In5.Cu")
		(net 391)
	)
	(arc
		(start 207.95 158.64715)
		(mid 207.898744 158.523406)
		(end 207.775 158.47215)
		(width 0.1)
		(layer "In5.Cu")
		(net 391)
	)
	(arc
		(start 209.7 159.1)
		(mid 209.648744 159.223744)
		(end 209.525 159.275)
		(width 0.1)
		(layer "In5.Cu")
		(net 391)
	)
	(arc
		(start 209.525 159.275)
		(mid 209.401256 159.223744)
		(end 209.35 159.1)
		(width 0.1)
		(layer "In5.Cu")
		(net 391)
	)
	(arc
		(start 210.925 159.275)
		(mid 210.801256 159.223744)
		(end 210.75 159.1)
		(width 0.1)
		(layer "In5.Cu")
		(net 391)
	)
	(arc
		(start 208.125 159.275)
		(mid 208.001256 159.223744)
		(end 207.95 159.1)
		(width 0.1)
		(layer "In5.Cu")
		(net 391)
	)
	(arc
		(start 208.3 159.1)
		(mid 208.248744 159.223744)
		(end 208.125 159.275)
		(width 0.1)
		(layer "In5.Cu")
		(net 391)
	)
	(segment
		(start 160.585002 114.758)
		(end 160.416804 114.758001)
		(width 0.16)
		(layer "F.Cu")
		(net 392)
	)
	(segment
		(start 160.095001 114.255001)
		(end 160.095001 114.436198)
		(width 0.16)
		(layer "F.Cu")
		(net 392)
	)
	(segment
		(start 160.585002 114.758)
		(end 160.730001 114.613001)
		(width 0.16)
		(layer "F.Cu")
		(net 392)
	)
	(segment
		(start 160.095001 114.436198)
		(end 160.416804 114.758001)
		(width 0.16)
		(layer "F.Cu")
		(net 392)
	)
	(segment
		(start 195.5 123.5)
		(end 195 123)
		(width 0.256)
		(layer "F.Cu")
		(net 392)
	)
	(via
		(at 160.730001 114.613001)
		(size 0.45)
		(drill 0.2)
		(layers "F.Cu" "B.Cu")
		(net 392)
	)
	(via
		(at 195 123)
		(size 0.45)
		(drill 0.2)
		(layers "F.Cu" "B.Cu")
		(net 392)
	)
	(segment
		(start 166.673001 126.486096)
		(end 166.673001 126.010001)
		(width 0.114)
		(layer "In7.Cu")
		(net 392)
	)
	(segment
		(start 174.941501 125.541501)
		(end 181.460561 125.541501)
		(width 0.114)
		(layer "In7.Cu")
		(net 392)
	)
	(segment
		(start 161.666501 121.353001)
		(end 162.310001 121.353001)
		(width 0.114)
		(layer "In7.Cu")
		(net 392)
	)
	(segment
		(start 160.730001 114.613001)
		(end 160.863501 114.746501)
		(width 0.114)
		(layer "In7.Cu")
		(net 392)
	)
	(segment
		(start 183.492501 124.900001)
		(end 183.442001 124.849501)
		(width 0.1)
		(layer "In7.Cu")
		(net 392)
	)
	(segment
		(start 162.778501 121.821501)
		(end 162.778501 124.355561)
		(width 0.114)
		(layer "In7.Cu")
		(net 392)
	)
	(segment
		(start 168.910001 126.010001)
		(end 168.910001 126.486096)
		(width 0.114)
		(layer "In7.Cu")
		(net 392)
	)
	(segment
		(start 193.706423 125.405001)
		(end 193.201423 124.900001)
		(width 0.1)
		(layer "In7.Cu")
		(net 392)
	)
	(segment
		(start 195.400001 125.188579)
		(end 195.183579 125.405001)
		(width 0.1)
		(layer "In7.Cu")
		(net 392)
	)
	(segment
		(start 162.310001 118.390001)
		(end 161.616501 118.390001)
		(width 0.114)
		(layer "In7.Cu")
		(net 392)
	)
	(segment
		(start 163.964441 125.541501)
		(end 165.841501 125.541501)
		(width 0.114)
		(layer "In7.Cu")
		(net 392)
	)
	(segment
		(start 193.201423 124.900001)
		(end 183.492501 124.900001)
		(width 0.1)
		(layer "In7.Cu")
		(net 392)
	)
	(segment
		(start 195.183579 125.405001)
		(end 193.706423 125.405001)
		(width 0.1)
		(layer "In7.Cu")
		(net 392)
	)
	(segment
		(start 161.616501 118.753001)
		(end 162.310001 118.753001)
		(width 0.114)
		(layer "In7.Cu")
		(net 392)
	)
	(segment
		(start 172.810001 126.010001)
		(end 172.810001 126.486096)
		(width 0.114)
		(layer "In7.Cu")
		(net 392)
	)
	(segment
		(start 171.873001 126.486096)
		(end 171.873001 126.010001)
		(width 0.114)
		(layer "In7.Cu")
		(net 392)
	)
	(segment
		(start 173.173001 126.486096)
		(end 173.173001 126.010001)
		(width 0.114)
		(layer "In7.Cu")
		(net 392)
	)
	(segment
		(start 174.473001 126.486096)
		(end 174.473001 126.010001)
		(width 0.114)
		(layer "In7.Cu")
		(net 392)
	)
	(segment
		(start 182.152561 124.849501)
		(end 183.442001 124.849501)
		(width 0.114)
		(layer "In7.Cu")
		(net 392)
	)
	(segment
		(start 161.249441 114.746501)
		(end 162.778501 116.275561)
		(width 0.114)
		(layer "In7.Cu")
		(net 392)
	)
	(segment
		(start 181.460561 125.541501)
		(end 182.152561 124.849501)
		(width 0.114)
		(layer "In7.Cu")
		(net 392)
	)
	(segment
		(start 171.510001 126.010001)
		(end 171.510001 126.486096)
		(width 0.114)
		(layer "In7.Cu")
		(net 392)
	)
	(segment
		(start 195.000001 123.000001)
		(end 195.400001 123.400001)
		(width 0.1)
		(layer "In7.Cu")
		(net 392)
	)
	(segment
		(start 161.616501 120.053001)
		(end 162.310001 120.053001)
		(width 0.114)
		(layer "In7.Cu")
		(net 392)
	)
	(segment
		(start 162.310001 120.990001)
		(end 161.666501 120.990001)
		(width 0.114)
		(layer "In7.Cu")
		(net 392)
	)
	(segment
		(start 167.973001 126.486096)
		(end 167.973001 126.010001)
		(width 0.114)
		(layer "In7.Cu")
		(net 392)
	)
	(segment
		(start 170.210001 126.010001)
		(end 170.210001 126.486096)
		(width 0.114)
		(layer "In7.Cu")
		(net 392)
	)
	(segment
		(start 174.110001 126.010001)
		(end 174.110001 126.486096)
		(width 0.114)
		(layer "In7.Cu")
		(net 392)
	)
	(segment
		(start 162.778501 116.275561)
		(end 162.778501 117.921501)
		(width 0.114)
		(layer "In7.Cu")
		(net 392)
	)
	(segment
		(start 195.400001 123.400001)
		(end 195.400001 125.188579)
		(width 0.1)
		(layer "In7.Cu")
		(net 392)
	)
	(segment
		(start 162.310001 119.690001)
		(end 161.616501 119.690001)
		(width 0.114)
		(layer "In7.Cu")
		(net 392)
	)
	(segment
		(start 166.310001 126.010001)
		(end 166.310001 126.486096)
		(width 0.114)
		(layer "In7.Cu")
		(net 392)
	)
	(segment
		(start 160.863501 114.746501)
		(end 161.249441 114.746501)
		(width 0.114)
		(layer "In7.Cu")
		(net 392)
	)
	(segment
		(start 170.573001 126.486096)
		(end 170.573001 126.010001)
		(width 0.114)
		(layer "In7.Cu")
		(net 392)
	)
	(segment
		(start 162.778501 124.355561)
		(end 163.964441 125.541501)
		(width 0.114)
		(layer "In7.Cu")
		(net 392)
	)
	(segment
		(start 167.610001 126.010001)
		(end 167.610001 126.486096)
		(width 0.114)
		(layer "In7.Cu")
		(net 392)
	)
	(segment
		(start 169.273001 126.486096)
		(end 169.273001 126.010001)
		(width 0.114)
		(layer "In7.Cu")
		(net 392)
	)
	(arc
		(start 161.666501 120.990001)
		(mid 161.538161 121.043161)
		(end 161.485001 121.171501)
		(width 0.114)
		(layer "In7.Cu")
		(net 392)
	)
	(arc
		(start 174.291501 126.667596)
		(mid 174.419841 126.614436)
		(end 174.473001 126.486096)
		(width 0.114)
		(layer "In7.Cu")
		(net 392)
	)
	(arc
		(start 168.910001 126.486096)
		(mid 168.963161 126.614436)
		(end 169.091501 126.667596)
		(width 0.114)
		(layer "In7.Cu")
		(net 392)
	)
	(arc
		(start 170.573001 126.010001)
		(mid 170.710221 125.678721)
		(end 171.041501 125.541501)
		(width 0.114)
		(layer "In7.Cu")
		(net 392)
	)
	(arc
		(start 162.778501 117.921501)
		(mid 162.641281 118.252781)
		(end 162.310001 118.390001)
		(width 0.114)
		(layer "In7.Cu")
		(net 392)
	)
	(arc
		(start 169.741501 125.541501)
		(mid 170.072781 125.678721)
		(end 170.210001 126.010001)
		(width 0.114)
		(layer "In7.Cu")
		(net 392)
	)
	(arc
		(start 161.485001 121.171501)
		(mid 161.538161 121.299841)
		(end 161.666501 121.353001)
		(width 0.114)
		(layer "In7.Cu")
		(net 392)
	)
	(arc
		(start 171.510001 126.486096)
		(mid 171.563161 126.614436)
		(end 171.691501 126.667596)
		(width 0.114)
		(layer "In7.Cu")
		(net 392)
	)
	(arc
		(start 169.273001 126.010001)
		(mid 169.410221 125.678721)
		(end 169.741501 125.541501)
		(width 0.114)
		(layer "In7.Cu")
		(net 392)
	)
	(arc
		(start 173.173001 126.010001)
		(mid 173.310221 125.678721)
		(end 173.641501 125.541501)
		(width 0.114)
		(layer "In7.Cu")
		(net 392)
	)
	(arc
		(start 174.473001 126.010001)
		(mid 174.610221 125.678721)
		(end 174.941501 125.541501)
		(width 0.114)
		(layer "In7.Cu")
		(net 392)
	)
	(arc
		(start 167.610001 126.486096)
		(mid 167.663161 126.614436)
		(end 167.791501 126.667596)
		(width 0.114)
		(layer "In7.Cu")
		(net 392)
	)
	(arc
		(start 162.778501 120.521501)
		(mid 162.641281 120.852781)
		(end 162.310001 120.990001)
		(width 0.114)
		(layer "In7.Cu")
		(net 392)
	)
	(arc
		(start 172.810001 126.486096)
		(mid 172.863161 126.614436)
		(end 172.991501 126.667596)
		(width 0.114)
		(layer "In7.Cu")
		(net 392)
	)
	(arc
		(start 174.110001 126.486096)
		(mid 174.163161 126.614436)
		(end 174.291501 126.667596)
		(width 0.114)
		(layer "In7.Cu")
		(net 392)
	)
	(arc
		(start 167.141501 125.541501)
		(mid 167.472781 125.678721)
		(end 167.610001 126.010001)
		(width 0.114)
		(layer "In7.Cu")
		(net 392)
	)
	(arc
		(start 169.091501 126.667596)
		(mid 169.219841 126.614436)
		(end 169.273001 126.486096)
		(width 0.114)
		(layer "In7.Cu")
		(net 392)
	)
	(arc
		(start 166.673001 126.010001)
		(mid 166.810221 125.678721)
		(end 167.141501 125.541501)
		(width 0.114)
		(layer "In7.Cu")
		(net 392)
	)
	(arc
		(start 171.691501 126.667596)
		(mid 171.819841 126.614436)
		(end 171.873001 126.486096)
		(width 0.114)
		(layer "In7.Cu")
		(net 392)
	)
	(arc
		(start 162.310001 118.753001)
		(mid 162.641281 118.890221)
		(end 162.778501 119.221501)
		(width 0.114)
		(layer "In7.Cu")
		(net 392)
	)
	(arc
		(start 162.310001 121.353001)
		(mid 162.641281 121.490221)
		(end 162.778501 121.821501)
		(width 0.114)
		(layer "In7.Cu")
		(net 392)
	)
	(arc
		(start 173.641501 125.541501)
		(mid 173.972781 125.678721)
		(end 174.110001 126.010001)
		(width 0.114)
		(layer "In7.Cu")
		(net 392)
	)
	(arc
		(start 162.778501 119.221501)
		(mid 162.641281 119.552781)
		(end 162.310001 119.690001)
		(width 0.114)
		(layer "In7.Cu")
		(net 392)
	)
	(arc
		(start 168.441501 125.541501)
		(mid 168.772781 125.678721)
		(end 168.910001 126.010001)
		(width 0.114)
		(layer "In7.Cu")
		(net 392)
	)
	(arc
		(start 165.841501 125.541501)
		(mid 166.172781 125.678721)
		(end 166.310001 126.010001)
		(width 0.114)
		(layer "In7.Cu")
		(net 392)
	)
	(arc
		(start 172.991501 126.667596)
		(mid 173.119841 126.614436)
		(end 173.173001 126.486096)
		(width 0.114)
		(layer "In7.Cu")
		(net 392)
	)
	(arc
		(start 167.973001 126.010001)
		(mid 168.110221 125.678721)
		(end 168.441501 125.541501)
		(width 0.114)
		(layer "In7.Cu")
		(net 392)
	)
	(arc
		(start 170.210001 126.486096)
		(mid 170.263161 126.614436)
		(end 170.391501 126.667596)
		(width 0.114)
		(layer "In7.Cu")
		(net 392)
	)
	(arc
		(start 167.791501 126.667596)
		(mid 167.919841 126.614436)
		(end 167.973001 126.486096)
		(width 0.114)
		(layer "In7.Cu")
		(net 392)
	)
	(arc
		(start 171.873001 126.010001)
		(mid 172.010221 125.678721)
		(end 172.341501 125.541501)
		(width 0.114)
		(layer "In7.Cu")
		(net 392)
	)
	(arc
		(start 162.310001 120.053001)
		(mid 162.641281 120.190221)
		(end 162.778501 120.521501)
		(width 0.114)
		(layer "In7.Cu")
		(net 392)
	)
	(arc
		(start 161.616501 118.390001)
		(mid 161.488161 118.443161)
		(end 161.435001 118.571501)
		(width 0.114)
		(layer "In7.Cu")
		(net 392)
	)
	(arc
		(start 161.435001 118.571501)
		(mid 161.488161 118.699841)
		(end 161.616501 118.753001)
		(width 0.114)
		(layer "In7.Cu")
		(net 392)
	)
	(arc
		(start 166.310001 126.486096)
		(mid 166.363161 126.614436)
		(end 166.491501 126.667596)
		(width 0.114)
		(layer "In7.Cu")
		(net 392)
	)
	(arc
		(start 171.041501 125.541501)
		(mid 171.372781 125.678721)
		(end 171.510001 126.010001)
		(width 0.114)
		(layer "In7.Cu")
		(net 392)
	)
	(arc
		(start 161.616501 119.690001)
		(mid 161.488161 119.743161)
		(end 161.435001 119.871501)
		(width 0.114)
		(layer "In7.Cu")
		(net 392)
	)
	(arc
		(start 161.435001 119.871501)
		(mid 161.488161 119.999841)
		(end 161.616501 120.053001)
		(width 0.114)
		(layer "In7.Cu")
		(net 392)
	)
	(arc
		(start 170.391501 126.667596)
		(mid 170.519841 126.614436)
		(end 170.573001 126.486096)
		(width 0.114)
		(layer "In7.Cu")
		(net 392)
	)
	(arc
		(start 172.341501 125.541501)
		(mid 172.672781 125.678721)
		(end 172.810001 126.010001)
		(width 0.114)
		(layer "In7.Cu")
		(net 392)
	)
	(arc
		(start 166.491501 126.667596)
		(mid 166.619841 126.614436)
		(end 166.673001 126.486096)
		(width 0.114)
		(layer "In7.Cu")
		(net 392)
	)
	(segment
		(start 194.012356 137.987644)
		(end 194.012356 138.000112)
		(width 0.256)
		(layer "F.Cu")
		(net 393)
	)
	(segment
		(start 194.5 137.5)
		(end 194.012356 137.987644)
		(width 0.256)
		(layer "F.Cu")
		(net 393)
	)
	(via
		(at 194.012356 138.000112)
		(size 0.45)
		(drill 0.2)
		(layers "F.Cu" "B.Cu")
		(net 393)
	)
	(via
		(at 249.275 140.625)
		(size 0.45)
		(drill 0.2)
		(layers "F.Cu" "B.Cu")
		(net 393)
	)
	(segment
		(start 249.3 140.765)
		(end 249.3 140.65)
		(width 0.184)
		(layer "B.Cu")
		(net 393)
	)
	(segment
		(start 250.05 137.5)
		(end 250.95 137.5)
		(width 0.184)
		(layer "B.Cu")
		(net 393)
	)
	(segment
		(start 249.3 140.65)
		(end 249.275 140.625)
		(width 0.184)
		(layer "B.Cu")
		(net 393)
	)
	(segment
		(start 249.275 138.275)
		(end 250.05 137.5)
		(width 0.184)
		(layer "B.Cu")
		(net 393)
	)
	(segment
		(start 249.275 140.625)
		(end 249.275 138.275)
		(width 0.184)
		(layer "B.Cu")
		(net 393)
	)
	(segment
		(start 198.4 140.4)
		(end 198.6 140.6)
		(width 0.1)
		(layer "In5.Cu")
		(net 393)
	)
	(segment
		(start 239.5 135.3)
		(end 240.3 135.3)
		(width 0.1)
		(layer "In5.Cu")
		(net 393)
	)
	(segment
		(start 240.3 135.3)
		(end 242.15 133.45)
		(width 0.1)
		(layer "In5.Cu")
		(net 393)
	)
	(segment
		(start 197.4 140)
		(end 197.8 140.4)
		(width 0.1)
		(layer "In5.Cu")
		(net 393)
	)
	(segment
		(start 251.375 141.15)
		(end 250.775 141.15)
		(width 0.1)
		(layer "In5.Cu")
		(net 393)
	)
	(segment
		(start 198.6 140.6)
		(end 198.6 145.55)
		(width 0.1)
		(layer "In5.Cu")
		(net 393)
	)
	(segment
		(start 195.925 138.538902)
		(end 195.925 139.425)
		(width 0.1)
		(layer "In5.Cu")
		(net 393)
	)
	(segment
		(start 197.8 140.4)
		(end 198.4 140.4)
		(width 0.1)
		(layer "In5.Cu")
		(net 393)
	)
	(segment
		(start 250.125 140.125)
		(end 249.775 140.125)
		(width 0.1)
		(layer "In5.Cu")
		(net 393)
	)
	(segment
		(start 195.225 138.588902)
		(end 195.225 139.425)
		(width 0.1)
		(layer "In5.Cu")
		(net 393)
	)
	(segment
		(start 243.95 133.45)
		(end 245.375 132.025)
		(width 0.1)
		(layer "In5.Cu")
		(net 393)
	)
	(segment
		(start 242.15 133.45)
		(end 243.95 133.45)
		(width 0.1)
		(layer "In5.Cu")
		(net 393)
	)
	(segment
		(start 250.5 140.875)
		(end 250.5 140.5)
		(width 0.1)
		(layer "In5.Cu")
		(net 393)
	)
	(segment
		(start 200.025 160.5)
		(end 200.325 160.8)
		(width 0.1)
		(layer "In5.Cu")
		(net 393)
	)
	(segment
		(start 252.2 138.65)
		(end 251.575 139.275)
		(width 0.1)
		(layer "In5.Cu")
		(net 393)
	)
	(segment
		(start 200.025 155.7)
		(end 200.025 160.5)
		(width 0.1)
		(layer "In5.Cu")
		(net 393)
	)
	(segment
		(start 198.6 145.55)
		(end 196.725 147.425)
		(width 0.1)
		(layer "In5.Cu")
		(net 393)
	)
	(segment
		(start 249.775 140.125)
		(end 249.275 140.625)
		(width 0.1)
		(layer "In5.Cu")
		(net 393)
	)
	(segment
		(start 250.775 141.15)
		(end 250.5 140.875)
		(width 0.1)
		(layer "In5.Cu")
		(net 393)
	)
	(segment
		(start 197.4 139.8)
		(end 197.4 140)
		(width 0.1)
		(layer "In5.Cu")
		(net 393)
	)
	(segment
		(start 194.375 139.375)
		(end 194.6 139.6)
		(width 0.1)
		(layer "In5.Cu")
		(net 393)
	)
	(segment
		(start 196.725 152.4)
		(end 200.025 155.7)
		(width 0.1)
		(layer "In5.Cu")
		(net 393)
	)
	(segment
		(start 250.5 140.5)
		(end 250.125 140.125)
		(width 0.1)
		(layer "In5.Cu")
		(net 393)
	)
	(segment
		(start 251.575 140.95)
		(end 251.375 141.15)
		(width 0.1)
		(layer "In5.Cu")
		(net 393)
	)
	(segment
		(start 220.725 151)
		(end 223.8 151)
		(width 0.1)
		(layer "In5.Cu")
		(net 393)
	)
	(segment
		(start 251.375 129.725)
		(end 252.2 130.55)
		(width 0.1)
		(layer "In5.Cu")
		(net 393)
	)
	(segment
		(start 245.375 131.15)
		(end 246.8 129.725)
		(width 0.1)
		(layer "In5.Cu")
		(net 393)
	)
	(segment
		(start 194.375 138.362756)
		(end 194.375 139.375)
		(width 0.1)
		(layer "In5.Cu")
		(net 393)
	)
	(segment
		(start 210.925 160.8)
		(end 220.725 151)
		(width 0.1)
		(layer "In5.Cu")
		(net 393)
	)
	(segment
		(start 251.575 139.275)
		(end 251.575 140.95)
		(width 0.1)
		(layer "In5.Cu")
		(net 393)
	)
	(segment
		(start 196.8 139.6)
		(end 197.2 139.6)
		(width 0.1)
		(layer "In5.Cu")
		(net 393)
	)
	(segment
		(start 197.2 139.6)
		(end 197.4 139.8)
		(width 0.1)
		(layer "In5.Cu")
		(net 393)
	)
	(segment
		(start 195.575 139.425)
		(end 195.575 138.538902)
		(width 0.1)
		(layer "In5.Cu")
		(net 393)
	)
	(segment
		(start 194.012356 138.000112)
		(end 194.375 138.362756)
		(width 0.1)
		(layer "In5.Cu")
		(net 393)
	)
	(segment
		(start 194.6 139.6)
		(end 194.7 139.6)
		(width 0.1)
		(layer "In5.Cu")
		(net 393)
	)
	(segment
		(start 223.8 151)
		(end 239.5 135.3)
		(width 0.1)
		(layer "In5.Cu")
		(net 393)
	)
	(segment
		(start 252.2 130.55)
		(end 252.2 138.65)
		(width 0.1)
		(layer "In5.Cu")
		(net 393)
	)
	(segment
		(start 246.8 129.725)
		(end 251.375 129.725)
		(width 0.1)
		(layer "In5.Cu")
		(net 393)
	)
	(segment
		(start 196.625 138.538902)
		(end 196.625 139.425)
		(width 0.1)
		(layer "In5.Cu")
		(net 393)
	)
	(segment
		(start 196.275 139.425)
		(end 196.275 138.538902)
		(width 0.1)
		(layer "In5.Cu")
		(net 393)
	)
	(segment
		(start 200.325 160.8)
		(end 210.925 160.8)
		(width 0.1)
		(layer "In5.Cu")
		(net 393)
	)
	(segment
		(start 196.725 147.425)
		(end 196.725 152.4)
		(width 0.1)
		(layer "In5.Cu")
		(net 393)
	)
	(segment
		(start 194.875 139.425)
		(end 194.875 138.588902)
		(width 0.1)
		(layer "In5.Cu")
		(net 393)
	)
	(segment
		(start 245.375 132.025)
		(end 245.375 131.15)
		(width 0.1)
		(layer "In5.Cu")
		(net 393)
	)
	(arc
		(start 196.1 139.6)
		(mid 196.223744 139.548744)
		(end 196.275 139.425)
		(width 0.1)
		(layer "In5.Cu")
		(net 393)
	)
	(arc
		(start 195.225 139.425)
		(mid 195.276256 139.548744)
		(end 195.4 139.6)
		(width 0.1)
		(layer "In5.Cu")
		(net 393)
	)
	(arc
		(start 195.925 139.425)
		(mid 195.976256 139.548744)
		(end 196.1 139.6)
		(width 0.1)
		(layer "In5.Cu")
		(net 393)
	)
	(arc
		(start 194.7 139.6)
		(mid 194.823744 139.548744)
		(end 194.875 139.425)
		(width 0.1)
		(layer "In5.Cu")
		(net 393)
	)
	(arc
		(start 195.05 138.413902)
		(mid 195.173744 138.465158)
		(end 195.225 138.588902)
		(width 0.1)
		(layer "In5.Cu")
		(net 393)
	)
	(arc
		(start 196.275 138.538902)
		(mid 196.326256 138.415158)
		(end 196.45 138.363902)
		(width 0.1)
		(layer "In5.Cu")
		(net 393)
	)
	(arc
		(start 195.75 138.363902)
		(mid 195.873744 138.415158)
		(end 195.925 138.538902)
		(width 0.1)
		(layer "In5.Cu")
		(net 393)
	)
	(arc
		(start 195.575 138.538902)
		(mid 195.626256 138.415158)
		(end 195.75 138.363902)
		(width 0.1)
		(layer "In5.Cu")
		(net 393)
	)
	(arc
		(start 194.875 138.588902)
		(mid 194.926256 138.465158)
		(end 195.05 138.413902)
		(width 0.1)
		(layer "In5.Cu")
		(net 393)
	)
	(arc
		(start 195.4 139.6)
		(mid 195.523744 139.548744)
		(end 195.575 139.425)
		(width 0.1)
		(layer "In5.Cu")
		(net 393)
	)
	(arc
		(start 196.45 138.363902)
		(mid 196.573744 138.415158)
		(end 196.625 138.538902)
		(width 0.1)
		(layer "In5.Cu")
		(net 393)
	)
	(arc
		(start 196.625 139.425)
		(mid 196.676256 139.548744)
		(end 196.8 139.6)
		(width 0.1)
		(layer "In5.Cu")
		(net 393)
	)
	(segment
		(start 195.5 137.5)
		(end 195 138)
		(width 0.256)
		(layer "F.Cu")
		(net 394)
	)
	(via
		(at 195 138)
		(size 0.45)
		(drill 0.2)
		(layers "F.Cu" "B.Cu")
		(net 394)
	)
	(via
		(at 244.275 131.575)
		(size 0.45)
		(drill 0.2)
		(layers "F.Cu" "B.Cu")
		(net 394)
	)
	(segment
		(start 244.275 130.625)
		(end 244.315 130.585)
		(width 0.184)
		(layer "B.Cu")
		(net 394)
	)
	(segment
		(start 244.315 130.585)
		(end 245 130.585)
		(width 0.184)
		(layer "B.Cu")
		(net 394)
	)
	(segment
		(start 244.275 131.575)
		(end 244.275 130.625)
		(width 0.184)
		(layer "B.Cu")
		(net 394)
	)
	(segment
		(start 244.275 132.775)
		(end 245.4 133.9)
		(width 0.184)
		(layer "B.Cu")
		(net 394)
	)
	(segment
		(start 245.4 133.9)
		(end 250.95 133.9)
		(width 0.184)
		(layer "B.Cu")
		(net 394)
	)
	(segment
		(start 244.275 131.575)
		(end 244.275 132.775)
		(width 0.184)
		(layer "B.Cu")
		(net 394)
	)
	(segment
		(start 197.025 147.575)
		(end 197.025 152.275)
		(width 0.1)
		(layer "In5.Cu")
		(net 394)
	)
	(segment
		(start 206.275 160.375)
		(end 206.275 159.725)
		(width 0.1)
		(layer "In5.Cu")
		(net 394)
	)
	(segment
		(start 211.4 159.55)
		(end 211.65 159.55)
		(width 0.1)
		(layer "In5.Cu")
		(net 394)
	)
	(segment
		(start 208.025 159.725)
		(end 208.025 160.375)
		(width 0.1)
		(layer "In5.Cu")
		(net 394)
	)
	(segment
		(start 211.35 159.55)
		(end 211.4 159.55)
		(width 0.1)
		(layer "In5.Cu")
		(net 394)
	)
	(segment
		(start 207.675 160.375)
		(end 207.675 159.725)
		(width 0.1)
		(layer "In5.Cu")
		(net 394)
	)
	(segment
		(start 195 138)
		(end 195.4 137.6)
		(width 0.1)
		(layer "In5.Cu")
		(net 394)
	)
	(segment
		(start 195.4 137.6)
		(end 197.2 137.6)
		(width 0.1)
		(layer "In5.Cu")
		(net 394)
	)
	(segment
		(start 223.6 150.7)
		(end 239.3 135)
		(width 0.1)
		(layer "In5.Cu")
		(net 394)
	)
	(segment
		(start 209.075 160.375)
		(end 209.075 159.725)
		(width 0.1)
		(layer "In5.Cu")
		(net 394)
	)
	(segment
		(start 241.55 133.475)
		(end 241.55 132.925)
		(width 0.1)
		(layer "In5.Cu")
		(net 394)
	)
	(segment
		(start 202.775 160.375)
		(end 202.775 159.725)
		(width 0.1)
		(layer "In5.Cu")
		(net 394)
	)
	(segment
		(start 200.35 155.6)
		(end 200.35 159.2)
		(width 0.1)
		(layer "In5.Cu")
		(net 394)
	)
	(segment
		(start 209.425 159.725)
		(end 209.425 160.375)
		(width 0.1)
		(layer "In5.Cu")
		(net 394)
	)
	(segment
		(start 202.425 159.725)
		(end 202.425 160.375)
		(width 0.1)
		(layer "In5.Cu")
		(net 394)
	)
	(segment
		(start 204.525 159.725)
		(end 204.525 160.375)
		(width 0.1)
		(layer "In5.Cu")
		(net 394)
	)
	(segment
		(start 201.375 160.375)
		(end 201.375 159.725)
		(width 0.1)
		(layer "In5.Cu")
		(net 394)
	)
	(segment
		(start 243.275 131.2)
		(end 244.075 131.2)
		(width 0.1)
		(layer "In5.Cu")
		(net 394)
	)
	(segment
		(start 203.825 159.725)
		(end 203.825 160.375)
		(width 0.1)
		(layer "In5.Cu")
		(net 394)
	)
	(segment
		(start 199.2 139.6)
		(end 199.4 139.8)
		(width 0.1)
		(layer "In5.Cu")
		(net 394)
	)
	(segment
		(start 239.3 135)
		(end 240.025 135)
		(width 0.1)
		(layer "In5.Cu")
		(net 394)
	)
	(segment
		(start 199.4 139.8)
		(end 199.4 145.2)
		(width 0.1)
		(layer "In5.Cu")
		(net 394)
	)
	(segment
		(start 210.125 159.725)
		(end 210.125 160.375)
		(width 0.1)
		(layer "In5.Cu")
		(net 394)
	)
	(segment
		(start 211.175 160.175)
		(end 211.175 159.725)
		(width 0.1)
		(layer "In5.Cu")
		(net 394)
	)
	(segment
		(start 199.4 145.2)
		(end 197.025 147.575)
		(width 0.1)
		(layer "In5.Cu")
		(net 394)
	)
	(segment
		(start 210.825 159.725)
		(end 210.825 160.175)
		(width 0.1)
		(layer "In5.Cu")
		(net 394)
	)
	(segment
		(start 202.075 160.375)
		(end 202.075 159.725)
		(width 0.1)
		(layer "In5.Cu")
		(net 394)
	)
	(segment
		(start 200.35 159.2)
		(end 200.7 159.55)
		(width 0.1)
		(layer "In5.Cu")
		(net 394)
	)
	(segment
		(start 241.55 132.925)
		(end 243.275 131.2)
		(width 0.1)
		(layer "In5.Cu")
		(net 394)
	)
	(segment
		(start 206.625 159.725)
		(end 206.625 160.375)
		(width 0.1)
		(layer "In5.Cu")
		(net 394)
	)
	(segment
		(start 208.375 160.375)
		(end 208.375 159.725)
		(width 0.1)
		(layer "In5.Cu")
		(net 394)
	)
	(segment
		(start 211.65 159.55)
		(end 220.5 150.7)
		(width 0.1)
		(layer "In5.Cu")
		(net 394)
	)
	(segment
		(start 240.025 135)
		(end 241.55 133.475)
		(width 0.1)
		(layer "In5.Cu")
		(net 394)
	)
	(segment
		(start 200.7 159.55)
		(end 200.85 159.55)
		(width 0.1)
		(layer "In5.Cu")
		(net 394)
	)
	(segment
		(start 220.5 150.7)
		(end 223.6 150.7)
		(width 0.1)
		(layer "In5.Cu")
		(net 394)
	)
	(segment
		(start 244.275 131.4)
		(end 244.275 131.575)
		(width 0.1)
		(layer "In5.Cu")
		(net 394)
	)
	(segment
		(start 207.325 159.725)
		(end 207.325 160.375)
		(width 0.1)
		(layer "In5.Cu")
		(net 394)
	)
	(segment
		(start 197.4 139.4)
		(end 197.6 139.6)
		(width 0.1)
		(layer "In5.Cu")
		(net 394)
	)
	(segment
		(start 210.475 160.375)
		(end 210.475 159.725)
		(width 0.1)
		(layer "In5.Cu")
		(net 394)
	)
	(segment
		(start 244.075 131.2)
		(end 244.275 131.4)
		(width 0.1)
		(layer "In5.Cu")
		(net 394)
	)
	(segment
		(start 201.025 159.725)
		(end 201.025 160.375)
		(width 0.1)
		(layer "In5.Cu")
		(net 394)
	)
	(segment
		(start 197.4 137.8)
		(end 197.4 139.4)
		(width 0.1)
		(layer "In5.Cu")
		(net 394)
	)
	(segment
		(start 203.475 160.375)
		(end 203.475 159.725)
		(width 0.1)
		(layer "In5.Cu")
		(net 394)
	)
	(segment
		(start 197.6 139.6)
		(end 199.2 139.6)
		(width 0.1)
		(layer "In5.Cu")
		(net 394)
	)
	(segment
		(start 203.125 159.725)
		(end 203.125 160.375)
		(width 0.1)
		(layer "In5.Cu")
		(net 394)
	)
	(segment
		(start 201.725 159.725)
		(end 201.725 160.375)
		(width 0.1)
		(layer "In5.Cu")
		(net 394)
	)
	(segment
		(start 209.775 160.375)
		(end 209.775 159.725)
		(width 0.1)
		(layer "In5.Cu")
		(net 394)
	)
	(segment
		(start 197.025 152.275)
		(end 200.35 155.6)
		(width 0.1)
		(layer "In5.Cu")
		(net 394)
	)
	(segment
		(start 205.575 160.375)
		(end 205.575 159.725)
		(width 0.1)
		(layer "In5.Cu")
		(net 394)
	)
	(segment
		(start 204.175 160.375)
		(end 204.175 159.725)
		(width 0.1)
		(layer "In5.Cu")
		(net 394)
	)
	(segment
		(start 206.975 160.375)
		(end 206.975 159.725)
		(width 0.1)
		(layer "In5.Cu")
		(net 394)
	)
	(segment
		(start 205.225 159.725)
		(end 205.225 160.375)
		(width 0.1)
		(layer "In5.Cu")
		(net 394)
	)
	(segment
		(start 208.725 159.725)
		(end 208.725 160.375)
		(width 0.1)
		(layer "In5.Cu")
		(net 394)
	)
	(segment
		(start 197.2 137.6)
		(end 197.4 137.8)
		(width 0.1)
		(layer "In5.Cu")
		(net 394)
	)
	(segment
		(start 204.875 160.375)
		(end 204.875 159.725)
		(width 0.1)
		(layer "In5.Cu")
		(net 394)
	)
	(segment
		(start 205.925 159.725)
		(end 205.925 160.375)
		(width 0.1)
		(layer "In5.Cu")
		(net 394)
	)
	(arc
		(start 204.525 160.375)
		(mid 204.576256 160.498744)
		(end 204.7 160.55)
		(width 0.1)
		(layer "In5.Cu")
		(net 394)
	)
	(arc
		(start 201.2 160.55)
		(mid 201.323744 160.498744)
		(end 201.375 160.375)
		(width 0.1)
		(layer "In5.Cu")
		(net 394)
	)
	(arc
		(start 202.425 160.375)
		(mid 202.476256 160.498744)
		(end 202.6 160.55)
		(width 0.1)
		(layer "In5.Cu")
		(net 394)
	)
	(arc
		(start 209.25 159.55)
		(mid 209.373744 159.601256)
		(end 209.425 159.725)
		(width 0.1)
		(layer "In5.Cu")
		(net 394)
	)
	(arc
		(start 206.625 160.375)
		(mid 206.676256 160.498744)
		(end 206.8 160.55)
		(width 0.1)
		(layer "In5.Cu")
		(net 394)
	)
	(arc
		(start 201.55 159.55)
		(mid 201.673744 159.601256)
		(end 201.725 159.725)
		(width 0.1)
		(layer "In5.Cu")
		(net 394)
	)
	(arc
		(start 200.85 159.55)
		(mid 200.973744 159.601256)
		(end 201.025 159.725)
		(width 0.1)
		(layer "In5.Cu")
		(net 394)
	)
	(arc
		(start 208.025 160.375)
		(mid 208.076256 160.498744)
		(end 208.2 160.55)
		(width 0.1)
		(layer "In5.Cu")
		(net 394)
	)
	(arc
		(start 209.95 159.55)
		(mid 210.073744 159.601256)
		(end 210.125 159.725)
		(width 0.1)
		(layer "In5.Cu")
		(net 394)
	)
	(arc
		(start 207.5 160.55)
		(mid 207.623744 160.498744)
		(end 207.675 160.375)
		(width 0.1)
		(layer "In5.Cu")
		(net 394)
	)
	(arc
		(start 210.125 160.375)
		(mid 210.176256 160.498744)
		(end 210.3 160.55)
		(width 0.1)
		(layer "In5.Cu")
		(net 394)
	)
	(arc
		(start 201.9 160.55)
		(mid 202.023744 160.498744)
		(end 202.075 160.375)
		(width 0.1)
		(layer "In5.Cu")
		(net 394)
	)
	(arc
		(start 201.725 160.375)
		(mid 201.776256 160.498744)
		(end 201.9 160.55)
		(width 0.1)
		(layer "In5.Cu")
		(net 394)
	)
	(arc
		(start 211.175 159.725)
		(mid 211.226256 159.601256)
		(end 211.35 159.55)
		(width 0.1)
		(layer "In5.Cu")
		(net 394)
	)
	(arc
		(start 206.975 159.725)
		(mid 207.026256 159.601256)
		(end 207.15 159.55)
		(width 0.1)
		(layer "In5.Cu")
		(net 394)
	)
	(arc
		(start 210.475 159.725)
		(mid 210.526256 159.601256)
		(end 210.65 159.55)
		(width 0.1)
		(layer "In5.Cu")
		(net 394)
	)
	(arc
		(start 201.025 160.375)
		(mid 201.076256 160.498744)
		(end 201.2 160.55)
		(width 0.1)
		(layer "In5.Cu")
		(net 394)
	)
	(arc
		(start 210.65 159.55)
		(mid 210.773744 159.601256)
		(end 210.825 159.725)
		(width 0.1)
		(layer "In5.Cu")
		(net 394)
	)
	(arc
		(start 208.9 160.55)
		(mid 209.023744 160.498744)
		(end 209.075 160.375)
		(width 0.1)
		(layer "In5.Cu")
		(net 394)
	)
	(arc
		(start 206.1 160.55)
		(mid 206.223744 160.498744)
		(end 206.275 160.375)
		(width 0.1)
		(layer "In5.Cu")
		(net 394)
	)
	(arc
		(start 208.375 159.725)
		(mid 208.426256 159.601256)
		(end 208.55 159.55)
		(width 0.1)
		(layer "In5.Cu")
		(net 394)
	)
	(arc
		(start 201.375 159.725)
		(mid 201.426256 159.601256)
		(end 201.55 159.55)
		(width 0.1)
		(layer "In5.Cu")
		(net 394)
	)
	(arc
		(start 205.925 160.375)
		(mid 205.976256 160.498744)
		(end 206.1 160.55)
		(width 0.1)
		(layer "In5.Cu")
		(net 394)
	)
	(arc
		(start 203.65 159.55)
		(mid 203.773744 159.601256)
		(end 203.825 159.725)
		(width 0.1)
		(layer "In5.Cu")
		(net 394)
	)
	(arc
		(start 209.6 160.55)
		(mid 209.723744 160.498744)
		(end 209.775 160.375)
		(width 0.1)
		(layer "In5.Cu")
		(net 394)
	)
	(arc
		(start 203.475 159.725)
		(mid 203.526256 159.601256)
		(end 203.65 159.55)
		(width 0.1)
		(layer "In5.Cu")
		(net 394)
	)
	(arc
		(start 208.725 160.375)
		(mid 208.776256 160.498744)
		(end 208.9 160.55)
		(width 0.1)
		(layer "In5.Cu")
		(net 394)
	)
	(arc
		(start 205.75 159.55)
		(mid 205.873744 159.601256)
		(end 205.925 159.725)
		(width 0.1)
		(layer "In5.Cu")
		(net 394)
	)
	(arc
		(start 211 160.35)
		(mid 211.123744 160.298744)
		(end 211.175 160.175)
		(width 0.1)
		(layer "In5.Cu")
		(net 394)
	)
	(arc
		(start 203.3 160.55)
		(mid 203.423744 160.498744)
		(end 203.475 160.375)
		(width 0.1)
		(layer "In5.Cu")
		(net 394)
	)
	(arc
		(start 206.275 159.725)
		(mid 206.326256 159.601256)
		(end 206.45 159.55)
		(width 0.1)
		(layer "In5.Cu")
		(net 394)
	)
	(arc
		(start 202.95 159.55)
		(mid 203.073744 159.601256)
		(end 203.125 159.725)
		(width 0.1)
		(layer "In5.Cu")
		(net 394)
	)
	(arc
		(start 206.8 160.55)
		(mid 206.923744 160.498744)
		(end 206.975 160.375)
		(width 0.1)
		(layer "In5.Cu")
		(net 394)
	)
	(arc
		(start 208.55 159.55)
		(mid 208.673744 159.601256)
		(end 208.725 159.725)
		(width 0.1)
		(layer "In5.Cu")
		(net 394)
	)
	(arc
		(start 210.825 160.175)
		(mid 210.876256 160.298744)
		(end 211 160.35)
		(width 0.1)
		(layer "In5.Cu")
		(net 394)
	)
	(arc
		(start 209.775 159.725)
		(mid 209.826256 159.601256)
		(end 209.95 159.55)
		(width 0.1)
		(layer "In5.Cu")
		(net 394)
	)
	(arc
		(start 210.3 160.55)
		(mid 210.423744 160.498744)
		(end 210.475 160.375)
		(width 0.1)
		(layer "In5.Cu")
		(net 394)
	)
	(arc
		(start 202.075 159.725)
		(mid 202.126256 159.601256)
		(end 202.25 159.55)
		(width 0.1)
		(layer "In5.Cu")
		(net 394)
	)
	(arc
		(start 208.2 160.55)
		(mid 208.323744 160.498744)
		(end 208.375 160.375)
		(width 0.1)
		(layer "In5.Cu")
		(net 394)
	)
	(arc
		(start 207.675 159.725)
		(mid 207.726256 159.601256)
		(end 207.85 159.55)
		(width 0.1)
		(layer "In5.Cu")
		(net 394)
	)
	(arc
		(start 202.775 159.725)
		(mid 202.826256 159.601256)
		(end 202.95 159.55)
		(width 0.1)
		(layer "In5.Cu")
		(net 394)
	)
	(arc
		(start 205.225 160.375)
		(mid 205.276256 160.498744)
		(end 205.4 160.55)
		(width 0.1)
		(layer "In5.Cu")
		(net 394)
	)
	(arc
		(start 205.575 159.725)
		(mid 205.626256 159.601256)
		(end 205.75 159.55)
		(width 0.1)
		(layer "In5.Cu")
		(net 394)
	)
	(arc
		(start 202.25 159.55)
		(mid 202.373744 159.601256)
		(end 202.425 159.725)
		(width 0.1)
		(layer "In5.Cu")
		(net 394)
	)
	(arc
		(start 204.35 159.55)
		(mid 204.473744 159.601256)
		(end 204.525 159.725)
		(width 0.1)
		(layer "In5.Cu")
		(net 394)
	)
	(arc
		(start 207.325 160.375)
		(mid 207.376256 160.498744)
		(end 207.5 160.55)
		(width 0.1)
		(layer "In5.Cu")
		(net 394)
	)
	(arc
		(start 206.45 159.55)
		(mid 206.573744 159.601256)
		(end 206.625 159.725)
		(width 0.1)
		(layer "In5.Cu")
		(net 394)
	)
	(arc
		(start 207.15 159.55)
		(mid 207.273744 159.601256)
		(end 207.325 159.725)
		(width 0.1)
		(layer "In5.Cu")
		(net 394)
	)
	(arc
		(start 204.175 159.725)
		(mid 204.226256 159.601256)
		(end 204.35 159.55)
		(width 0.1)
		(layer "In5.Cu")
		(net 394)
	)
	(arc
		(start 207.85 159.55)
		(mid 207.973744 159.601256)
		(end 208.025 159.725)
		(width 0.1)
		(layer "In5.Cu")
		(net 394)
	)
	(arc
		(start 209.425 160.375)
		(mid 209.476256 160.498744)
		(end 209.6 160.55)
		(width 0.1)
		(layer "In5.Cu")
		(net 394)
	)
	(arc
		(start 204.875 159.725)
		(mid 204.926256 159.601256)
		(end 205.05 159.55)
		(width 0.1)
		(layer "In5.Cu")
		(net 394)
	)
	(arc
		(start 205.05 159.55)
		(mid 205.173744 159.601256)
		(end 205.225 159.725)
		(width 0.1)
		(layer "In5.Cu")
		(net 394)
	)
	(arc
		(start 203.125 160.375)
		(mid 203.176256 160.498744)
		(end 203.3 160.55)
		(width 0.1)
		(layer "In5.Cu")
		(net 394)
	)
	(arc
		(start 204 160.55)
		(mid 204.123744 160.498744)
		(end 204.175 160.375)
		(width 0.1)
		(layer "In5.Cu")
		(net 394)
	)
	(arc
		(start 205.4 160.55)
		(mid 205.523744 160.498744)
		(end 205.575 160.375)
		(width 0.1)
		(layer "In5.Cu")
		(net 394)
	)
	(arc
		(start 209.075 159.725)
		(mid 209.126256 159.601256)
		(end 209.25 159.55)
		(width 0.1)
		(layer "In5.Cu")
		(net 394)
	)
	(arc
		(start 203.825 160.375)
		(mid 203.876256 160.498744)
		(end 204 160.55)
		(width 0.1)
		(layer "In5.Cu")
		(net 394)
	)
	(arc
		(start 204.7 160.55)
		(mid 204.823744 160.498744)
		(end 204.875 160.375)
		(width 0.1)
		(layer "In5.Cu")
		(net 394)
	)
	(arc
		(start 202.6 160.55)
		(mid 202.723744 160.498744)
		(end 202.775 160.375)
		(width 0.1)
		(layer "In5.Cu")
		(net 394)
	)
	(segment
		(start 198.5 144.5)
		(end 198 145)
		(width 0.256)
		(layer "F.Cu")
		(net 395)
	)
	(via
		(at 246.375 131.225)
		(size 0.45)
		(drill 0.2)
		(layers "F.Cu" "B.Cu")
		(net 395)
	)
	(via
		(at 198 145)
		(size 0.45)
		(drill 0.2)
		(layers "F.Cu" "B.Cu")
		(net 395)
	)
	(segment
		(start 246.4 132.2)
		(end 246.4 131.25)
		(width 0.184)
		(layer "B.Cu")
		(net 395)
	)
	(segment
		(start 246.4 131.25)
		(end 246.375 131.225)
		(width 0.184)
		(layer "B.Cu")
		(net 395)
	)
	(segment
		(start 247.3 133.1)
		(end 246.4 132.2)
		(width 0.184)
		(layer "B.Cu")
		(net 395)
	)
	(segment
		(start 246.375 130.61)
		(end 246.35 130.585)
		(width 0.184)
		(layer "B.Cu")
		(net 395)
	)
	(segment
		(start 250.95 133.1)
		(end 247.3 133.1)
		(width 0.184)
		(layer "B.Cu")
		(net 395)
	)
	(segment
		(start 246.375 131.225)
		(end 246.375 130.61)
		(width 0.184)
		(layer "B.Cu")
		(net 395)
	)
	(segment
		(start 246.034923 132.690073)
		(end 246.034923 132.690074)
		(width 0.1)
		(layer "In5.Cu")
		(net 395)
	)
	(segment
		(start 208.5 161.425)
		(end 208.5 161.92409)
		(width 0.1)
		(layer "In5.Cu")
		(net 395)
	)
	(segment
		(start 196.125 146.875)
		(end 196.125 152.675)
		(width 0.1)
		(layer "In5.Cu")
		(net 395)
	)
	(segment
		(start 209.55 161.92409)
		(end 209.55 161.425)
		(width 0.1)
		(layer "In5.Cu")
		(net 395)
	)
	(segment
		(start 200.45 161.92409)
		(end 200.45 161.425)
		(width 0.1)
		(layer "In5.Cu")
		(net 395)
	)
	(segment
		(start 201.85 161.92409)
		(end 201.85 161.425)
		(width 0.1)
		(layer "In5.Cu")
		(net 395)
	)
	(segment
		(start 240.55 136.2)
		(end 242.25 134.5)
		(width 0.1)
		(layer "In5.Cu")
		(net 395)
	)
	(segment
		(start 203.25 161.92409)
		(end 203.25 161.425)
		(width 0.1)
		(layer "In5.Cu")
		(net 395)
	)
	(segment
		(start 204.3 161.425)
		(end 204.3 161.92409)
		(width 0.1)
		(layer "In5.Cu")
		(net 395)
	)
	(segment
		(start 201.5 161.425)
		(end 201.5 161.92409)
		(width 0.1)
		(layer "In5.Cu")
		(net 395)
	)
	(segment
		(start 245.999569 134.139644)
		(end 245.999568 134.139644)
		(width 0.1)
		(layer "In5.Cu")
		(net 395)
	)
	(segment
		(start 245.504593 134.387131)
		(end 245.044973 133.927511)
		(width 0.1)
		(layer "In5.Cu")
		(net 395)
	)
	(segment
		(start 246.375 132.35)
		(end 246.375 131.225)
		(width 0.1)
		(layer "In5.Cu")
		(net 395)
	)
	(segment
		(start 245.504594 134.634619)
		(end 245.504593 134.634619)
		(width 0.1)
		(layer "In5.Cu")
		(net 395)
	)
	(segment
		(start 205 161.425)
		(end 205 161.92409)
		(width 0.1)
		(layer "In5.Cu")
		(net 395)
	)
	(segment
		(start 210.25 161.92409)
		(end 210.25 161.425)
		(width 0.1)
		(layer "In5.Cu")
		(net 395)
	)
	(segment
		(start 200.1 161.425)
		(end 200.1 161.92409)
		(width 0.1)
		(layer "In5.Cu")
		(net 395)
	)
	(segment
		(start 245.539948 133.185049)
		(end 245.53995 133.18505)
		(width 0.1)
		(layer "In5.Cu")
		(net 395)
	)
	(segment
		(start 208.85 161.92409)
		(end 208.85 161.425)
		(width 0.1)
		(layer "In5.Cu")
		(net 395)
	)
	(segment
		(start 203.95 161.92409)
		(end 203.95 161.425)
		(width 0.1)
		(layer "In5.Cu")
		(net 395)
	)
	(segment
		(start 206.05 161.92409)
		(end 206.05 161.425)
		(width 0.1)
		(layer "In5.Cu")
		(net 395)
	)
	(segment
		(start 205.7 161.425)
		(end 205.7 161.92409)
		(width 0.1)
		(layer "In5.Cu")
		(net 395)
	)
	(segment
		(start 200.8 161.425)
		(end 200.8 161.92409)
		(width 0.1)
		(layer "In5.Cu")
		(net 395)
	)
	(segment
		(start 244.797486 134.175)
		(end 244.797487 134.175)
		(width 0.1)
		(layer "In5.Cu")
		(net 395)
	)
	(segment
		(start 198 145)
		(end 196.125 146.875)
		(width 0.1)
		(layer "In5.Cu")
		(net 395)
	)
	(segment
		(start 208.15 161.92409)
		(end 208.15 161.425)
		(width 0.1)
		(layer "In5.Cu")
		(net 395)
	)
	(segment
		(start 206.75 161.92409)
		(end 206.75 161.425)
		(width 0.1)
		(layer "In5.Cu")
		(net 395)
	)
	(segment
		(start 203.6 161.425)
		(end 203.6 161.92409)
		(width 0.1)
		(layer "In5.Cu")
		(net 395)
	)
	(segment
		(start 245.539948 133.185048)
		(end 245.539948 133.185049)
		(width 0.1)
		(layer "In5.Cu")
		(net 395)
	)
	(segment
		(start 207.45 161.92409)
		(end 207.45 161.425)
		(width 0.1)
		(layer "In5.Cu")
		(net 395)
	)
	(segment
		(start 245.044973 133.680024)
		(end 245.044975 133.680025)
		(width 0.1)
		(layer "In5.Cu")
		(net 395)
	)
	(segment
		(start 199.425 160.85)
		(end 199.825 161.25)
		(width 0.1)
		(layer "In5.Cu")
		(net 395)
	)
	(segment
		(start 211.125 161.25)
		(end 211.175 161.25)
		(width 0.1)
		(layer "In5.Cu")
		(net 395)
	)
	(segment
		(start 244.225 134.5)
		(end 244.55 134.175)
		(width 0.1)
		(layer "In5.Cu")
		(net 395)
	)
	(segment
		(start 245.044973 133.680023)
		(end 245.044973 133.680024)
		(width 0.1)
		(layer "In5.Cu")
		(net 395)
	)
	(segment
		(start 239.7 136.2)
		(end 240.55 136.2)
		(width 0.1)
		(layer "In5.Cu")
		(net 395)
	)
	(segment
		(start 245.292461 133.680025)
		(end 245.292462 133.680025)
		(width 0.1)
		(layer "In5.Cu")
		(net 395)
	)
	(segment
		(start 210.95 161.87409)
		(end 210.95 161.425)
		(width 0.1)
		(layer "In5.Cu")
		(net 395)
	)
	(segment
		(start 211.175 161.25)
		(end 211.45 161.25)
		(width 0.1)
		(layer "In5.Cu")
		(net 395)
	)
	(segment
		(start 242.25 134.5)
		(end 244.225 134.5)
		(width 0.1)
		(layer "In5.Cu")
		(net 395)
	)
	(segment
		(start 202.9 161.425)
		(end 202.9 161.92409)
		(width 0.1)
		(layer "In5.Cu")
		(net 395)
	)
	(segment
		(start 204.65 161.92409)
		(end 204.65 161.425)
		(width 0.1)
		(layer "In5.Cu")
		(net 395)
	)
	(segment
		(start 205.35 161.92409)
		(end 205.35 161.425)
		(width 0.1)
		(layer "In5.Cu")
		(net 395)
	)
	(segment
		(start 246.494544 133.644669)
		(end 246.494543 133.644669)
		(width 0.1)
		(layer "In5.Cu")
		(net 395)
	)
	(segment
		(start 224.3 151.6)
		(end 239.7 136.2)
		(width 0.1)
		(layer "In5.Cu")
		(net 395)
	)
	(segment
		(start 207.8 161.425)
		(end 207.8 161.92409)
		(width 0.1)
		(layer "In5.Cu")
		(net 395)
	)
	(segment
		(start 221.1 151.6)
		(end 224.3 151.6)
		(width 0.1)
		(layer "In5.Cu")
		(net 395)
	)
	(segment
		(start 199.825 161.25)
		(end 199.925 161.25)
		(width 0.1)
		(layer "In5.Cu")
		(net 395)
	)
	(segment
		(start 202.2 161.425)
		(end 202.2 161.92409)
		(width 0.1)
		(layer "In5.Cu")
		(net 395)
	)
	(segment
		(start 196.125 152.675)
		(end 199.425 155.975)
		(width 0.1)
		(layer "In5.Cu")
		(net 395)
	)
	(segment
		(start 211.45 161.25)
		(end 221.1 151.6)
		(width 0.1)
		(layer "In5.Cu")
		(net 395)
	)
	(segment
		(start 245.999568 133.892156)
		(end 245.539948 133.432536)
		(width 0.1)
		(layer "In5.Cu")
		(net 395)
	)
	(segment
		(start 246.034923 132.690074)
		(end 246.375 132.35)
		(width 0.1)
		(layer "In5.Cu")
		(net 395)
	)
	(segment
		(start 209.9 161.425)
		(end 209.9 161.92409)
		(width 0.1)
		(layer "In5.Cu")
		(net 395)
	)
	(segment
		(start 210.6 161.425)
		(end 210.6 161.87409)
		(width 0.1)
		(layer "In5.Cu")
		(net 395)
	)
	(segment
		(start 245.787436 133.18505)
		(end 245.787437 133.18505)
		(width 0.1)
		(layer "In5.Cu")
		(net 395)
	)
	(segment
		(start 209.2 161.425)
		(end 209.2 161.92409)
		(width 0.1)
		(layer "In5.Cu")
		(net 395)
	)
	(segment
		(start 199.425 155.975)
		(end 199.425 160.85)
		(width 0.1)
		(layer "In5.Cu")
		(net 395)
	)
	(segment
		(start 207.1 161.425)
		(end 207.1 161.92409)
		(width 0.1)
		(layer "In5.Cu")
		(net 395)
	)
	(segment
		(start 244.797487 134.175)
		(end 245.257106 134.634619)
		(width 0.1)
		(layer "In5.Cu")
		(net 395)
	)
	(segment
		(start 202.55 161.92409)
		(end 202.55 161.425)
		(width 0.1)
		(layer "In5.Cu")
		(net 395)
	)
	(segment
		(start 246.494543 133.397181)
		(end 246.034923 132.937561)
		(width 0.1)
		(layer "In5.Cu")
		(net 395)
	)
	(segment
		(start 206.4 161.425)
		(end 206.4 161.92409)
		(width 0.1)
		(layer "In5.Cu")
		(net 395)
	)
	(segment
		(start 245.292462 133.680025)
		(end 245.752081 134.139644)
		(width 0.1)
		(layer "In5.Cu")
		(net 395)
	)
	(segment
		(start 245.787437 133.18505)
		(end 246.247056 133.644669)
		(width 0.1)
		(layer "In5.Cu")
		(net 395)
	)
	(segment
		(start 201.15 161.92409)
		(end 201.15 161.425)
		(width 0.1)
		(layer "In5.Cu")
		(net 395)
	)
	(arc
		(start 245.752081 134.139644)
		(mid 245.875825 134.1909)
		(end 245.999569 134.139644)
		(width 0.1)
		(layer "In5.Cu")
		(net 395)
	)
	(arc
		(start 201.675 162.09909)
		(mid 201.798744 162.047834)
		(end 201.85 161.92409)
		(width 0.1)
		(layer "In5.Cu")
		(net 395)
	)
	(arc
		(start 245.539948 133.432536)
		(mid 245.488692 133.308792)
		(end 245.539948 133.185048)
		(width 0.1)
		(layer "In5.Cu")
		(net 395)
	)
	(arc
		(start 200.275 162.09909)
		(mid 200.398744 162.047834)
		(end 200.45 161.92409)
		(width 0.1)
		(layer "In5.Cu")
		(net 395)
	)
	(arc
		(start 245.044975 133.680025)
		(mid 245.168718 133.628769)
		(end 245.292461 133.680025)
		(width 0.1)
		(layer "In5.Cu")
		(net 395)
	)
	(arc
		(start 201.85 161.425)
		(mid 201.901256 161.301256)
		(end 202.025 161.25)
		(width 0.1)
		(layer "In5.Cu")
		(net 395)
	)
	(arc
		(start 200.1 161.92409)
		(mid 200.151256 162.047834)
		(end 200.275 162.09909)
		(width 0.1)
		(layer "In5.Cu")
		(net 395)
	)
	(arc
		(start 209.025 161.25)
		(mid 209.148744 161.301256)
		(end 209.2 161.425)
		(width 0.1)
		(layer "In5.Cu")
		(net 395)
	)
	(arc
		(start 245.504593 134.634619)
		(mid 245.555849 134.510875)
		(end 245.504593 134.387131)
		(width 0.1)
		(layer "In5.Cu")
		(net 395)
	)
	(arc
		(start 206.75 161.425)
		(mid 206.801256 161.301256)
		(end 206.925 161.25)
		(width 0.1)
		(layer "In5.Cu")
		(net 395)
	)
	(arc
		(start 207.45 161.425)
		(mid 207.501256 161.301256)
		(end 207.625 161.25)
		(width 0.1)
		(layer "In5.Cu")
		(net 395)
	)
	(arc
		(start 206.05 161.425)
		(mid 206.101256 161.301256)
		(end 206.225 161.25)
		(width 0.1)
		(layer "In5.Cu")
		(net 395)
	)
	(arc
		(start 245.999568 134.139644)
		(mid 246.050824 134.0159)
		(end 245.999568 133.892156)
		(width 0.1)
		(layer "In5.Cu")
		(net 395)
	)
	(arc
		(start 203.6 161.92409)
		(mid 203.651256 162.047834)
		(end 203.775 162.09909)
		(width 0.1)
		(layer "In5.Cu")
		(net 395)
	)
	(arc
		(start 210.6 161.87409)
		(mid 210.651256 161.997834)
		(end 210.775 162.04909)
		(width 0.1)
		(layer "In5.Cu")
		(net 395)
	)
	(arc
		(start 204.475 162.09909)
		(mid 204.598744 162.047834)
		(end 204.65 161.92409)
		(width 0.1)
		(layer "In5.Cu")
		(net 395)
	)
	(arc
		(start 209.725 161.25)
		(mid 209.848744 161.301256)
		(end 209.9 161.425)
		(width 0.1)
		(layer "In5.Cu")
		(net 395)
	)
	(arc
		(start 245.257106 134.634619)
		(mid 245.38085 134.685875)
		(end 245.504594 134.634619)
		(width 0.1)
		(layer "In5.Cu")
		(net 395)
	)
	(arc
		(start 206.575 162.09909)
		(mid 206.698744 162.047834)
		(end 206.75 161.92409)
		(width 0.1)
		(layer "In5.Cu")
		(net 395)
	)
	(arc
		(start 210.25 161.425)
		(mid 210.301256 161.301256)
		(end 210.425 161.25)
		(width 0.1)
		(layer "In5.Cu")
		(net 395)
	)
	(arc
		(start 201.325 161.25)
		(mid 201.448744 161.301256)
		(end 201.5 161.425)
		(width 0.1)
		(layer "In5.Cu")
		(net 395)
	)
	(arc
		(start 203.075 162.09909)
		(mid 203.198744 162.047834)
		(end 203.25 161.92409)
		(width 0.1)
		(layer "In5.Cu")
		(net 395)
	)
	(arc
		(start 207.8 161.92409)
		(mid 207.851256 162.047834)
		(end 207.975 162.09909)
		(width 0.1)
		(layer "In5.Cu")
		(net 395)
	)
	(arc
		(start 203.425 161.25)
		(mid 203.548744 161.301256)
		(end 203.6 161.425)
		(width 0.1)
		(layer "In5.Cu")
		(net 395)
	)
	(arc
		(start 245.53995 133.18505)
		(mid 245.663693 133.133794)
		(end 245.787436 133.18505)
		(width 0.1)
		(layer "In5.Cu")
		(net 395)
	)
	(arc
		(start 200.625 161.25)
		(mid 200.748744 161.301256)
		(end 200.8 161.425)
		(width 0.1)
		(layer "In5.Cu")
		(net 395)
	)
	(arc
		(start 202.025 161.25)
		(mid 202.148744 161.301256)
		(end 202.2 161.425)
		(width 0.1)
		(layer "In5.Cu")
		(net 395)
	)
	(arc
		(start 246.247056 133.644669)
		(mid 246.3708 133.695925)
		(end 246.494544 133.644669)
		(width 0.1)
		(layer "In5.Cu")
		(net 395)
	)
	(arc
		(start 245.044973 133.927511)
		(mid 244.993717 133.803767)
		(end 245.044973 133.680023)
		(width 0.1)
		(layer "In5.Cu")
		(net 395)
	)
	(arc
		(start 204.65 161.425)
		(mid 204.701256 161.301256)
		(end 204.825 161.25)
		(width 0.1)
		(layer "In5.Cu")
		(net 395)
	)
	(arc
		(start 202.725 161.25)
		(mid 202.848744 161.301256)
		(end 202.9 161.425)
		(width 0.1)
		(layer "In5.Cu")
		(net 395)
	)
	(arc
		(start 209.375 162.09909)
		(mid 209.498744 162.047834)
		(end 209.55 161.92409)
		(width 0.1)
		(layer "In5.Cu")
		(net 395)
	)
	(arc
		(start 201.15 161.425)
		(mid 201.201256 161.301256)
		(end 201.325 161.25)
		(width 0.1)
		(layer "In5.Cu")
		(net 395)
	)
	(arc
		(start 205 161.92409)
		(mid 205.051256 162.047834)
		(end 205.175 162.09909)
		(width 0.1)
		(layer "In5.Cu")
		(net 395)
	)
	(arc
		(start 208.325 161.25)
		(mid 208.448744 161.301256)
		(end 208.5 161.425)
		(width 0.1)
		(layer "In5.Cu")
		(net 395)
	)
	(arc
		(start 246.034923 132.937561)
		(mid 245.983667 132.813817)
		(end 246.034923 132.690073)
		(width 0.1)
		(layer "In5.Cu")
		(net 395)
	)
	(arc
		(start 208.15 161.425)
		(mid 208.201256 161.301256)
		(end 208.325 161.25)
		(width 0.1)
		(layer "In5.Cu")
		(net 395)
	)
	(arc
		(start 204.825 161.25)
		(mid 204.948744 161.301256)
		(end 205 161.425)
		(width 0.1)
		(layer "In5.Cu")
		(net 395)
	)
	(arc
		(start 200.975 162.09909)
		(mid 201.098744 162.047834)
		(end 201.15 161.92409)
		(width 0.1)
		(layer "In5.Cu")
		(net 395)
	)
	(arc
		(start 210.075 162.09909)
		(mid 210.198744 162.047834)
		(end 210.25 161.92409)
		(width 0.1)
		(layer "In5.Cu")
		(net 395)
	)
	(arc
		(start 205.525 161.25)
		(mid 205.648744 161.301256)
		(end 205.7 161.425)
		(width 0.1)
		(layer "In5.Cu")
		(net 395)
	)
	(arc
		(start 208.675 162.09909)
		(mid 208.798744 162.047834)
		(end 208.85 161.92409)
		(width 0.1)
		(layer "In5.Cu")
		(net 395)
	)
	(arc
		(start 204.3 161.92409)
		(mid 204.351256 162.047834)
		(end 204.475 162.09909)
		(width 0.1)
		(layer "In5.Cu")
		(net 395)
	)
	(arc
		(start 206.925 161.25)
		(mid 207.048744 161.301256)
		(end 207.1 161.425)
		(width 0.1)
		(layer "In5.Cu")
		(net 395)
	)
	(arc
		(start 203.775 162.09909)
		(mid 203.898744 162.047834)
		(end 203.95 161.92409)
		(width 0.1)
		(layer "In5.Cu")
		(net 395)
	)
	(arc
		(start 205.35 161.425)
		(mid 205.401256 161.301256)
		(end 205.525 161.25)
		(width 0.1)
		(layer "In5.Cu")
		(net 395)
	)
	(arc
		(start 202.375 162.09909)
		(mid 202.498744 162.047834)
		(end 202.55 161.92409)
		(width 0.1)
		(layer "In5.Cu")
		(net 395)
	)
	(arc
		(start 208.85 161.425)
		(mid 208.901256 161.301256)
		(end 209.025 161.25)
		(width 0.1)
		(layer "In5.Cu")
		(net 395)
	)
	(arc
		(start 205.7 161.92409)
		(mid 205.751256 162.047834)
		(end 205.875 162.09909)
		(width 0.1)
		(layer "In5.Cu")
		(net 395)
	)
	(arc
		(start 200.45 161.425)
		(mid 200.501256 161.301256)
		(end 200.625 161.25)
		(width 0.1)
		(layer "In5.Cu")
		(net 395)
	)
	(arc
		(start 207.275 162.09909)
		(mid 207.398744 162.047834)
		(end 207.45 161.92409)
		(width 0.1)
		(layer "In5.Cu")
		(net 395)
	)
	(arc
		(start 209.55 161.425)
		(mid 209.601256 161.301256)
		(end 209.725 161.25)
		(width 0.1)
		(layer "In5.Cu")
		(net 395)
	)
	(arc
		(start 244.55 134.175)
		(mid 244.673743 134.123744)
		(end 244.797486 134.175)
		(width 0.1)
		(layer "In5.Cu")
		(net 395)
	)
	(arc
		(start 200.8 161.92409)
		(mid 200.851256 162.047834)
		(end 200.975 162.09909)
		(width 0.1)
		(layer "In5.Cu")
		(net 395)
	)
	(arc
		(start 199.925 161.25)
		(mid 200.048744 161.301256)
		(end 200.1 161.425)
		(width 0.1)
		(layer "In5.Cu")
		(net 395)
	)
	(arc
		(start 207.975 162.09909)
		(mid 208.098744 162.047834)
		(end 208.15 161.92409)
		(width 0.1)
		(layer "In5.Cu")
		(net 395)
	)
	(arc
		(start 207.625 161.25)
		(mid 207.748744 161.301256)
		(end 207.8 161.425)
		(width 0.1)
		(layer "In5.Cu")
		(net 395)
	)
	(arc
		(start 205.875 162.09909)
		(mid 205.998744 162.047834)
		(end 206.05 161.92409)
		(width 0.1)
		(layer "In5.Cu")
		(net 395)
	)
	(arc
		(start 207.1 161.92409)
		(mid 207.151256 162.047834)
		(end 207.275 162.09909)
		(width 0.1)
		(layer "In5.Cu")
		(net 395)
	)
	(arc
		(start 201.5 161.92409)
		(mid 201.551256 162.047834)
		(end 201.675 162.09909)
		(width 0.1)
		(layer "In5.Cu")
		(net 395)
	)
	(arc
		(start 206.4 161.92409)
		(mid 206.451256 162.047834)
		(end 206.575 162.09909)
		(width 0.1)
		(layer "In5.Cu")
		(net 395)
	)
	(arc
		(start 203.95 161.425)
		(mid 204.001256 161.301256)
		(end 204.125 161.25)
		(width 0.1)
		(layer "In5.Cu")
		(net 395)
	)
	(arc
		(start 206.225 161.25)
		(mid 206.348744 161.301256)
		(end 206.4 161.425)
		(width 0.1)
		(layer "In5.Cu")
		(net 395)
	)
	(arc
		(start 202.2 161.92409)
		(mid 202.251256 162.047834)
		(end 202.375 162.09909)
		(width 0.1)
		(layer "In5.Cu")
		(net 395)
	)
	(arc
		(start 210.95 161.425)
		(mid 211.001256 161.301256)
		(end 211.125 161.25)
		(width 0.1)
		(layer "In5.Cu")
		(net 395)
	)
	(arc
		(start 204.125 161.25)
		(mid 204.248744 161.301256)
		(end 204.3 161.425)
		(width 0.1)
		(layer "In5.Cu")
		(net 395)
	)
	(arc
		(start 202.9 161.92409)
		(mid 202.951256 162.047834)
		(end 203.075 162.09909)
		(width 0.1)
		(layer "In5.Cu")
		(net 395)
	)
	(arc
		(start 203.25 161.425)
		(mid 203.301256 161.301256)
		(end 203.425 161.25)
		(width 0.1)
		(layer "In5.Cu")
		(net 395)
	)
	(arc
		(start 209.2 161.92409)
		(mid 209.251256 162.047834)
		(end 209.375 162.09909)
		(width 0.1)
		(layer "In5.Cu")
		(net 395)
	)
	(arc
		(start 205.175 162.09909)
		(mid 205.298744 162.047834)
		(end 205.35 161.92409)
		(width 0.1)
		(layer "In5.Cu")
		(net 395)
	)
	(arc
		(start 210.425 161.25)
		(mid 210.548744 161.301256)
		(end 210.6 161.425)
		(width 0.1)
		(layer "In5.Cu")
		(net 395)
	)
	(arc
		(start 202.55 161.425)
		(mid 202.601256 161.301256)
		(end 202.725 161.25)
		(width 0.1)
		(layer "In5.Cu")
		(net 395)
	)
	(arc
		(start 210.775 162.04909)
		(mid 210.898744 161.997834)
		(end 210.95 161.87409)
		(width 0.1)
		(layer "In5.Cu")
		(net 395)
	)
	(arc
		(start 246.494543 133.644669)
		(mid 246.545799 133.520925)
		(end 246.494543 133.397181)
		(width 0.1)
		(layer "In5.Cu")
		(net 395)
	)
	(arc
		(start 209.9 161.92409)
		(mid 209.951256 162.047834)
		(end 210.075 162.09909)
		(width 0.1)
		(layer "In5.Cu")
		(net 395)
	)
	(arc
		(start 208.5 161.92409)
		(mid 208.551256 162.047834)
		(end 208.675 162.09909)
		(width 0.1)
		(layer "In5.Cu")
		(net 395)
	)
	(segment
		(start 159.146804 112.482001)
		(end 158.825001 112.803804)
		(width 0.16)
		(layer "F.Cu")
		(net 396)
	)
	(segment
		(start 196.5 122.5)
		(end 196 122)
		(width 0.256)
		(layer "F.Cu")
		(net 396)
	)
	(segment
		(start 159.315002 112.482002)
		(end 159.146804 112.482001)
		(width 0.16)
		(layer "F.Cu")
		(net 396)
	)
	(segment
		(start 159.315002 112.482002)
		(end 159.460001 112.627001)
		(width 0.16)
		(layer "F.Cu")
		(net 396)
	)
	(segment
		(start 158.825001 112.803804)
		(end 158.825001 112.985001)
		(width 0.16)
		(layer "F.Cu")
		(net 396)
	)
	(via
		(at 171.204737 114.780265)
		(size 0.45)
		(drill 0.2)
		(layers "F.Cu" "B.Cu")
		(net 396)
	)
	(via
		(at 159.460001 112.627001)
		(size 0.45)
		(drill 0.2)
		(layers "F.Cu" "B.Cu")
		(net 396)
	)
	(via
		(at 196 122)
		(size 0.45)
		(drill 0.2)
		(layers "F.Cu" "B.Cu")
		(net 396)
	)
	(segment
		(start 169.750561 111.853501)
		(end 160.539441 111.853501)
		(width 0.114)
		(layer "In3.Cu")
		(net 396)
	)
	(segment
		(start 170.156501 113.494441)
		(end 170.156501 112.259441)
		(width 0.114)
		(layer "In3.Cu")
		(net 396)
	)
	(segment
		(start 170.156501 112.259441)
		(end 169.750561 111.853501)
		(width 0.114)
		(layer "In3.Cu")
		(net 396)
	)
	(segment
		(start 171.204737 114.542677)
		(end 170.156501 113.494441)
		(width 0.114)
		(layer "In3.Cu")
		(net 396)
	)
	(segment
		(start 159.899441 112.493501)
		(end 159.593501 112.493501)
		(width 0.114)
		(layer "In3.Cu")
		(net 396)
	)
	(segment
		(start 171.204737 114.780265)
		(end 171.204737 114.542677)
		(width 0.114)
		(layer "In3.Cu")
		(net 396)
	)
	(segment
		(start 160.539441 111.853501)
		(end 159.899441 112.493501)
		(width 0.114)
		(layer "In3.Cu")
		(net 396)
	)
	(segment
		(start 159.593501 112.493501)
		(end 159.460001 112.627001)
		(width 0.114)
		(layer "In3.Cu")
		(net 396)
	)
	(segment
		(start 177.738001 123.325001)
		(end 177.738001 124.051742)
		(width 0.114)
		(layer "In5.Cu")
		(net 396)
	)
	(segment
		(start 175.138001 123.325001)
		(end 175.138001 124.051742)
		(width 0.114)
		(layer "In5.Cu")
		(net 396)
	)
	(segment
		(start 182.575001 124.051742)
		(end 182.575001 123.325001)
		(width 0.114)
		(layer "In5.Cu")
		(net 396)
	)
	(segment
		(start 172.955561 123.143501)
		(end 173.656501 123.143501)
		(width 0.114)
		(layer "In5.Cu")
		(net 396)
	)
	(segment
		(start 180.338001 123.325001)
		(end 180.338001 124.051742)
		(width 0.114)
		(layer "In5.Cu")
		(net 396)
	)
	(segment
		(start 179.975001 124.051742)
		(end 179.975001 123.325001)
		(width 0.114)
		(layer "In5.Cu")
		(net 396)
	)
	(segment
		(start 195.266423 123.600001)
		(end 193.533579 123.600001)
		(width 0.1)
		(layer "In5.Cu")
		(net 396)
	)
	(segment
		(start 176.075001 124.051742)
		(end 176.075001 123.325001)
		(width 0.114)
		(layer "In5.Cu")
		(net 396)
	)
	(segment
		(start 195.600001 123.266423)
		(end 195.266423 123.600001)
		(width 0.1)
		(layer "In5.Cu")
		(net 396)
	)
	(segment
		(start 176.438001 123.325001)
		(end 176.438001 124.051742)
		(width 0.114)
		(layer "In5.Cu")
		(net 396)
	)
	(segment
		(start 196.000001 122.000001)
		(end 195.600001 122.400001)
		(width 0.1)
		(layer "In5.Cu")
		(net 396)
	)
	(segment
		(start 172.556501 118.656501)
		(end 172.556501 118.746629)
		(width 0.114)
		(layer "In5.Cu")
		(net 396)
	)
	(segment
		(start 181.638001 123.325001)
		(end 181.638001 124.051742)
		(width 0.114)
		(layer "In5.Cu")
		(net 396)
	)
	(segment
		(start 171.881501 117.175001)
		(end 172.375001 117.175001)
		(width 0.114)
		(layer "In5.Cu")
		(net 396)
	)
	(segment
		(start 178.675001 124.051742)
		(end 178.675001 123.325001)
		(width 0.114)
		(layer "In5.Cu")
		(net 396)
	)
	(segment
		(start 171.204737 114.780265)
		(end 171.442325 114.780265)
		(width 0.114)
		(layer "In5.Cu")
		(net 396)
	)
	(segment
		(start 193.533579 123.600001)
		(end 193.033579 123.100001)
		(width 0.1)
		(layer "In5.Cu")
		(net 396)
	)
	(segment
		(start 183.448501 123.100001)
		(end 183.405001 123.143501)
		(width 0.1)
		(layer "In5.Cu")
		(net 396)
	)
	(segment
		(start 195.600001 122.400001)
		(end 195.600001 123.266423)
		(width 0.1)
		(layer "In5.Cu")
		(net 396)
	)
	(segment
		(start 177.375001 124.051742)
		(end 177.375001 123.325001)
		(width 0.114)
		(layer "In5.Cu")
		(net 396)
	)
	(segment
		(start 174.775001 124.051742)
		(end 174.775001 123.325001)
		(width 0.114)
		(layer "In5.Cu")
		(net 396)
	)
	(segment
		(start 172.556501 118.746629)
		(end 172.556501 122.744441)
		(width 0.114)
		(layer "In5.Cu")
		(net 396)
	)
	(segment
		(start 172.375001 117.538001)
		(end 171.881501 117.538001)
		(width 0.114)
		(layer "In5.Cu")
		(net 396)
	)
	(segment
		(start 173.838001 123.325001)
		(end 173.838001 124.051742)
		(width 0.114)
		(layer "In5.Cu")
		(net 396)
	)
	(segment
		(start 172.375001 116.238001)
		(end 171.881501 116.238001)
		(width 0.114)
		(layer "In5.Cu")
		(net 396)
	)
	(segment
		(start 179.038001 123.325001)
		(end 179.038001 124.051742)
		(width 0.114)
		(layer "In5.Cu")
		(net 396)
	)
	(segment
		(start 171.881501 118.475001)
		(end 172.375001 118.475001)
		(width 0.114)
		(layer "In5.Cu")
		(net 396)
	)
	(segment
		(start 172.556501 115.894441)
		(end 172.556501 116.056501)
		(width 0.114)
		(layer "In5.Cu")
		(net 396)
	)
	(segment
		(start 171.442325 114.780265)
		(end 172.556501 115.894441)
		(width 0.114)
		(layer "In5.Cu")
		(net 396)
	)
	(segment
		(start 172.556501 122.744441)
		(end 172.955561 123.143501)
		(width 0.114)
		(layer "In5.Cu")
		(net 396)
	)
	(segment
		(start 193.033579 123.100001)
		(end 183.448501 123.100001)
		(width 0.1)
		(layer "In5.Cu")
		(net 396)
	)
	(segment
		(start 181.275001 124.051742)
		(end 181.275001 123.325001)
		(width 0.114)
		(layer "In5.Cu")
		(net 396)
	)
	(segment
		(start 182.756501 123.143501)
		(end 183.405001 123.143501)
		(width 0.114)
		(layer "In5.Cu")
		(net 396)
	)
	(arc
		(start 171.881501 117.538001)
		(mid 171.550221 117.675221)
		(end 171.413001 118.006501)
		(width 0.114)
		(layer "In5.Cu")
		(net 396)
	)
	(arc
		(start 176.075001 123.325001)
		(mid 176.128161 123.196661)
		(end 176.256501 123.143501)
		(width 0.114)
		(layer "In5.Cu")
		(net 396)
	)
	(arc
		(start 176.906501 124.520242)
		(mid 177.237781 124.383022)
		(end 177.375001 124.051742)
		(width 0.114)
		(layer "In5.Cu")
		(net 396)
	)
	(arc
		(start 178.675001 123.325001)
		(mid 178.728161 123.196661)
		(end 178.856501 123.143501)
		(width 0.114)
		(layer "In5.Cu")
		(net 396)
	)
	(arc
		(start 179.038001 124.051742)
		(mid 179.175221 124.383022)
		(end 179.506501 124.520242)
		(width 0.114)
		(layer "In5.Cu")
		(net 396)
	)
	(arc
		(start 181.275001 123.325001)
		(mid 181.328161 123.196661)
		(end 181.456501 123.143501)
		(width 0.114)
		(layer "In5.Cu")
		(net 396)
	)
	(arc
		(start 175.606501 124.520242)
		(mid 175.937781 124.383022)
		(end 176.075001 124.051742)
		(width 0.114)
		(layer "In5.Cu")
		(net 396)
	)
	(arc
		(start 178.856501 123.143501)
		(mid 178.984841 123.196661)
		(end 179.038001 123.325001)
		(width 0.114)
		(layer "In5.Cu")
		(net 396)
	)
	(arc
		(start 182.575001 123.325001)
		(mid 182.628161 123.196661)
		(end 182.756501 123.143501)
		(width 0.114)
		(layer "In5.Cu")
		(net 396)
	)
	(arc
		(start 174.306501 124.520242)
		(mid 174.637781 124.383022)
		(end 174.775001 124.051742)
		(width 0.114)
		(layer "In5.Cu")
		(net 396)
	)
	(arc
		(start 179.975001 123.325001)
		(mid 180.028161 123.196661)
		(end 180.156501 123.143501)
		(width 0.114)
		(layer "In5.Cu")
		(net 396)
	)
	(arc
		(start 174.956501 123.143501)
		(mid 175.084841 123.196661)
		(end 175.138001 123.325001)
		(width 0.114)
		(layer "In5.Cu")
		(net 396)
	)
	(arc
		(start 174.775001 123.325001)
		(mid 174.828161 123.196661)
		(end 174.956501 123.143501)
		(width 0.114)
		(layer "In5.Cu")
		(net 396)
	)
	(arc
		(start 182.106501 124.520242)
		(mid 182.437781 124.383022)
		(end 182.575001 124.051742)
		(width 0.114)
		(layer "In5.Cu")
		(net 396)
	)
	(arc
		(start 177.738001 124.051742)
		(mid 177.875221 124.383022)
		(end 178.206501 124.520242)
		(width 0.114)
		(layer "In5.Cu")
		(net 396)
	)
	(arc
		(start 173.838001 124.051742)
		(mid 173.975221 124.383022)
		(end 174.306501 124.520242)
		(width 0.114)
		(layer "In5.Cu")
		(net 396)
	)
	(arc
		(start 181.638001 124.051742)
		(mid 181.775221 124.383022)
		(end 182.106501 124.520242)
		(width 0.114)
		(layer "In5.Cu")
		(net 396)
	)
	(arc
		(start 180.156501 123.143501)
		(mid 180.284841 123.196661)
		(end 180.338001 123.325001)
		(width 0.114)
		(layer "In5.Cu")
		(net 396)
	)
	(arc
		(start 179.506501 124.520242)
		(mid 179.837781 124.383022)
		(end 179.975001 124.051742)
		(width 0.114)
		(layer "In5.Cu")
		(net 396)
	)
	(arc
		(start 171.413001 116.706501)
		(mid 171.550221 117.037781)
		(end 171.881501 117.175001)
		(width 0.114)
		(layer "In5.Cu")
		(net 396)
	)
	(arc
		(start 181.456501 123.143501)
		(mid 181.584841 123.196661)
		(end 181.638001 123.325001)
		(width 0.114)
		(layer "In5.Cu")
		(net 396)
	)
	(arc
		(start 175.138001 124.051742)
		(mid 175.275221 124.383022)
		(end 175.606501 124.520242)
		(width 0.114)
		(layer "In5.Cu")
		(net 396)
	)
	(arc
		(start 172.556501 117.356501)
		(mid 172.503341 117.484841)
		(end 172.375001 117.538001)
		(width 0.114)
		(layer "In5.Cu")
		(net 396)
	)
	(arc
		(start 171.413001 118.006501)
		(mid 171.550221 118.337781)
		(end 171.881501 118.475001)
		(width 0.114)
		(layer "In5.Cu")
		(net 396)
	)
	(arc
		(start 171.881501 116.238001)
		(mid 171.550221 116.375221)
		(end 171.413001 116.706501)
		(width 0.114)
		(layer "In5.Cu")
		(net 396)
	)
	(arc
		(start 172.556501 116.056501)
		(mid 172.503341 116.184841)
		(end 172.375001 116.238001)
		(width 0.114)
		(layer "In5.Cu")
		(net 396)
	)
	(arc
		(start 180.806501 124.520242)
		(mid 181.137781 124.383022)
		(end 181.275001 124.051742)
		(width 0.114)
		(layer "In5.Cu")
		(net 396)
	)
	(arc
		(start 177.556501 123.143501)
		(mid 177.684841 123.196661)
		(end 177.738001 123.325001)
		(width 0.114)
		(layer "In5.Cu")
		(net 396)
	)
	(arc
		(start 180.338001 124.051742)
		(mid 180.475221 124.383022)
		(end 180.806501 124.520242)
		(width 0.114)
		(layer "In5.Cu")
		(net 396)
	)
	(arc
		(start 176.438001 124.051742)
		(mid 176.575221 124.383022)
		(end 176.906501 124.520242)
		(width 0.114)
		(layer "In5.Cu")
		(net 396)
	)
	(arc
		(start 176.256501 123.143501)
		(mid 176.384841 123.196661)
		(end 176.438001 123.325001)
		(width 0.114)
		(layer "In5.Cu")
		(net 396)
	)
	(arc
		(start 177.375001 123.325001)
		(mid 177.428161 123.196661)
		(end 177.556501 123.143501)
		(width 0.114)
		(layer "In5.Cu")
		(net 396)
	)
	(arc
		(start 173.656501 123.143501)
		(mid 173.784841 123.196661)
		(end 173.838001 123.325001)
		(width 0.114)
		(layer "In5.Cu")
		(net 396)
	)
	(arc
		(start 172.375001 118.475001)
		(mid 172.503341 118.528161)
		(end 172.556501 118.656501)
		(width 0.114)
		(layer "In5.Cu")
		(net 396)
	)
	(arc
		(start 178.206501 124.520242)
		(mid 178.537781 124.383022)
		(end 178.675001 124.051742)
		(width 0.114)
		(layer "In5.Cu")
		(net 396)
	)
	(arc
		(start 172.375001 117.175001)
		(mid 172.503341 117.228161)
		(end 172.556501 117.356501)
		(width 0.114)
		(layer "In5.Cu")
		(net 396)
	)
	(segment
		(start 195.5 140.5)
		(end 195 141)
		(width 0.256)
		(layer "F.Cu")
		(net 397)
	)
	(via
		(at 251.275 131)
		(size 0.45)
		(drill 0.2)
		(layers "F.Cu" "B.Cu")
		(net 397)
	)
	(via
		(at 195 141)
		(size 0.45)
		(drill 0.2)
		(layers "F.Cu" "B.Cu")
		(net 397)
	)
	(segment
		(start 247.975 132.7)
		(end 250.95 132.7)
		(width 0.184)
		(layer "B.Cu")
		(net 397)
	)
	(segment
		(start 247.4 131.225)
		(end 247.4 130.585)
		(width 0.184)
		(layer "B.Cu")
		(net 397)
	)
	(segment
		(start 251.275 131)
		(end 250.95 131.325)
		(width 0.184)
		(layer "B.Cu")
		(net 397)
	)
	(segment
		(start 247.975 132.7)
		(end 247.475 132.2)
		(width 0.184)
		(layer "B.Cu")
		(net 397)
	)
	(segment
		(start 250.95 131.325)
		(end 250.95 132.7)
		(width 0.184)
		(layer "B.Cu")
		(net 397)
	)
	(segment
		(start 247.475 131.3)
		(end 247.4 131.225)
		(width 0.184)
		(layer "B.Cu")
		(net 397)
	)
	(segment
		(start 247.475 132.2)
		(end 247.475 131.3)
		(width 0.184)
		(layer "B.Cu")
		(net 397)
	)
	(segment
		(start 199.825 162.8)
		(end 199.825 163.097148)
		(width 0.1)
		(layer "In5.Cu")
		(net 397)
	)
	(segment
		(start 198.75 156.175)
		(end 198.75 162.15)
		(width 0.1)
		(layer "In5.Cu")
		(net 397)
	)
	(segment
		(start 210.15 162.625)
		(end 210.9 162.625)
		(width 0.1)
		(layer "In5.Cu")
		(net 397)
	)
	(segment
		(start 208.225 162.8)
		(end 208.225 163.097148)
		(width 0.1)
		(layer "In5.Cu")
		(net 397)
	)
	(segment
		(start 197.4 144.6)
		(end 195.525 146.475)
		(width 0.1)
		(layer "In5.Cu")
		(net 397)
	)
	(segment
		(start 242.498527 141.601473)
		(end 251.275 132.825)
		(width 0.1)
		(layer "In5.Cu")
		(net 397)
	)
	(segment
		(start 251.275 132.825)
		(end 251.275 131)
		(width 0.1)
		(layer "In5.Cu")
		(net 397)
	)
	(segment
		(start 195 141)
		(end 195.4 140.6)
		(width 0.1)
		(layer "In5.Cu")
		(net 397)
	)
	(segment
		(start 203.675 163.097148)
		(end 203.675 162.8)
		(width 0.1)
		(layer "In5.Cu")
		(net 397)
	)
	(segment
		(start 206.125 162.8)
		(end 206.125 163.097148)
		(width 0.1)
		(layer "In5.Cu")
		(net 397)
	)
	(segment
		(start 204.025 162.8)
		(end 204.025 163.097148)
		(width 0.1)
		(layer "In5.Cu")
		(net 397)
	)
	(segment
		(start 200.175 163.097148)
		(end 200.175 162.8)
		(width 0.1)
		(layer "In5.Cu")
		(net 397)
	)
	(segment
		(start 221.5 152.2)
		(end 224.8 152.2)
		(width 0.1)
		(layer "In5.Cu")
		(net 397)
	)
	(segment
		(start 198.75 162.15)
		(end 199.225 162.625)
		(width 0.1)
		(layer "In5.Cu")
		(net 397)
	)
	(segment
		(start 199.225 162.625)
		(end 199.65 162.625)
		(width 0.1)
		(layer "In5.Cu")
		(net 397)
	)
	(segment
		(start 211.075 162.625)
		(end 221.5 152.2)
		(width 0.1)
		(layer "In5.Cu")
		(net 397)
	)
	(segment
		(start 200.525 162.8)
		(end 200.525 163.097148)
		(width 0.1)
		(layer "In5.Cu")
		(net 397)
	)
	(segment
		(start 197.130331 140.6)
		(end 197.4 140.869669)
		(width 0.1)
		(layer "In5.Cu")
		(net 397)
	)
	(segment
		(start 209.275 163.097148)
		(end 209.275 162.8)
		(width 0.1)
		(layer "In5.Cu")
		(net 397)
	)
	(segment
		(start 207.175 163.097148)
		(end 207.175 162.8)
		(width 0.1)
		(layer "In5.Cu")
		(net 397)
	)
	(segment
		(start 208.575 163.097148)
		(end 208.575 162.8)
		(width 0.1)
		(layer "In5.Cu")
		(net 397)
	)
	(segment
		(start 207.875 163.097148)
		(end 207.875 162.8)
		(width 0.1)
		(layer "In5.Cu")
		(net 397)
	)
	(segment
		(start 201.225 162.8)
		(end 201.225 163.097148)
		(width 0.1)
		(layer "In5.Cu")
		(net 397)
	)
	(segment
		(start 203.325 162.8)
		(end 203.325 163.097148)
		(width 0.1)
		(layer "In5.Cu")
		(net 397)
	)
	(segment
		(start 202.975 163.097148)
		(end 202.975 162.8)
		(width 0.1)
		(layer "In5.Cu")
		(net 397)
	)
	(segment
		(start 204.375 163.097148)
		(end 204.375 162.8)
		(width 0.1)
		(layer "In5.Cu")
		(net 397)
	)
	(segment
		(start 209.625 162.8)
		(end 209.625 163.097148)
		(width 0.1)
		(layer "In5.Cu")
		(net 397)
	)
	(segment
		(start 197.4 140.869669)
		(end 197.4 144.6)
		(width 0.1)
		(layer "In5.Cu")
		(net 397)
	)
	(segment
		(start 205.775 163.097148)
		(end 205.775 162.8)
		(width 0.1)
		(layer "In5.Cu")
		(net 397)
	)
	(segment
		(start 235.398527 141.601473)
		(end 242.498527 141.601473)
		(width 0.1)
		(layer "In5.Cu")
		(net 397)
	)
	(segment
		(start 200.875 163.097148)
		(end 200.875 162.8)
		(width 0.1)
		(layer "In5.Cu")
		(net 397)
	)
	(segment
		(start 224.8 152.2)
		(end 235.398527 141.601473)
		(width 0.1)
		(layer "In5.Cu")
		(net 397)
	)
	(segment
		(start 210.9 162.625)
		(end 211.075 162.625)
		(width 0.1)
		(layer "In5.Cu")
		(net 397)
	)
	(segment
		(start 205.425 162.8)
		(end 205.425 163.097148)
		(width 0.1)
		(layer "In5.Cu")
		(net 397)
	)
	(segment
		(start 207.525 162.8)
		(end 207.525 163.097148)
		(width 0.1)
		(layer "In5.Cu")
		(net 397)
	)
	(segment
		(start 202.275 163.097148)
		(end 202.275 162.8)
		(width 0.1)
		(layer "In5.Cu")
		(net 397)
	)
	(segment
		(start 206.825 162.8)
		(end 206.825 163.097148)
		(width 0.1)
		(layer "In5.Cu")
		(net 397)
	)
	(segment
		(start 195.525 152.95)
		(end 198.75 156.175)
		(width 0.1)
		(layer "In5.Cu")
		(net 397)
	)
	(segment
		(start 195.525 146.475)
		(end 195.525 152.95)
		(width 0.1)
		(layer "In5.Cu")
		(net 397)
	)
	(segment
		(start 208.925 162.8)
		(end 208.925 163.097148)
		(width 0.1)
		(layer "In5.Cu")
		(net 397)
	)
	(segment
		(start 201.925 162.8)
		(end 201.925 163.097148)
		(width 0.1)
		(layer "In5.Cu")
		(net 397)
	)
	(segment
		(start 195.4 140.6)
		(end 197.130331 140.6)
		(width 0.1)
		(layer "In5.Cu")
		(net 397)
	)
	(segment
		(start 202.625 162.8)
		(end 202.625 163.097148)
		(width 0.1)
		(layer "In5.Cu")
		(net 397)
	)
	(segment
		(start 209.975 163.097148)
		(end 209.975 162.8)
		(width 0.1)
		(layer "In5.Cu")
		(net 397)
	)
	(segment
		(start 206.475 163.097148)
		(end 206.475 162.8)
		(width 0.1)
		(layer "In5.Cu")
		(net 397)
	)
	(segment
		(start 205.075 163.097148)
		(end 205.075 162.8)
		(width 0.1)
		(layer "In5.Cu")
		(net 397)
	)
	(segment
		(start 204.725 162.8)
		(end 204.725 163.097148)
		(width 0.1)
		(layer "In5.Cu")
		(net 397)
	)
	(segment
		(start 201.575 163.097148)
		(end 201.575 162.8)
		(width 0.1)
		(layer "In5.Cu")
		(net 397)
	)
	(arc
		(start 199.65 162.625)
		(mid 199.773744 162.676256)
		(end 199.825 162.8)
		(width 0.1)
		(layer "In5.Cu")
		(net 397)
	)
	(arc
		(start 203.675 162.8)
		(mid 203.726256 162.676256)
		(end 203.85 162.625)
		(width 0.1)
		(layer "In5.Cu")
		(net 397)
	)
	(arc
		(start 207.35 162.625)
		(mid 207.473744 162.676256)
		(end 207.525 162.8)
		(width 0.1)
		(layer "In5.Cu")
		(net 397)
	)
	(arc
		(start 203.85 162.625)
		(mid 203.973744 162.676256)
		(end 204.025 162.8)
		(width 0.1)
		(layer "In5.Cu")
		(net 397)
	)
	(arc
		(start 200 163.272148)
		(mid 200.123744 163.220892)
		(end 200.175 163.097148)
		(width 0.1)
		(layer "In5.Cu")
		(net 397)
	)
	(arc
		(start 204.025 163.097148)
		(mid 204.076256 163.220892)
		(end 204.2 163.272148)
		(width 0.1)
		(layer "In5.Cu")
		(net 397)
	)
	(arc
		(start 207.7 163.272148)
		(mid 207.823744 163.220892)
		(end 207.875 163.097148)
		(width 0.1)
		(layer "In5.Cu")
		(net 397)
	)
	(arc
		(start 205.25 162.625)
		(mid 205.373744 162.676256)
		(end 205.425 162.8)
		(width 0.1)
		(layer "In5.Cu")
		(net 397)
	)
	(arc
		(start 208.225 163.097148)
		(mid 208.276256 163.220892)
		(end 208.4 163.272148)
		(width 0.1)
		(layer "In5.Cu")
		(net 397)
	)
	(arc
		(start 200.525 163.097148)
		(mid 200.576256 163.220892)
		(end 200.7 163.272148)
		(width 0.1)
		(layer "In5.Cu")
		(net 397)
	)
	(arc
		(start 206.825 163.097148)
		(mid 206.876256 163.220892)
		(end 207 163.272148)
		(width 0.1)
		(layer "In5.Cu")
		(net 397)
	)
	(arc
		(start 207.875 162.8)
		(mid 207.926256 162.676256)
		(end 208.05 162.625)
		(width 0.1)
		(layer "In5.Cu")
		(net 397)
	)
	(arc
		(start 209.975 162.8)
		(mid 210.026256 162.676256)
		(end 210.15 162.625)
		(width 0.1)
		(layer "In5.Cu")
		(net 397)
	)
	(arc
		(start 204.2 163.272148)
		(mid 204.323744 163.220892)
		(end 204.375 163.097148)
		(width 0.1)
		(layer "In5.Cu")
		(net 397)
	)
	(arc
		(start 205.95 162.625)
		(mid 206.073744 162.676256)
		(end 206.125 162.8)
		(width 0.1)
		(layer "In5.Cu")
		(net 397)
	)
	(arc
		(start 200.175 162.8)
		(mid 200.226256 162.676256)
		(end 200.35 162.625)
		(width 0.1)
		(layer "In5.Cu")
		(net 397)
	)
	(arc
		(start 201.4 163.272148)
		(mid 201.523744 163.220892)
		(end 201.575 163.097148)
		(width 0.1)
		(layer "In5.Cu")
		(net 397)
	)
	(arc
		(start 201.925 163.097148)
		(mid 201.976256 163.220892)
		(end 202.1 163.272148)
		(width 0.1)
		(layer "In5.Cu")
		(net 397)
	)
	(arc
		(start 204.725 163.097148)
		(mid 204.776256 163.220892)
		(end 204.9 163.272148)
		(width 0.1)
		(layer "In5.Cu")
		(net 397)
	)
	(arc
		(start 205.425 163.097148)
		(mid 205.476256 163.220892)
		(end 205.6 163.272148)
		(width 0.1)
		(layer "In5.Cu")
		(net 397)
	)
	(arc
		(start 204.55 162.625)
		(mid 204.673744 162.676256)
		(end 204.725 162.8)
		(width 0.1)
		(layer "In5.Cu")
		(net 397)
	)
	(arc
		(start 204.375 162.8)
		(mid 204.426256 162.676256)
		(end 204.55 162.625)
		(width 0.1)
		(layer "In5.Cu")
		(net 397)
	)
	(arc
		(start 202.8 163.272148)
		(mid 202.923744 163.220892)
		(end 202.975 163.097148)
		(width 0.1)
		(layer "In5.Cu")
		(net 397)
	)
	(arc
		(start 200.875 162.8)
		(mid 200.926256 162.676256)
		(end 201.05 162.625)
		(width 0.1)
		(layer "In5.Cu")
		(net 397)
	)
	(arc
		(start 208.925 163.097148)
		(mid 208.976256 163.220892)
		(end 209.1 163.272148)
		(width 0.1)
		(layer "In5.Cu")
		(net 397)
	)
	(arc
		(start 206.3 163.272148)
		(mid 206.423744 163.220892)
		(end 206.475 163.097148)
		(width 0.1)
		(layer "In5.Cu")
		(net 397)
	)
	(arc
		(start 205.775 162.8)
		(mid 205.826256 162.676256)
		(end 205.95 162.625)
		(width 0.1)
		(layer "In5.Cu")
		(net 397)
	)
	(arc
		(start 202.275 162.8)
		(mid 202.326256 162.676256)
		(end 202.45 162.625)
		(width 0.1)
		(layer "In5.Cu")
		(net 397)
	)
	(arc
		(start 202.45 162.625)
		(mid 202.573744 162.676256)
		(end 202.625 162.8)
		(width 0.1)
		(layer "In5.Cu")
		(net 397)
	)
	(arc
		(start 209.45 162.625)
		(mid 209.573744 162.676256)
		(end 209.625 162.8)
		(width 0.1)
		(layer "In5.Cu")
		(net 397)
	)
	(arc
		(start 202.625 163.097148)
		(mid 202.676256 163.220892)
		(end 202.8 163.272148)
		(width 0.1)
		(layer "In5.Cu")
		(net 397)
	)
	(arc
		(start 204.9 163.272148)
		(mid 205.023744 163.220892)
		(end 205.075 163.097148)
		(width 0.1)
		(layer "In5.Cu")
		(net 397)
	)
	(arc
		(start 201.225 163.097148)
		(mid 201.276256 163.220892)
		(end 201.4 163.272148)
		(width 0.1)
		(layer "In5.Cu")
		(net 397)
	)
	(arc
		(start 208.05 162.625)
		(mid 208.173744 162.676256)
		(end 208.225 162.8)
		(width 0.1)
		(layer "In5.Cu")
		(net 397)
	)
	(arc
		(start 201.05 162.625)
		(mid 201.173744 162.676256)
		(end 201.225 162.8)
		(width 0.1)
		(layer "In5.Cu")
		(net 397)
	)
	(arc
		(start 209.8 163.272148)
		(mid 209.923744 163.220892)
		(end 209.975 163.097148)
		(width 0.1)
		(layer "In5.Cu")
		(net 397)
	)
	(arc
		(start 207 163.272148)
		(mid 207.123744 163.220892)
		(end 207.175 163.097148)
		(width 0.1)
		(layer "In5.Cu")
		(net 397)
	)
	(arc
		(start 199.825 163.097148)
		(mid 199.876256 163.220892)
		(end 200 163.272148)
		(width 0.1)
		(layer "In5.Cu")
		(net 397)
	)
	(arc
		(start 205.075 162.8)
		(mid 205.126256 162.676256)
		(end 205.25 162.625)
		(width 0.1)
		(layer "In5.Cu")
		(net 397)
	)
	(arc
		(start 209.625 163.097148)
		(mid 209.676256 163.220892)
		(end 209.8 163.272148)
		(width 0.1)
		(layer "In5.Cu")
		(net 397)
	)
	(arc
		(start 209.1 163.272148)
		(mid 209.223744 163.220892)
		(end 209.275 163.097148)
		(width 0.1)
		(layer "In5.Cu")
		(net 397)
	)
	(arc
		(start 207.175 162.8)
		(mid 207.226256 162.676256)
		(end 207.35 162.625)
		(width 0.1)
		(layer "In5.Cu")
		(net 397)
	)
	(arc
		(start 206.65 162.625)
		(mid 206.773744 162.676256)
		(end 206.825 162.8)
		(width 0.1)
		(layer "In5.Cu")
		(net 397)
	)
	(arc
		(start 206.125 163.097148)
		(mid 206.176256 163.220892)
		(end 206.3 163.272148)
		(width 0.1)
		(layer "In5.Cu")
		(net 397)
	)
	(arc
		(start 205.6 163.272148)
		(mid 205.723744 163.220892)
		(end 205.775 163.097148)
		(width 0.1)
		(layer "In5.Cu")
		(net 397)
	)
	(arc
		(start 203.325 163.097148)
		(mid 203.376256 163.220892)
		(end 203.5 163.272148)
		(width 0.1)
		(layer "In5.Cu")
		(net 397)
	)
	(arc
		(start 203.15 162.625)
		(mid 203.273744 162.676256)
		(end 203.325 162.8)
		(width 0.1)
		(layer "In5.Cu")
		(net 397)
	)
	(arc
		(start 200.7 163.272148)
		(mid 200.823744 163.220892)
		(end 200.875 163.097148)
		(width 0.1)
		(layer "In5.Cu")
		(net 397)
	)
	(arc
		(start 202.975 162.8)
		(mid 203.026256 162.676256)
		(end 203.15 162.625)
		(width 0.1)
		(layer "In5.Cu")
		(net 397)
	)
	(arc
		(start 207.525 163.097148)
		(mid 207.576256 163.220892)
		(end 207.7 163.272148)
		(width 0.1)
		(layer "In5.Cu")
		(net 397)
	)
	(arc
		(start 201.75 162.625)
		(mid 201.873744 162.676256)
		(end 201.925 162.8)
		(width 0.1)
		(layer "In5.Cu")
		(net 397)
	)
	(arc
		(start 208.4 163.272148)
		(mid 208.523744 163.220892)
		(end 208.575 163.097148)
		(width 0.1)
		(layer "In5.Cu")
		(net 397)
	)
	(arc
		(start 206.475 162.8)
		(mid 206.526256 162.676256)
		(end 206.65 162.625)
		(width 0.1)
		(layer "In5.Cu")
		(net 397)
	)
	(arc
		(start 203.5 163.272148)
		(mid 203.623744 163.220892)
		(end 203.675 163.097148)
		(width 0.1)
		(layer "In5.Cu")
		(net 397)
	)
	(arc
		(start 200.35 162.625)
		(mid 200.473744 162.676256)
		(end 200.525 162.8)
		(width 0.1)
		(layer "In5.Cu")
		(net 397)
	)
	(arc
		(start 208.575 162.8)
		(mid 208.626256 162.676256)
		(end 208.75 162.625)
		(width 0.1)
		(layer "In5.Cu")
		(net 397)
	)
	(arc
		(start 209.275 162.8)
		(mid 209.326256 162.676256)
		(end 209.45 162.625)
		(width 0.1)
		(layer "In5.Cu")
		(net 397)
	)
	(arc
		(start 201.575 162.8)
		(mid 201.626256 162.676256)
		(end 201.75 162.625)
		(width 0.1)
		(layer "In5.Cu")
		(net 397)
	)
	(arc
		(start 208.75 162.625)
		(mid 208.873744 162.676256)
		(end 208.925 162.8)
		(width 0.1)
		(layer "In5.Cu")
		(net 397)
	)
	(arc
		(start 202.1 163.272148)
		(mid 202.223744 163.220892)
		(end 202.275 163.097148)
		(width 0.1)
		(layer "In5.Cu")
		(net 397)
	)
	(segment
		(start 236.4 117.5)
		(end 236.4 118.5)
		(width 0.1)
		(layer "F.Cu")
		(net 398)
	)
	(segment
		(start 208.5 129.5)
		(end 209 129)
		(width 0.256)
		(layer "F.Cu")
		(net 398)
	)
	(segment
		(start 237.1 119.2)
		(end 237.1 122.8)
		(width 0.1)
		(layer "F.Cu")
		(net 398)
	)
	(segment
		(start 236.6 123.3)
		(end 236.175 123.3)
		(width 0.1)
		(layer "F.Cu")
		(net 398)
	)
	(segment
		(start 237.1 122.8)
		(end 236.6 123.3)
		(width 0.1)
		(layer "F.Cu")
		(net 398)
	)
	(segment
		(start 236.4 118.5)
		(end 237.1 119.2)
		(width 0.1)
		(layer "F.Cu")
		(net 398)
	)
	(via
		(at 209 129)
		(size 0.45)
		(drill 0.2)
		(layers "F.Cu" "B.Cu")
		(net 398)
	)
	(via
		(at 236.175 123.3)
		(size 0.45)
		(drill 0.2)
		(layers "F.Cu" "B.Cu")
		(net 398)
	)
	(segment
		(start 219.7 123.55)
		(end 215.825 127.425)
		(width 0.1)
		(layer "In7.Cu")
		(net 398)
	)
	(segment
		(start 226.625 123.55)
		(end 219.7 123.55)
		(width 0.1)
		(layer "In7.Cu")
		(net 398)
	)
	(segment
		(start 209.625 128.375)
		(end 209 129)
		(width 0.1)
		(layer "In7.Cu")
		(net 398)
	)
	(segment
		(start 210.755 127.425)
		(end 210.425 127.755)
		(width 0.1)
		(layer "In7.Cu")
		(net 398)
	)
	(segment
		(start 210.425 127.755)
		(end 210.425 128.239316)
		(width 0.1)
		(layer "In7.Cu")
		(net 398)
	)
	(segment
		(start 210.289316 128.375)
		(end 209.625 128.375)
		(width 0.1)
		(layer "In7.Cu")
		(net 398)
	)
	(segment
		(start 210.425 128.239316)
		(end 210.289316 128.375)
		(width 0.1)
		(layer "In7.Cu")
		(net 398)
	)
	(segment
		(start 215.825 127.425)
		(end 210.755 127.425)
		(width 0.1)
		(layer "In7.Cu")
		(net 398)
	)
	(segment
		(start 236.175 123.3)
		(end 235.675 122.8)
		(width 0.1)
		(layer "In7.Cu")
		(net 398)
	)
	(segment
		(start 227.375 122.8)
		(end 226.625 123.55)
		(width 0.1)
		(layer "In7.Cu")
		(net 398)
	)
	(segment
		(start 235.675 122.8)
		(end 227.375 122.8)
		(width 0.1)
		(layer "In7.Cu")
		(net 398)
	)
	(segment
		(start 158.825001 111.715001)
		(end 158.825001 111.896198)
		(width 0.16)
		(layer "F.Cu")
		(net 400)
	)
	(segment
		(start 159.315002 112.218)
		(end 159.146804 112.218001)
		(width 0.16)
		(layer "F.Cu")
		(net 400)
	)
	(segment
		(start 195.5 122.5)
		(end 195.025 122.025)
		(width 0.256)
		(layer "F.Cu")
		(net 400)
	)
	(segment
		(start 195.025 122.025)
		(end 195.025 122.01)
		(width 0.256)
		(layer "F.Cu")
		(net 400)
	)
	(segment
		(start 159.315002 112.218)
		(end 159.460001 112.073001)
		(width 0.16)
		(layer "F.Cu")
		(net 400)
	)
	(segment
		(start 158.825001 111.896198)
		(end 159.146804 112.218001)
		(width 0.16)
		(layer "F.Cu")
		(net 400)
	)
	(via
		(at 159.460001 112.073001)
		(size 0.45)
		(drill 0.2)
		(layers "F.Cu" "B.Cu")
		(net 400)
	)
	(via
		(at 195.025 122.01)
		(size 0.45)
		(drill 0.2)
		(layers "F.Cu" "B.Cu")
		(net 400)
	)
	(via
		(at 171.645265 114.339737)
		(size 0.45)
		(drill 0.2)
		(layers "F.Cu" "B.Cu")
		(net 400)
	)
	(segment
		(start 171.407677 114.339737)
		(end 171.645265 114.339737)
		(width 0.114)
		(layer "In3.Cu")
		(net 400)
	)
	(segment
		(start 159.593501 112.206501)
		(end 159.780561 112.206501)
		(width 0.114)
		(layer "In3.Cu")
		(net 400)
	)
	(segment
		(start 160.420561 111.566501)
		(end 160.806501 111.566501)
		(width 0.114)
		(layer "In3.Cu")
		(net 400)
	)
	(segment
		(start 161.331501 111.299593)
		(end 161.331501 111.391501)
		(width 0.114)
		(layer "In3.Cu")
		(net 400)
	)
	(segment
		(start 159.780561 112.206501)
		(end 160.420561 111.566501)
		(width 0.114)
		(layer "In3.Cu")
		(net 400)
	)
	(segment
		(start 159.460001 112.073001)
		(end 159.593501 112.206501)
		(width 0.114)
		(layer "In3.Cu")
		(net 400)
	)
	(segment
		(start 161.506501 111.566501)
		(end 169.869441 111.566501)
		(width 0.114)
		(layer "In3.Cu")
		(net 400)
	)
	(segment
		(start 169.869441 111.566501)
		(end 170.443501 112.140561)
		(width 0.114)
		(layer "In3.Cu")
		(net 400)
	)
	(segment
		(start 160.981501 111.391501)
		(end 160.981501 111.299593)
		(width 0.114)
		(layer "In3.Cu")
		(net 400)
	)
	(segment
		(start 170.443501 112.140561)
		(end 170.443501 113.375561)
		(width 0.114)
		(layer "In3.Cu")
		(net 400)
	)
	(segment
		(start 170.443501 113.375561)
		(end 171.407677 114.339737)
		(width 0.114)
		(layer "In3.Cu")
		(net 400)
	)
	(arc
		(start 160.981501 111.299593)
		(mid 161.032757 111.175849)
		(end 161.156501 111.124593)
		(width 0.114)
		(layer "In3.Cu")
		(net 400)
	)
	(arc
		(start 161.331501 111.391501)
		(mid 161.382757 111.515245)
		(end 161.506501 111.566501)
		(width 0.114)
		(layer "In3.Cu")
		(net 400)
	)
	(arc
		(start 161.156501 111.124593)
		(mid 161.280245 111.175849)
		(end 161.331501 111.299593)
		(width 0.114)
		(layer "In3.Cu")
		(net 400)
	)
	(arc
		(start 160.806501 111.566501)
		(mid 160.930245 111.515245)
		(end 160.981501 111.391501)
		(width 0.114)
		(layer "In3.Cu")
		(net 400)
	)
	(segment
		(start 180.625001 123.325001)
		(end 180.625001 124.051742)
		(width 0.114)
		(layer "In5.Cu")
		(net 400)
	)
	(segment
		(start 171.645265 114.577325)
		(end 172.843501 115.775561)
		(width 0.114)
		(layer "In5.Cu")
		(net 400)
	)
	(segment
		(start 183.448501 122.900001)
		(end 183.405001 122.856501)
		(width 0.1)
		(layer "In5.Cu")
		(net 400)
	)
	(segment
		(start 172.843501 118.656501)
		(end 172.843501 118.746629)
		(width 0.114)
		(layer "In5.Cu")
		(net 400)
	)
	(segment
		(start 171.881501 118.188001)
		(end 172.375001 118.188001)
		(width 0.114)
		(layer "In5.Cu")
		(net 400)
	)
	(segment
		(start 172.843501 115.775561)
		(end 172.843501 116.056501)
		(width 0.114)
		(layer "In5.Cu")
		(net 400)
	)
	(segment
		(start 195.400001 123.183579)
		(end 195.183579 123.400001)
		(width 0.1)
		(layer "In5.Cu")
		(net 400)
	)
	(segment
		(start 193.116423 122.900001)
		(end 183.448501 122.900001)
		(width 0.1)
		(layer "In5.Cu")
		(net 400)
	)
	(segment
		(start 195.400001 122.400001)
		(end 195.400001 123.183579)
		(width 0.1)
		(layer "In5.Cu")
		(net 400)
	)
	(segment
		(start 181.925001 123.325001)
		(end 181.925001 124.051742)
		(width 0.114)
		(layer "In5.Cu")
		(net 400)
	)
	(segment
		(start 171.645265 114.339737)
		(end 171.645265 114.577325)
		(width 0.114)
		(layer "In5.Cu")
		(net 400)
	)
	(segment
		(start 173.074441 122.856501)
		(end 173.656501 122.856501)
		(width 0.114)
		(layer "In5.Cu")
		(net 400)
	)
	(segment
		(start 178.388001 124.051742)
		(end 178.388001 123.325001)
		(width 0.114)
		(layer "In5.Cu")
		(net 400)
	)
	(segment
		(start 174.125001 123.325001)
		(end 174.125001 124.051742)
		(width 0.114)
		(layer "In5.Cu")
		(net 400)
	)
	(segment
		(start 182.756501 122.856501)
		(end 183.405001 122.856501)
		(width 0.114)
		(layer "In5.Cu")
		(net 400)
	)
	(segment
		(start 179.688001 124.051742)
		(end 179.688001 123.325001)
		(width 0.114)
		(layer "In5.Cu")
		(net 400)
	)
	(segment
		(start 174.488001 124.051742)
		(end 174.488001 123.325001)
		(width 0.114)
		(layer "In5.Cu")
		(net 400)
	)
	(segment
		(start 171.881501 116.888001)
		(end 172.375001 116.888001)
		(width 0.114)
		(layer "In5.Cu")
		(net 400)
	)
	(segment
		(start 172.843501 122.625561)
		(end 173.074441 122.856501)
		(width 0.114)
		(layer "In5.Cu")
		(net 400)
	)
	(segment
		(start 172.375001 116.525001)
		(end 171.881501 116.525001)
		(width 0.114)
		(layer "In5.Cu")
		(net 400)
	)
	(segment
		(start 175.788001 124.051742)
		(end 175.788001 123.325001)
		(width 0.114)
		(layer "In5.Cu")
		(net 400)
	)
	(segment
		(start 172.375001 117.825001)
		(end 171.881501 117.825001)
		(width 0.114)
		(layer "In5.Cu")
		(net 400)
	)
	(segment
		(start 179.325001 123.325001)
		(end 179.325001 124.051742)
		(width 0.114)
		(layer "In5.Cu")
		(net 400)
	)
	(segment
		(start 195.183579 123.400001)
		(end 193.616423 123.400001)
		(width 0.1)
		(layer "In5.Cu")
		(net 400)
	)
	(segment
		(start 182.288001 124.051742)
		(end 182.288001 123.325001)
		(width 0.114)
		(layer "In5.Cu")
		(net 400)
	)
	(segment
		(start 180.988001 124.051742)
		(end 180.988001 123.325001)
		(width 0.114)
		(layer "In5.Cu")
		(net 400)
	)
	(segment
		(start 175.425001 123.325001)
		(end 175.425001 124.051742)
		(width 0.114)
		(layer "In5.Cu")
		(net 400)
	)
	(segment
		(start 195.000001 122.000001)
		(end 195.400001 122.400001)
		(width 0.1)
		(layer "In5.Cu")
		(net 400)
	)
	(segment
		(start 193.616423 123.400001)
		(end 193.116423 122.900001)
		(width 0.1)
		(layer "In5.Cu")
		(net 400)
	)
	(segment
		(start 178.025001 123.325001)
		(end 178.025001 124.051742)
		(width 0.114)
		(layer "In5.Cu")
		(net 400)
	)
	(segment
		(start 172.843501 118.746629)
		(end 172.843501 122.625561)
		(width 0.114)
		(layer "In5.Cu")
		(net 400)
	)
	(segment
		(start 176.725001 123.325001)
		(end 176.725001 124.051742)
		(width 0.114)
		(layer "In5.Cu")
		(net 400)
	)
	(segment
		(start 177.088001 124.051742)
		(end 177.088001 123.325001)
		(width 0.114)
		(layer "In5.Cu")
		(net 400)
	)
	(arc
		(start 171.881501 116.525001)
		(mid 171.753161 116.578161)
		(end 171.700001 116.706501)
		(width 0.114)
		(layer "In5.Cu")
		(net 400)
	)
	(arc
		(start 180.806501 124.233242)
		(mid 180.934841 124.180082)
		(end 180.988001 124.051742)
		(width 0.114)
		(layer "In5.Cu")
		(net 400)
	)
	(arc
		(start 179.506501 124.233242)
		(mid 179.634841 124.180082)
		(end 179.688001 124.051742)
		(width 0.114)
		(layer "In5.Cu")
		(net 400)
	)
	(arc
		(start 172.375001 116.888001)
		(mid 172.706281 117.025221)
		(end 172.843501 117.356501)
		(width 0.114)
		(layer "In5.Cu")
		(net 400)
	)
	(arc
		(start 175.425001 124.051742)
		(mid 175.478161 124.180082)
		(end 175.606501 124.233242)
		(width 0.114)
		(layer "In5.Cu")
		(net 400)
	)
	(arc
		(start 180.156501 122.856501)
		(mid 180.487781 122.993721)
		(end 180.625001 123.325001)
		(width 0.114)
		(layer "In5.Cu")
		(net 400)
	)
	(arc
		(start 179.325001 124.051742)
		(mid 179.378161 124.180082)
		(end 179.506501 124.233242)
		(width 0.114)
		(layer "In5.Cu")
		(net 400)
	)
	(arc
		(start 171.881501 117.825001)
		(mid 171.753161 117.878161)
		(end 171.700001 118.006501)
		(width 0.114)
		(layer "In5.Cu")
		(net 400)
	)
	(arc
		(start 182.288001 123.325001)
		(mid 182.425221 122.993721)
		(end 182.756501 122.856501)
		(width 0.114)
		(layer "In5.Cu")
		(net 400)
	)
	(arc
		(start 181.925001 124.051742)
		(mid 181.978161 124.180082)
		(end 182.106501 124.233242)
		(width 0.114)
		(layer "In5.Cu")
		(net 400)
	)
	(arc
		(start 177.088001 123.325001)
		(mid 177.225221 122.993721)
		(end 177.556501 122.856501)
		(width 0.114)
		(layer "In5.Cu")
		(net 400)
	)
	(arc
		(start 177.556501 122.856501)
		(mid 177.887781 122.993721)
		(end 178.025001 123.325001)
		(width 0.114)
		(layer "In5.Cu")
		(net 400)
	)
	(arc
		(start 174.125001 124.051742)
		(mid 174.178161 124.180082)
		(end 174.306501 124.233242)
		(width 0.114)
		(layer "In5.Cu")
		(net 400)
	)
	(arc
		(start 180.988001 123.325001)
		(mid 181.125221 122.993721)
		(end 181.456501 122.856501)
		(width 0.114)
		(layer "In5.Cu")
		(net 400)
	)
	(arc
		(start 174.956501 122.856501)
		(mid 175.287781 122.993721)
		(end 175.425001 123.325001)
		(width 0.114)
		(layer "In5.Cu")
		(net 400)
	)
	(arc
		(start 172.375001 118.188001)
		(mid 172.706281 118.325221)
		(end 172.843501 118.656501)
		(width 0.114)
		(layer "In5.Cu")
		(net 400)
	)
	(arc
		(start 172.843501 116.056501)
		(mid 172.706281 116.387781)
		(end 172.375001 116.525001)
		(width 0.114)
		(layer "In5.Cu")
		(net 400)
	)
	(arc
		(start 172.843501 117.356501)
		(mid 172.706281 117.687781)
		(end 172.375001 117.825001)
		(width 0.114)
		(layer "In5.Cu")
		(net 400)
	)
	(arc
		(start 182.106501 124.233242)
		(mid 182.234841 124.180082)
		(end 182.288001 124.051742)
		(width 0.114)
		(layer "In5.Cu")
		(net 400)
	)
	(arc
		(start 178.856501 122.856501)
		(mid 179.187781 122.993721)
		(end 179.325001 123.325001)
		(width 0.114)
		(layer "In5.Cu")
		(net 400)
	)
	(arc
		(start 174.488001 123.325001)
		(mid 174.625221 122.993721)
		(end 174.956501 122.856501)
		(width 0.114)
		(layer "In5.Cu")
		(net 400)
	)
	(arc
		(start 175.606501 124.233242)
		(mid 175.734841 124.180082)
		(end 175.788001 124.051742)
		(width 0.114)
		(layer "In5.Cu")
		(net 400)
	)
	(arc
		(start 171.700001 118.006501)
		(mid 171.753161 118.134841)
		(end 171.881501 118.188001)
		(width 0.114)
		(layer "In5.Cu")
		(net 400)
	)
	(arc
		(start 180.625001 124.051742)
		(mid 180.678161 124.180082)
		(end 180.806501 124.233242)
		(width 0.114)
		(layer "In5.Cu")
		(net 400)
	)
	(arc
		(start 179.688001 123.325001)
		(mid 179.825221 122.993721)
		(end 180.156501 122.856501)
		(width 0.114)
		(layer "In5.Cu")
		(net 400)
	)
	(arc
		(start 176.725001 124.051742)
		(mid 176.778161 124.180082)
		(end 176.906501 124.233242)
		(width 0.114)
		(layer "In5.Cu")
		(net 400)
	)
	(arc
		(start 178.388001 123.325001)
		(mid 178.525221 122.993721)
		(end 178.856501 122.856501)
		(width 0.114)
		(layer "In5.Cu")
		(net 400)
	)
	(arc
		(start 174.306501 124.233242)
		(mid 174.434841 124.180082)
		(end 174.488001 124.051742)
		(width 0.114)
		(layer "In5.Cu")
		(net 400)
	)
	(arc
		(start 178.025001 124.051742)
		(mid 178.078161 124.180082)
		(end 178.206501 124.233242)
		(width 0.114)
		(layer "In5.Cu")
		(net 400)
	)
	(arc
		(start 181.456501 122.856501)
		(mid 181.787781 122.993721)
		(end 181.925001 123.325001)
		(width 0.114)
		(layer "In5.Cu")
		(net 400)
	)
	(arc
		(start 178.206501 124.233242)
		(mid 178.334841 124.180082)
		(end 178.388001 124.051742)
		(width 0.114)
		(layer "In5.Cu")
		(net 400)
	)
	(arc
		(start 171.700001 116.706501)
		(mid 171.753161 116.834841)
		(end 171.881501 116.888001)
		(width 0.114)
		(layer "In5.Cu")
		(net 400)
	)
	(arc
		(start 176.906501 124.233242)
		(mid 177.034841 124.180082)
		(end 177.088001 124.051742)
		(width 0.114)
		(layer "In5.Cu")
		(net 400)
	)
	(arc
		(start 175.788001 123.325001)
		(mid 175.925221 122.993721)
		(end 176.256501 122.856501)
		(width 0.114)
		(layer "In5.Cu")
		(net 400)
	)
	(arc
		(start 173.656501 122.856501)
		(mid 173.987781 122.993721)
		(end 174.125001 123.325001)
		(width 0.114)
		(layer "In5.Cu")
		(net 400)
	)
	(arc
		(start 176.256501 122.856501)
		(mid 176.587781 122.993721)
		(end 176.725001 123.325001)
		(width 0.114)
		(layer "In5.Cu")
		(net 400)
	)
	(segment
		(start 160.095001 111.715001)
		(end 160.095001 111.461001)
		(width 0.198)
		(layer "F.Cu")
		(net 401)
	)
	(segment
		(start 160.095001 111.461001)
		(end 159.818001 111.184001)
		(width 0.198)
		(layer "F.Cu")
		(net 401)
	)
	(segment
		(start 159.818001 111.184001)
		(end 159.818001 111.080001)
		(width 0.198)
		(layer "F.Cu")
		(net 401)
	)
	(segment
		(start 195.5 124.5)
		(end 195 124)
		(width 0.256)
		(layer "F.Cu")
		(net 401)
	)
	(via
		(at 195 124)
		(size 0.45)
		(drill 0.2)
		(layers "F.Cu" "B.Cu")
		(net 401)
	)
	(via
		(at 159.818001 111.080001)
		(size 0.45)
		(drill 0.2)
		(layers "F.Cu" "B.Cu")
		(net 401)
	)
	(segment
		(start 164.017767 110.735349)
		(end 164.017767 112.682235)
		(width 0.114)
		(layer "In7.Cu")
		(net 401)
	)
	(segment
		(start 166.517767 121.575735)
		(end 164.224267 121.575735)
		(width 0.114)
		(layer "In7.Cu")
		(net 401)
	)
	(segment
		(start 164.967767 116.411267)
		(end 164.224267 116.411267)
		(width 0.114)
		(layer "In7.Cu")
		(net 401)
	)
	(segment
		(start 164.017767 121.782235)
		(end 164.017767 123.464827)
		(width 0.114)
		(layer "In7.Cu")
		(net 401)
	)
	(segment
		(start 164.199267 112.863735)
		(end 164.692767 112.863735)
		(width 0.114)
		(layer "In7.Cu")
		(net 401)
	)
	(segment
		(start 164.017767 116.635046)
		(end 164.017767 120.382235)
		(width 0.114)
		(layer "In7.Cu")
		(net 401)
	)
	(segment
		(start 168.475001 123.449558)
		(end 168.475001 124.075001)
		(width 0.114)
		(layer "In7.Cu")
		(net 401)
	)
	(segment
		(start 163.055767 113.800735)
		(end 164.692767 113.800735)
		(width 0.114)
		(layer "In7.Cu")
		(net 401)
	)
	(segment
		(start 164.224267 115.424267)
		(end 164.967767 115.424267)
		(width 0.114)
		(layer "In7.Cu")
		(net 401)
	)
	(segment
		(start 166.238001 124.075001)
		(end 166.238001 123.449558)
		(width 0.114)
		(layer "In7.Cu")
		(net 401)
	)
	(segment
		(start 195.000001 124.000001)
		(end 194.600001 124.400001)
		(width 0.1)
		(layer "In7.Cu")
		(net 401)
	)
	(segment
		(start 173.290561 124.256501)
		(end 173.690561 123.856501)
		(width 0.114)
		(layer "In7.Cu")
		(net 401)
	)
	(segment
		(start 168.656501 124.256501)
		(end 173.290561 124.256501)
		(width 0.114)
		(layer "In7.Cu")
		(net 401)
	)
	(segment
		(start 183.448501 123.900001)
		(end 183.405001 123.856501)
		(width 0.1)
		(layer "In7.Cu")
		(net 401)
	)
	(segment
		(start 164.017767 114.68528)
		(end 164.017767 115.217767)
		(width 0.114)
		(layer "In7.Cu")
		(net 401)
	)
	(segment
		(start 164.809441 124.256501)
		(end 166.056501 124.256501)
		(width 0.114)
		(layer "In7.Cu")
		(net 401)
	)
	(segment
		(start 160.26673 110.301501)
		(end 163.583919 110.301501)
		(width 0.114)
		(layer "In7.Cu")
		(net 401)
	)
	(segment
		(start 163.055767 114.163735)
		(end 163.549267 114.163735)
		(width 0.114)
		(layer "In7.Cu")
		(net 401)
	)
	(segment
		(start 193.676423 124.400001)
		(end 193.176423 123.900001)
		(width 0.1)
		(layer "In7.Cu")
		(net 401)
	)
	(segment
		(start 167.175001 123.449558)
		(end 167.175001 124.075001)
		(width 0.114)
		(layer "In7.Cu")
		(net 401)
	)
	(segment
		(start 164.224267 120.588735)
		(end 166.517767 120.588735)
		(width 0.114)
		(layer "In7.Cu")
		(net 401)
	)
	(segment
		(start 159.818001 111.080001)
		(end 159.951501 110.946501)
		(width 0.114)
		(layer "In7.Cu")
		(net 401)
	)
	(segment
		(start 159.951501 110.61673)
		(end 160.26673 110.301501)
		(width 0.114)
		(layer "In7.Cu")
		(net 401)
	)
	(segment
		(start 163.583919 110.301501)
		(end 164.017767 110.735349)
		(width 0.114)
		(layer "In7.Cu")
		(net 401)
	)
	(segment
		(start 164.017767 123.464827)
		(end 164.809441 124.256501)
		(width 0.114)
		(layer "In7.Cu")
		(net 401)
	)
	(segment
		(start 164.017767 114.632235)
		(end 164.017767 114.68528)
		(width 0.114)
		(layer "In7.Cu")
		(net 401)
	)
	(segment
		(start 193.176423 123.900001)
		(end 183.448501 123.900001)
		(width 0.1)
		(layer "In7.Cu")
		(net 401)
	)
	(segment
		(start 167.538001 124.075001)
		(end 167.538001 123.449558)
		(width 0.114)
		(layer "In7.Cu")
		(net 401)
	)
	(segment
		(start 173.690561 123.856501)
		(end 183.405001 123.856501)
		(width 0.114)
		(layer "In7.Cu")
		(net 401)
	)
	(segment
		(start 194.600001 124.400001)
		(end 193.676423 124.400001)
		(width 0.1)
		(layer "In7.Cu")
		(net 401)
	)
	(segment
		(start 159.951501 110.946501)
		(end 159.951501 110.61673)
		(width 0.114)
		(layer "In7.Cu")
		(net 401)
	)
	(segment
		(start 164.017767 116.617767)
		(end 164.017767 116.635046)
		(width 0.114)
		(layer "In7.Cu")
		(net 401)
	)
	(arc
		(start 164.224267 121.575735)
		(mid 164.078249 121.636217)
		(end 164.017767 121.782235)
		(width 0.114)
		(layer "In7.Cu")
		(net 401)
	)
	(arc
		(start 165.161267 113.332235)
		(mid 165.024047 113.663515)
		(end 164.692767 113.800735)
		(width 0.114)
		(layer "In7.Cu")
		(net 401)
	)
	(arc
		(start 165.461267 115.917767)
		(mid 165.316724 116.266724)
		(end 164.967767 116.411267)
		(width 0.114)
		(layer "In7.Cu")
		(net 401)
	)
	(arc
		(start 166.056501 124.256501)
		(mid 166.184841 124.203341)
		(end 166.238001 124.075001)
		(width 0.114)
		(layer "In7.Cu")
		(net 401)
	)
	(arc
		(start 162.874267 113.982235)
		(mid 162.927427 114.110575)
		(end 163.055767 114.163735)
		(width 0.114)
		(layer "In7.Cu")
		(net 401)
	)
	(arc
		(start 167.538001 123.449558)
		(mid 167.675221 123.118278)
		(end 168.006501 122.981058)
		(width 0.114)
		(layer "In7.Cu")
		(net 401)
	)
	(arc
		(start 164.692767 112.863735)
		(mid 165.024047 113.000955)
		(end 165.161267 113.332235)
		(width 0.114)
		(layer "In7.Cu")
		(net 401)
	)
	(arc
		(start 166.238001 123.449558)
		(mid 166.375221 123.118278)
		(end 166.706501 122.981058)
		(width 0.114)
		(layer "In7.Cu")
		(net 401)
	)
	(arc
		(start 167.011267 121.082235)
		(mid 166.866724 121.431192)
		(end 166.517767 121.575735)
		(width 0.114)
		(layer "In7.Cu")
		(net 401)
	)
	(arc
		(start 163.549267 114.163735)
		(mid 163.880547 114.300955)
		(end 164.017767 114.632235)
		(width 0.114)
		(layer "In7.Cu")
		(net 401)
	)
	(arc
		(start 167.356501 124.256501)
		(mid 167.484841 124.203341)
		(end 167.538001 124.075001)
		(width 0.114)
		(layer "In7.Cu")
		(net 401)
	)
	(arc
		(start 164.017767 120.382235)
		(mid 164.078249 120.528253)
		(end 164.224267 120.588735)
		(width 0.114)
		(layer "In7.Cu")
		(net 401)
	)
	(arc
		(start 166.517767 120.588735)
		(mid 166.866724 120.733278)
		(end 167.011267 121.082235)
		(width 0.114)
		(layer "In7.Cu")
		(net 401)
	)
	(arc
		(start 168.475001 124.075001)
		(mid 168.528161 124.203341)
		(end 168.656501 124.256501)
		(width 0.114)
		(layer "In7.Cu")
		(net 401)
	)
	(arc
		(start 168.006501 122.981058)
		(mid 168.337781 123.118278)
		(end 168.475001 123.449558)
		(width 0.114)
		(layer "In7.Cu")
		(net 401)
	)
	(arc
		(start 164.224267 116.411267)
		(mid 164.078249 116.471749)
		(end 164.017767 116.617767)
		(width 0.114)
		(layer "In7.Cu")
		(net 401)
	)
	(arc
		(start 164.967767 115.424267)
		(mid 165.316724 115.56881)
		(end 165.461267 115.917767)
		(width 0.114)
		(layer "In7.Cu")
		(net 401)
	)
	(arc
		(start 163.055767 113.800735)
		(mid 162.927427 113.853895)
		(end 162.874267 113.982235)
		(width 0.114)
		(layer "In7.Cu")
		(net 401)
	)
	(arc
		(start 167.175001 124.075001)
		(mid 167.228161 124.203341)
		(end 167.356501 124.256501)
		(width 0.114)
		(layer "In7.Cu")
		(net 401)
	)
	(arc
		(start 164.017767 115.217767)
		(mid 164.078249 115.363785)
		(end 164.224267 115.424267)
		(width 0.114)
		(layer "In7.Cu")
		(net 401)
	)
	(arc
		(start 164.017767 112.682235)
		(mid 164.070927 112.810575)
		(end 164.199267 112.863735)
		(width 0.114)
		(layer "In7.Cu")
		(net 401)
	)
	(arc
		(start 166.706501 122.981058)
		(mid 167.037781 123.118278)
		(end 167.175001 123.449558)
		(width 0.114)
		(layer "In7.Cu")
		(net 401)
	)
	(segment
		(start 210.91 154.195)
		(end 210.94 154.225)
		(width 0.184)
		(layer "F.Cu")
		(net 402)
	)
	(segment
		(start 197.5 141.5)
		(end 197 142)
		(width 0.256)
		(layer "F.Cu")
		(net 402)
	)
	(segment
		(start 210.94 154.225)
		(end 211.9 154.225)
		(width 0.184)
		(layer "F.Cu")
		(net 402)
	)
	(via
		(at 197 142)
		(size 0.45)
		(drill 0.2)
		(layers "F.Cu" "B.Cu")
		(net 402)
	)
	(via
		(at 212.31 154.63)
		(size 0.45)
		(drill 0.2)
		(layers "F.Cu" "B.Cu")
		(net 402)
	)
	(segment
		(start 196.7 145.8)
		(end 196.8 145.7)
		(width 0.1)
		(layer "In7.Cu")
		(net 402)
	)
	(segment
		(start 211.9 155.04)
		(end 211.9 159.2)
		(width 0.1)
		(layer "In7.Cu")
		(net 402)
	)
	(segment
		(start 205.5 159.6)
		(end 196.7 150.8)
		(width 0.1)
		(layer "In7.Cu")
		(net 402)
	)
	(segment
		(start 196.6 142.4)
		(end 197 142)
		(width 0.1)
		(layer "In7.Cu")
		(net 402)
	)
	(segment
		(start 211.5 159.6)
		(end 205.5 159.6)
		(width 0.1)
		(layer "In7.Cu")
		(net 402)
	)
	(segment
		(start 196.6 144.3)
		(end 196.6 142.4)
		(width 0.1)
		(layer "In7.Cu")
		(net 402)
	)
	(segment
		(start 196.7 150.8)
		(end 196.7 145.8)
		(width 0.1)
		(layer "In7.Cu")
		(net 402)
	)
	(segment
		(start 196.8 145.7)
		(end 196.8 144.5)
		(width 0.1)
		(layer "In7.Cu")
		(net 402)
	)
	(segment
		(start 211.9 159.2)
		(end 211.5 159.6)
		(width 0.1)
		(layer "In7.Cu")
		(net 402)
	)
	(segment
		(start 212.31 154.63)
		(end 211.9 155.04)
		(width 0.1)
		(layer "In7.Cu")
		(net 402)
	)
	(segment
		(start 196.8 144.5)
		(end 196.6 144.3)
		(width 0.1)
		(layer "In7.Cu")
		(net 402)
	)
	(segment
		(start 224.54 120.5)
		(end 224.54 122.24)
		(width 0.1)
		(layer "F.Cu")
		(net 403)
	)
	(segment
		(start 203.5 129.5)
		(end 204 129)
		(width 0.256)
		(layer "F.Cu")
		(net 403)
	)
	(segment
		(start 224.54 122.24)
		(end 225 122.7)
		(width 0.1)
		(layer "F.Cu")
		(net 403)
	)
	(via
		(at 204 129)
		(size 0.45)
		(drill 0.2)
		(layers "F.Cu" "B.Cu")
		(net 403)
	)
	(via
		(at 225 122.7)
		(size 0.45)
		(drill 0.2)
		(layers "F.Cu" "B.Cu")
		(net 403)
	)
	(segment
		(start 210.561827 125.625)
		(end 207.786827 128.4)
		(width 0.1)
		(layer "In7.Cu")
		(net 403)
	)
	(segment
		(start 204.6 128.4)
		(end 204 129)
		(width 0.1)
		(layer "In7.Cu")
		(net 403)
	)
	(segment
		(start 216.423632 125.625)
		(end 210.561827 125.625)
		(width 0.1)
		(layer "In7.Cu")
		(net 403)
	)
	(segment
		(start 219.548632 122.5)
		(end 216.423632 125.625)
		(width 0.1)
		(layer "In7.Cu")
		(net 403)
	)
	(segment
		(start 224.8 122.5)
		(end 219.548632 122.5)
		(width 0.1)
		(layer "In7.Cu")
		(net 403)
	)
	(segment
		(start 207.786827 128.4)
		(end 204.6 128.4)
		(width 0.1)
		(layer "In7.Cu")
		(net 403)
	)
	(segment
		(start 225 122.7)
		(end 224.8 122.5)
		(width 0.1)
		(layer "In7.Cu")
		(net 403)
	)
	(segment
		(start 214.435 165.985)
		(end 214.8 165.985)
		(width 0.1)
		(layer "F.Cu")
		(net 404)
	)
	(segment
		(start 214.4 165.95)
		(end 214.435 165.985)
		(width 0.1)
		(layer "F.Cu")
		(net 404)
	)
	(segment
		(start 213.9 165.885)
		(end 214 165.985)
		(width 0.1)
		(layer "F.Cu")
		(net 404)
	)
	(segment
		(start 214 165.985)
		(end 214.435 165.985)
		(width 0.1)
		(layer "F.Cu")
		(net 404)
	)
	(segment
		(start 214.8 165.985)
		(end 214.9 165.885)
		(width 0.1)
		(layer "F.Cu")
		(net 404)
	)
	(segment
		(start 196.5 142.5)
		(end 196 143)
		(width 0.256)
		(layer "F.Cu")
		(net 404)
	)
	(segment
		(start 214.4 165.525)
		(end 214.4 165.95)
		(width 0.1)
		(layer "F.Cu")
		(net 404)
	)
	(via
		(at 214.4 165.525)
		(size 0.45)
		(drill 0.2)
		(layers "F.Cu" "B.Cu")
		(net 404)
	)
	(via
		(at 196 143)
		(size 0.45)
		(drill 0.2)
		(layers "F.Cu" "B.Cu")
		(net 404)
	)
	(segment
		(start 195.5 143.5)
		(end 196 143)
		(width 0.1)
		(layer "In7.Cu")
		(net 404)
	)
	(segment
		(start 214 160.4)
		(end 205.3 160.4)
		(width 0.1)
		(layer "In7.Cu")
		(net 404)
	)
	(segment
		(start 214.400005 165.524995)
		(end 214.400005 160.800005)
		(width 0.1)
		(layer "In7.Cu")
		(net 404)
	)
	(segment
		(start 195.5 144.6)
		(end 195.5 143.5)
		(width 0.1)
		(layer "In7.Cu")
		(net 404)
	)
	(segment
		(start 195.8 150.9)
		(end 195.8 144.9)
		(width 0.1)
		(layer "In7.Cu")
		(net 404)
	)
	(segment
		(start 214.400005 160.800005)
		(end 214 160.4)
		(width 0.1)
		(layer "In7.Cu")
		(net 404)
	)
	(segment
		(start 205.3 160.4)
		(end 195.8 150.9)
		(width 0.1)
		(layer "In7.Cu")
		(net 404)
	)
	(segment
		(start 214.4 165.525)
		(end 214.400005 165.524995)
		(width 0.1)
		(layer "In7.Cu")
		(net 404)
	)
	(segment
		(start 195.8 144.9)
		(end 195.5 144.6)
		(width 0.1)
		(layer "In7.Cu")
		(net 404)
	)
	(segment
		(start 160.095001 110.757374)
		(end 160.095001 110.445001)
		(width 0.198)
		(layer "F.Cu")
		(net 405)
	)
	(segment
		(start 160.372001 111.034374)
		(end 160.095001 110.757374)
		(width 0.198)
		(layer "F.Cu")
		(net 405)
	)
	(segment
		(start 160.372001 111.080001)
		(end 160.372001 111.034374)
		(width 0.198)
		(layer "F.Cu")
		(net 405)
	)
	(segment
		(start 195.5 125.5)
		(end 195 125)
		(width 0.256)
		(layer "F.Cu")
		(net 405)
	)
	(via
		(at 195 125)
		(size 0.45)
		(drill 0.2)
		(layers "F.Cu" "B.Cu")
		(net 405)
	)
	(via
		(at 160.372001 111.080001)
		(size 0.45)
		(drill 0.2)
		(layers "F.Cu" "B.Cu")
		(net 405)
	)
	(segment
		(start 163.730767 121.782235)
		(end 163.730767 123.583707)
		(width 0.114)
		(layer "In7.Cu")
		(net 405)
	)
	(segment
		(start 160.38561 110.588501)
		(end 160.902501 110.588501)
		(width 0.114)
		(layer "In7.Cu")
		(net 405)
	)
	(segment
		(start 166.525001 124.075001)
		(end 166.525001 123.449558)
		(width 0.114)
		(layer "In7.Cu")
		(net 405)
	)
	(segment
		(start 164.199267 113.150735)
		(end 164.692767 113.150735)
		(width 0.114)
		(layer "In7.Cu")
		(net 405)
	)
	(segment
		(start 163.465039 110.588501)
		(end 163.730767 110.854229)
		(width 0.114)
		(layer "In7.Cu")
		(net 405)
	)
	(segment
		(start 163.055767 113.513735)
		(end 164.692767 113.513735)
		(width 0.114)
		(layer "In7.Cu")
		(net 405)
	)
	(segment
		(start 163.730767 114.632235)
		(end 163.730767 114.68528)
		(width 0.114)
		(layer "In7.Cu")
		(net 405)
	)
	(segment
		(start 163.730767 116.617767)
		(end 163.730767 116.635046)
		(width 0.114)
		(layer "In7.Cu")
		(net 405)
	)
	(segment
		(start 195.000001 125.000001)
		(end 194.600001 124.600001)
		(width 0.1)
		(layer "In7.Cu")
		(net 405)
	)
	(segment
		(start 166.888001 123.449558)
		(end 166.888001 124.075001)
		(width 0.114)
		(layer "In7.Cu")
		(net 405)
	)
	(segment
		(start 160.238501 110.73561)
		(end 160.38561 110.588501)
		(width 0.114)
		(layer "In7.Cu")
		(net 405)
	)
	(segment
		(start 193.093579 124.100001)
		(end 183.448501 124.100001)
		(width 0.1)
		(layer "In7.Cu")
		(net 405)
	)
	(segment
		(start 173.809441 124.143501)
		(end 183.405001 124.143501)
		(width 0.114)
		(layer "In7.Cu")
		(net 405)
	)
	(segment
		(start 163.730767 116.635046)
		(end 163.730767 120.382235)
		(width 0.114)
		(layer "In7.Cu")
		(net 405)
	)
	(segment
		(start 160.372001 111.080001)
		(end 160.238501 110.946501)
		(width 0.114)
		(layer "In7.Cu")
		(net 405)
	)
	(segment
		(start 163.730767 110.854229)
		(end 163.730767 112.682235)
		(width 0.114)
		(layer "In7.Cu")
		(net 405)
	)
	(segment
		(start 161.202501 110.888501)
		(end 161.202501 111.173807)
		(width 0.114)
		(layer "In7.Cu")
		(net 405)
	)
	(segment
		(start 163.730767 123.583707)
		(end 164.690561 124.543501)
		(width 0.114)
		(layer "In7.Cu")
		(net 405)
	)
	(segment
		(start 167.825001 124.075001)
		(end 167.825001 123.449558)
		(width 0.114)
		(layer "In7.Cu")
		(net 405)
	)
	(segment
		(start 164.224267 120.875735)
		(end 166.517767 120.875735)
		(width 0.114)
		(layer "In7.Cu")
		(net 405)
	)
	(segment
		(start 166.517767 121.288735)
		(end 164.224267 121.288735)
		(width 0.114)
		(layer "In7.Cu")
		(net 405)
	)
	(segment
		(start 162.102501 110.588501)
		(end 163.465039 110.588501)
		(width 0.114)
		(layer "In7.Cu")
		(net 405)
	)
	(segment
		(start 183.448501 124.100001)
		(end 183.405001 124.143501)
		(width 0.1)
		(layer "In7.Cu")
		(net 405)
	)
	(segment
		(start 168.188001 123.449558)
		(end 168.188001 124.075001)
		(width 0.114)
		(layer "In7.Cu")
		(net 405)
	)
	(segment
		(start 168.656501 124.543501)
		(end 173.409441 124.543501)
		(width 0.114)
		(layer "In7.Cu")
		(net 405)
	)
	(segment
		(start 194.600001 124.600001)
		(end 193.593579 124.600001)
		(width 0.1)
		(layer "In7.Cu")
		(net 405)
	)
	(segment
		(start 164.690561 124.543501)
		(end 166.056501 124.543501)
		(width 0.114)
		(layer "In7.Cu")
		(net 405)
	)
	(segment
		(start 161.802501 111.173807)
		(end 161.802501 110.888501)
		(width 0.114)
		(layer "In7.Cu")
		(net 405)
	)
	(segment
		(start 164.224267 115.711267)
		(end 164.967767 115.711267)
		(width 0.114)
		(layer "In7.Cu")
		(net 405)
	)
	(segment
		(start 193.593579 124.600001)
		(end 193.093579 124.100001)
		(width 0.1)
		(layer "In7.Cu")
		(net 405)
	)
	(segment
		(start 164.967767 116.124267)
		(end 164.224267 116.124267)
		(width 0.114)
		(layer "In7.Cu")
		(net 405)
	)
	(segment
		(start 160.238501 110.946501)
		(end 160.238501 110.73561)
		(width 0.114)
		(layer "In7.Cu")
		(net 405)
	)
	(segment
		(start 163.055767 114.450735)
		(end 163.549267 114.450735)
		(width 0.114)
		(layer "In7.Cu")
		(net 405)
	)
	(segment
		(start 163.730767 114.68528)
		(end 163.730767 115.217767)
		(width 0.114)
		(layer "In7.Cu")
		(net 405)
	)
	(segment
		(start 173.409441 124.543501)
		(end 173.809441 124.143501)
		(width 0.114)
		(layer "In7.Cu")
		(net 405)
	)
	(arc
		(start 163.730767 120.382235)
		(mid 163.87531 120.731192)
		(end 164.224267 120.875735)
		(width 0.114)
		(layer "In7.Cu")
		(net 405)
	)
	(arc
		(start 164.224267 121.288735)
		(mid 163.87531 121.433278)
		(end 163.730767 121.782235)
		(width 0.114)
		(layer "In7.Cu")
		(net 405)
	)
	(arc
		(start 162.587267 113.982235)
		(mid 162.724487 114.313515)
		(end 163.055767 114.450735)
		(width 0.114)
		(layer "In7.Cu")
		(net 405)
	)
	(arc
		(start 160.902501 110.588501)
		(mid 161.114633 110.676369)
		(end 161.202501 110.888501)
		(width 0.114)
		(layer "In7.Cu")
		(net 405)
	)
	(arc
		(start 164.692767 113.150735)
		(mid 164.821107 113.203895)
		(end 164.874267 113.332235)
		(width 0.114)
		(layer "In7.Cu")
		(net 405)
	)
	(arc
		(start 164.874267 113.332235)
		(mid 164.821107 113.460575)
		(end 164.692767 113.513735)
		(width 0.114)
		(layer "In7.Cu")
		(net 405)
	)
	(arc
		(start 164.967767 115.711267)
		(mid 165.113785 115.771749)
		(end 165.174267 115.917767)
		(width 0.114)
		(layer "In7.Cu")
		(net 405)
	)
	(arc
		(start 166.706501 123.268058)
		(mid 166.834841 123.321218)
		(end 166.888001 123.449558)
		(width 0.114)
		(layer "In7.Cu")
		(net 405)
	)
	(arc
		(start 166.724267 121.082235)
		(mid 166.663785 121.228253)
		(end 166.517767 121.288735)
		(width 0.114)
		(layer "In7.Cu")
		(net 405)
	)
	(arc
		(start 161.802501 110.888501)
		(mid 161.890369 110.676369)
		(end 162.102501 110.588501)
		(width 0.114)
		(layer "In7.Cu")
		(net 405)
	)
	(arc
		(start 161.502501 111.473807)
		(mid 161.714633 111.385939)
		(end 161.802501 111.173807)
		(width 0.114)
		(layer "In7.Cu")
		(net 405)
	)
	(arc
		(start 166.056501 124.543501)
		(mid 166.387781 124.406281)
		(end 166.525001 124.075001)
		(width 0.114)
		(layer "In7.Cu")
		(net 405)
	)
	(arc
		(start 166.888001 124.075001)
		(mid 167.025221 124.406281)
		(end 167.356501 124.543501)
		(width 0.114)
		(layer "In7.Cu")
		(net 405)
	)
	(arc
		(start 168.188001 124.075001)
		(mid 168.325221 124.406281)
		(end 168.656501 124.543501)
		(width 0.114)
		(layer "In7.Cu")
		(net 405)
	)
	(arc
		(start 164.224267 116.124267)
		(mid 163.87531 116.26881)
		(end 163.730767 116.617767)
		(width 0.114)
		(layer "In7.Cu")
		(net 405)
	)
	(arc
		(start 163.730767 112.682235)
		(mid 163.867987 113.013515)
		(end 164.199267 113.150735)
		(width 0.114)
		(layer "In7.Cu")
		(net 405)
	)
	(arc
		(start 167.825001 123.449558)
		(mid 167.878161 123.321218)
		(end 168.006501 123.268058)
		(width 0.114)
		(layer "In7.Cu")
		(net 405)
	)
	(arc
		(start 163.730767 115.217767)
		(mid 163.87531 115.566724)
		(end 164.224267 115.711267)
		(width 0.114)
		(layer "In7.Cu")
		(net 405)
	)
	(arc
		(start 161.202501 111.173807)
		(mid 161.290369 111.385939)
		(end 161.502501 111.473807)
		(width 0.114)
		(layer "In7.Cu")
		(net 405)
	)
	(arc
		(start 163.549267 114.450735)
		(mid 163.677607 114.503895)
		(end 163.730767 114.632235)
		(width 0.114)
		(layer "In7.Cu")
		(net 405)
	)
	(arc
		(start 163.055767 113.513735)
		(mid 162.724487 113.650955)
		(end 162.587267 113.982235)
		(width 0.114)
		(layer "In7.Cu")
		(net 405)
	)
	(arc
		(start 166.517767 120.875735)
		(mid 166.663785 120.936217)
		(end 166.724267 121.082235)
		(width 0.114)
		(layer "In7.Cu")
		(net 405)
	)
	(arc
		(start 167.356501 124.543501)
		(mid 167.687781 124.406281)
		(end 167.825001 124.075001)
		(width 0.114)
		(layer "In7.Cu")
		(net 405)
	)
	(arc
		(start 166.525001 123.449558)
		(mid 166.578161 123.321218)
		(end 166.706501 123.268058)
		(width 0.114)
		(layer "In7.Cu")
		(net 405)
	)
	(arc
		(start 165.174267 115.917767)
		(mid 165.113785 116.063785)
		(end 164.967767 116.124267)
		(width 0.114)
		(layer "In7.Cu")
		(net 405)
	)
	(arc
		(start 168.006501 123.268058)
		(mid 168.134841 123.321218)
		(end 168.188001 123.449558)
		(width 0.114)
		(layer "In7.Cu")
		(net 405)
	)
	(segment
		(start 210.9 165.885)
		(end 211 165.985)
		(width 0.1)
		(layer "F.Cu")
		(net 407)
	)
	(segment
		(start 211.400005 165.970005)
		(end 211.415 165.985)
		(width 0.1)
		(layer "F.Cu")
		(net 407)
	)
	(segment
		(start 197.5 140.5)
		(end 197.008178 140.991822)
		(width 0.256)
		(layer "F.Cu")
		(net 407)
	)
	(segment
		(start 211.400005 165.55)
		(end 211.400005 165.970005)
		(width 0.1)
		(layer "F.Cu")
		(net 407)
	)
	(segment
		(start 211.8 165.985)
		(end 211.9 165.885)
		(width 0.1)
		(layer "F.Cu")
		(net 407)
	)
	(segment
		(start 197.008178 140.991822)
		(end 197.008178 141.019902)
		(width 0.256)
		(layer "F.Cu")
		(net 407)
	)
	(segment
		(start 211 165.985)
		(end 211.415 165.985)
		(width 0.1)
		(layer "F.Cu")
		(net 407)
	)
	(segment
		(start 211.415 165.985)
		(end 211.8 165.985)
		(width 0.1)
		(layer "F.Cu")
		(net 407)
	)
	(via
		(at 211.400005 165.55)
		(size 0.45)
		(drill 0.2)
		(layers "F.Cu" "B.Cu")
		(net 407)
	)
	(via
		(at 197.008178 141.019902)
		(size 0.45)
		(drill 0.2)
		(layers "F.Cu" "B.Cu")
		(net 407)
	)
	(segment
		(start 195 151.05)
		(end 205.175 161.225)
		(width 0.1)
		(layer "In7.Cu")
		(net 407)
	)
	(segment
		(start 211.400005 161.725005)
		(end 211.400005 165.55)
		(width 0.1)
		(layer "In7.Cu")
		(net 407)
	)
	(segment
		(start 210.9 161.225)
		(end 211.400005 161.725005)
		(width 0.1)
		(layer "In7.Cu")
		(net 407)
	)
	(segment
		(start 197.008178 141.019902)
		(end 195 143.02808)
		(width 0.1)
		(layer "In7.Cu")
		(net 407)
	)
	(segment
		(start 205.175 161.225)
		(end 210.9 161.225)
		(width 0.1)
		(layer "In7.Cu")
		(net 407)
	)
	(segment
		(start 195 143.02808)
		(end 195 151.05)
		(width 0.1)
		(layer "In7.Cu")
		(net 407)
	)
	(segment
		(start 213.4 154.7)
		(end 213.4 154.3)
		(width 0.1)
		(layer "F.Cu")
		(net 408)
	)
	(segment
		(start 214.815 154.28)
		(end 214.88 154.215)
		(width 0.184)
		(layer "F.Cu")
		(net 408)
	)
	(segment
		(start 212.88 154.215)
		(end 212.945 154.28)
		(width 0.184)
		(layer "F.Cu")
		(net 408)
	)
	(segment
		(start 196.5 143.5)
		(end 196 144)
		(width 0.256)
		(layer "F.Cu")
		(net 408)
	)
	(segment
		(start 213.38 154.28)
		(end 214.815 154.28)
		(width 0.184)
		(layer "F.Cu")
		(net 408)
	)
	(segment
		(start 213.4 154.3)
		(end 213.38 154.28)
		(width 0.1)
		(layer "F.Cu")
		(net 408)
	)
	(segment
		(start 212.945 154.28)
		(end 213.38 154.28)
		(width 0.184)
		(layer "F.Cu")
		(net 408)
	)
	(via
		(at 213.4 154.7)
		(size 0.45)
		(drill 0.2)
		(layers "F.Cu" "B.Cu")
		(net 408)
	)
	(via
		(at 196 144)
		(size 0.45)
		(drill 0.2)
		(layers "F.Cu" "B.Cu")
		(net 408)
	)
	(segment
		(start 196.3 145.7)
		(end 196.3 150.9)
		(width 0.1)
		(layer "In7.Cu")
		(net 408)
	)
	(segment
		(start 196.6 144.6)
		(end 196.6 145.4)
		(width 0.1)
		(layer "In7.Cu")
		(net 408)
	)
	(segment
		(start 213.399957 154.700043)
		(end 213.4 154.7)
		(width 0.1)
		(layer "In7.Cu")
		(net 408)
	)
	(segment
		(start 196 144)
		(end 196.6 144.6)
		(width 0.1)
		(layer "In7.Cu")
		(net 408)
	)
	(segment
		(start 196.3 150.9)
		(end 205.4 160)
		(width 0.1)
		(layer "In7.Cu")
		(net 408)
	)
	(segment
		(start 213.399957 159.500043)
		(end 213.399957 154.700043)
		(width 0.1)
		(layer "In7.Cu")
		(net 408)
	)
	(segment
		(start 212.9 160)
		(end 213.399957 159.500043)
		(width 0.1)
		(layer "In7.Cu")
		(net 408)
	)
	(segment
		(start 205.4 160)
		(end 212.9 160)
		(width 0.1)
		(layer "In7.Cu")
		(net 408)
	)
	(segment
		(start 196.6 145.4)
		(end 196.3 145.7)
		(width 0.1)
		(layer "In7.Cu")
		(net 408)
	)
	(segment
		(start 200.5 119.5)
		(end 200 120)
		(width 0.256)
		(layer "F.Cu")
		(net 409)
	)
	(segment
		(start 158.825001 108.993804)
		(end 158.825001 109.175001)
		(width 0.16)
		(layer "F.Cu")
		(net 409)
	)
	(segment
		(start 159.146804 108.672001)
		(end 158.825001 108.993804)
		(width 0.16)
		(layer "F.Cu")
		(net 409)
	)
	(segment
		(start 159.315002 108.672002)
		(end 159.146804 108.672001)
		(width 0.16)
		(layer "F.Cu")
		(net 409)
	)
	(segment
		(start 159.315002 108.672002)
		(end 159.460001 108.817001)
		(width 0.16)
		(layer "F.Cu")
		(net 409)
	)
	(via
		(at 200 120)
		(size 0.45)
		(drill 0.2)
		(layers "F.Cu" "B.Cu")
		(net 409)
	)
	(via
		(at 159.460001 108.817001)
		(size 0.45)
		(drill 0.2)
		(layers "F.Cu" "B.Cu")
		(net 409)
	)
	(segment
		(start 199.771423 118.600001)
		(end 204.158579 118.600001)
		(width 0.1)
		(layer "In5.Cu")
		(net 409)
	)
	(segment
		(start 157.215001 128.472001)
		(end 156.102392 128.472001)
		(width 0.114)
		(layer "In5.Cu")
		(net 409)
	)
	(segment
		(start 159.326501 108.683501)
		(end 158.749441 108.683501)
		(width 0.114)
		(layer "In5.Cu")
		(net 409)
	)
	(segment
		(start 157.683501 130.330561)
		(end 158.207941 130.855001)
		(width 0.114)
		(layer "In5.Cu")
		(net 409)
	)
	(segment
		(start 199.600001 119.600001)
		(end 199.600001 118.771423)
		(width 0.1)
		(layer "In5.Cu")
		(net 409)
	)
	(segment
		(start 158.37778 113.150501)
		(end 157.808501 113.150501)
		(width 0.114)
		(layer "In5.Cu")
		(net 409)
	)
	(segment
		(start 199.600001 118.771423)
		(end 199.771423 118.600001)
		(width 0.1)
		(layer "In5.Cu")
		(net 409)
	)
	(segment
		(start 158.37778 113.650501)
		(end 157.808501 113.650501)
		(width 0.114)
		(layer "In5.Cu")
		(net 409)
	)
	(segment
		(start 204.400001 130.183579)
		(end 204.183579 130.400001)
		(width 0.1)
		(layer "In5.Cu")
		(net 409)
	)
	(segment
		(start 157.683501 113.775501)
		(end 157.683501 125.596501)
		(width 0.114)
		(layer "In5.Cu")
		(net 409)
	)
	(segment
		(start 157.808501 113.400501)
		(end 158.37778 113.400501)
		(width 0.114)
		(layer "In5.Cu")
		(net 409)
	)
	(segment
		(start 157.683501 109.749441)
		(end 157.683501 112.775501)
		(width 0.114)
		(layer "In5.Cu")
		(net 409)
	)
	(segment
		(start 183.455001 130.900001)
		(end 183.410001 130.855001)
		(width 0.1)
		(layer "In5.Cu")
		(net 409)
	)
	(segment
		(start 158.749441 108.683501)
		(end 157.683501 109.749441)
		(width 0.114)
		(layer "In5.Cu")
		(net 409)
	)
	(segment
		(start 158.207941 130.855001)
		(end 177.791501 130.855001)
		(width 0.114)
		(layer "In5.Cu")
		(net 409)
	)
	(segment
		(start 157.808501 112.900501)
		(end 158.37778 112.900501)
		(width 0.114)
		(layer "In5.Cu")
		(net 409)
	)
	(segment
		(start 155.821501 126.428001)
		(end 157.215001 126.428001)
		(width 0.114)
		(layer "In5.Cu")
		(net 409)
	)
	(segment
		(start 159.460001 108.817001)
		(end 159.326501 108.683501)
		(width 0.114)
		(layer "In5.Cu")
		(net 409)
	)
	(segment
		(start 200.000001 120.000001)
		(end 199.600001 119.600001)
		(width 0.1)
		(layer "In5.Cu")
		(net 409)
	)
	(segment
		(start 157.683501 126.896501)
		(end 157.683501 128.003501)
		(width 0.114)
		(layer "In5.Cu")
		(net 409)
	)
	(segment
		(start 193.533579 130.400001)
		(end 193.033579 130.900001)
		(width 0.1)
		(layer "In5.Cu")
		(net 409)
	)
	(segment
		(start 204.183579 130.400001)
		(end 193.533579 130.400001)
		(width 0.1)
		(layer "In5.Cu")
		(net 409)
	)
	(segment
		(start 204.400001 118.841423)
		(end 204.400001 130.183579)
		(width 0.1)
		(layer "In5.Cu")
		(net 409)
	)
	(segment
		(start 183.410001 130.855001)
		(end 177.791501 130.855001)
		(width 0.1)
		(layer "In5.Cu")
		(net 409)
	)
	(segment
		(start 204.158579 118.600001)
		(end 204.400001 118.841423)
		(width 0.1)
		(layer "In5.Cu")
		(net 409)
	)
	(segment
		(start 157.683501 129.303501)
		(end 157.683501 130.330561)
		(width 0.114)
		(layer "In5.Cu")
		(net 409)
	)
	(segment
		(start 156.102392 128.835001)
		(end 157.215001 128.835001)
		(width 0.114)
		(layer "In5.Cu")
		(net 409)
	)
	(segment
		(start 157.215001 126.065001)
		(end 155.821501 126.065001)
		(width 0.114)
		(layer "In5.Cu")
		(net 409)
	)
	(segment
		(start 193.033579 130.900001)
		(end 183.455001 130.900001)
		(width 0.1)
		(layer "In5.Cu")
		(net 409)
	)
	(arc
		(start 155.640001 126.246501)
		(mid 155.693161 126.374841)
		(end 155.821501 126.428001)
		(width 0.114)
		(layer "In5.Cu")
		(net 409)
	)
	(arc
		(start 158.37778 113.400501)
		(mid 158.466168 113.437113)
		(end 158.50278 113.525501)
		(width 0.114)
		(layer "In5.Cu")
		(net 409)
	)
	(arc
		(start 157.215001 128.835001)
		(mid 157.546281 128.972221)
		(end 157.683501 129.303501)
		(width 0.114)
		(layer "In5.Cu")
		(net 409)
	)
	(arc
		(start 157.808501 113.150501)
		(mid 157.720113 113.187113)
		(end 157.683501 113.275501)
		(width 0.114)
		(layer "In5.Cu")
		(net 409)
	)
	(arc
		(start 155.920892 128.653501)
		(mid 155.974052 128.781841)
		(end 156.102392 128.835001)
		(width 0.114)
		(layer "In5.Cu")
		(net 409)
	)
	(arc
		(start 156.102392 128.472001)
		(mid 155.974052 128.525161)
		(end 155.920892 128.653501)
		(width 0.114)
		(layer "In5.Cu")
		(net 409)
	)
	(arc
		(start 155.821501 126.065001)
		(mid 155.693161 126.118161)
		(end 155.640001 126.246501)
		(width 0.114)
		(layer "In5.Cu")
		(net 409)
	)
	(arc
		(start 158.50278 113.025501)
		(mid 158.466168 113.113889)
		(end 158.37778 113.150501)
		(width 0.114)
		(layer "In5.Cu")
		(net 409)
	)
	(arc
		(start 157.808501 113.650501)
		(mid 157.720113 113.687113)
		(end 157.683501 113.775501)
		(width 0.114)
		(layer "In5.Cu")
		(net 409)
	)
	(arc
		(start 157.683501 113.275501)
		(mid 157.720113 113.363889)
		(end 157.808501 113.400501)
		(width 0.114)
		(layer "In5.Cu")
		(net 409)
	)
	(arc
		(start 158.37778 112.900501)
		(mid 158.466168 112.937113)
		(end 158.50278 113.025501)
		(width 0.114)
		(layer "In5.Cu")
		(net 409)
	)
	(arc
		(start 158.50278 113.525501)
		(mid 158.466168 113.613889)
		(end 158.37778 113.650501)
		(width 0.114)
		(layer "In5.Cu")
		(net 409)
	)
	(arc
		(start 157.683501 125.596501)
		(mid 157.546281 125.927781)
		(end 157.215001 126.065001)
		(width 0.114)
		(layer "In5.Cu")
		(net 409)
	)
	(arc
		(start 157.215001 126.428001)
		(mid 157.546281 126.565221)
		(end 157.683501 126.896501)
		(width 0.114)
		(layer "In5.Cu")
		(net 409)
	)
	(arc
		(start 157.683501 112.775501)
		(mid 157.720113 112.863889)
		(end 157.808501 112.900501)
		(width 0.114)
		(layer "In5.Cu")
		(net 409)
	)
	(arc
		(start 157.683501 128.003501)
		(mid 157.546281 128.334781)
		(end 157.215001 128.472001)
		(width 0.114)
		(layer "In5.Cu")
		(net 409)
	)
	(segment
		(start 216.025 155.725)
		(end 216.45 156.15)
		(width 0.184)
		(layer "F.Cu")
		(net 410)
	)
	(segment
		(start 216.025 154.025)
		(end 216.025 155.725)
		(width 0.184)
		(layer "F.Cu")
		(net 410)
	)
	(segment
		(start 216.45 156.15)
		(end 216.45 156.615)
		(width 0.184)
		(layer "F.Cu")
		(net 410)
	)
	(segment
		(start 197.5 143.5)
		(end 197 144)
		(width 0.256)
		(layer "F.Cu")
		(net 410)
	)
	(via
		(at 216.025 154.025)
		(size 0.45)
		(drill 0.2)
		(layers "F.Cu" "B.Cu")
		(net 410)
	)
	(via
		(at 197 144)
		(size 0.45)
		(drill 0.2)
		(layers "F.Cu" "B.Cu")
		(net 410)
	)
	(segment
		(start 210.475 154.425)
		(end 210.475 158.925)
		(width 0.1)
		(layer "In7.Cu")
		(net 410)
	)
	(segment
		(start 216.025 154.025)
		(end 215.7 153.7)
		(width 0.1)
		(layer "In7.Cu")
		(net 410)
	)
	(segment
		(start 205.6 159.2)
		(end 197.1 150.7)
		(width 0.1)
		(layer "In7.Cu")
		(net 410)
	)
	(segment
		(start 197.1 144.1)
		(end 197 144)
		(width 0.1)
		(layer "In7.Cu")
		(net 410)
	)
	(segment
		(start 210.2 159.2)
		(end 205.6 159.2)
		(width 0.1)
		(layer "In7.Cu")
		(net 410)
	)
	(segment
		(start 197.1 150.7)
		(end 197.1 144.1)
		(width 0.1)
		(layer "In7.Cu")
		(net 410)
	)
	(segment
		(start 210.475 158.925)
		(end 210.2 159.2)
		(width 0.1)
		(layer "In7.Cu")
		(net 410)
	)
	(segment
		(start 215.7 153.7)
		(end 211.2 153.7)
		(width 0.1)
		(layer "In7.Cu")
		(net 410)
	)
	(segment
		(start 211.2 153.7)
		(end 210.475 154.425)
		(width 0.1)
		(layer "In7.Cu")
		(net 410)
	)
	(segment
		(start 196.45 145.55)
		(end 195.718623 145.55)
		(width 0.256)
		(layer "F.Cu")
		(net 411)
	)
	(segment
		(start 195.718623 145.55)
		(end 195.379409 145.210786)
		(width 0.256)
		(layer "F.Cu")
		(net 411)
	)
	(segment
		(start 197.5 144.5)
		(end 196.45 145.55)
		(width 0.256)
		(layer "F.Cu")
		(net 411)
	)
	(segment
		(start 212.488594 165.505206)
		(end 212.868388 165.885)
		(width 0.1)
		(layer "F.Cu")
		(net 411)
	)
	(segment
		(start 212.868388 165.885)
		(end 212.9 165.885)
		(width 0.1)
		(layer "F.Cu")
		(net 411)
	)
	(via
		(at 195.379409 145.210786)
		(size 0.45)
		(drill 0.2)
		(layers "F.Cu" "B.Cu")
		(net 411)
	)
	(via
		(at 212.488594 165.505206)
		(size 0.45)
		(drill 0.2)
		(layers "F.Cu" "B.Cu")
		(net 411)
	)
	(segment
		(start 211.95 160.75)
		(end 205.15 160.75)
		(width 0.1)
		(layer "In7.Cu")
		(net 411)
	)
	(segment
		(start 212.45 161.25)
		(end 211.95 160.75)
		(width 0.1)
		(layer "In7.Cu")
		(net 411)
	)
	(segment
		(start 195.379409 150.979409)
		(end 195.379409 145.210786)
		(width 0.1)
		(layer "In7.Cu")
		(net 411)
	)
	(segment
		(start 205.15 160.75)
		(end 195.379409 150.979409)
		(width 0.1)
		(layer "In7.Cu")
		(net 411)
	)
	(segment
		(start 212.488594 165.505206)
		(end 212.45 165.466612)
		(width 0.1)
		(layer "In7.Cu")
		(net 411)
	)
	(segment
		(start 212.45 165.466612)
		(end 212.45 161.25)
		(width 0.1)
		(layer "In7.Cu")
		(net 411)
	)
	(segment
		(start 158.825001 107.905001)
		(end 158.825001 108.086198)
		(width 0.16)
		(layer "F.Cu")
		(net 413)
	)
	(segment
		(start 199.5 120.5)
		(end 199 120)
		(width 0.256)
		(layer "F.Cu")
		(net 413)
	)
	(segment
		(start 158.825001 108.086198)
		(end 159.146804 108.408001)
		(width 0.16)
		(layer "F.Cu")
		(net 413)
	)
	(segment
		(start 159.315002 108.408)
		(end 159.460001 108.263001)
		(width 0.16)
		(layer "F.Cu")
		(net 413)
	)
	(segment
		(start 159.315002 108.408)
		(end 159.146804 108.408001)
		(width 0.16)
		(layer "F.Cu")
		(net 413)
	)
	(via
		(at 199 120)
		(size 0.45)
		(drill 0.2)
		(layers "F.Cu" "B.Cu")
		(net 413)
	)
	(via
		(at 159.460001 108.263001)
		(size 0.45)
		(drill 0.2)
		(layers "F.Cu" "B.Cu")
		(net 413)
	)
	(segment
		(start 157.215001 128.185001)
		(end 156.102392 128.185001)
		(width 0.114)
		(layer "In5.Cu")
		(net 413)
	)
	(segment
		(start 199.400001 118.688579)
		(end 199.688579 118.400001)
		(width 0.1)
		(layer "In5.Cu")
		(net 413)
	)
	(segment
		(start 204.241423 118.400001)
		(end 204.600001 118.758579)
		(width 0.1)
		(layer "In5.Cu")
		(net 413)
	)
	(segment
		(start 199.688579 118.400001)
		(end 204.241423 118.400001)
		(width 0.1)
		(layer "In5.Cu")
		(net 413)
	)
	(segment
		(start 157.396501 129.303501)
		(end 157.396501 130.449441)
		(width 0.114)
		(layer "In5.Cu")
		(net 413)
	)
	(segment
		(start 157.396501 126.896501)
		(end 157.396501 128.003501)
		(width 0.114)
		(layer "In5.Cu")
		(net 413)
	)
	(segment
		(start 204.600001 118.758579)
		(end 204.600001 130.266423)
		(width 0.1)
		(layer "In5.Cu")
		(net 413)
	)
	(segment
		(start 157.396501 109.630561)
		(end 157.396501 125.596501)
		(width 0.114)
		(layer "In5.Cu")
		(net 413)
	)
	(segment
		(start 159.326501 108.396501)
		(end 158.630561 108.396501)
		(width 0.114)
		(layer "In5.Cu")
		(net 413)
	)
	(segment
		(start 193.616423 130.600001)
		(end 193.116423 131.100001)
		(width 0.1)
		(layer "In5.Cu")
		(net 413)
	)
	(segment
		(start 204.266423 130.600001)
		(end 193.616423 130.600001)
		(width 0.1)
		(layer "In5.Cu")
		(net 413)
	)
	(segment
		(start 204.600001 130.266423)
		(end 204.266423 130.600001)
		(width 0.1)
		(layer "In5.Cu")
		(net 413)
	)
	(segment
		(start 158.089061 131.142001)
		(end 177.791501 131.142001)
		(width 0.114)
		(layer "In5.Cu")
		(net 413)
	)
	(segment
		(start 157.215001 125.778001)
		(end 155.821501 125.778001)
		(width 0.114)
		(layer "In5.Cu")
		(net 413)
	)
	(segment
		(start 156.102392 129.122001)
		(end 157.215001 129.122001)
		(width 0.114)
		(layer "In5.Cu")
		(net 413)
	)
	(segment
		(start 199.000001 120.000001)
		(end 199.400001 119.600001)
		(width 0.1)
		(layer "In5.Cu")
		(net 413)
	)
	(segment
		(start 157.396501 130.449441)
		(end 158.089061 131.142001)
		(width 0.114)
		(layer "In5.Cu")
		(net 413)
	)
	(segment
		(start 183.410001 131.142001)
		(end 177.791501 131.142001)
		(width 0.1)
		(layer "In5.Cu")
		(net 413)
	)
	(segment
		(start 159.460001 108.263001)
		(end 159.326501 108.396501)
		(width 0.114)
		(layer "In5.Cu")
		(net 413)
	)
	(segment
		(start 183.452001 131.100001)
		(end 183.410001 131.142001)
		(width 0.1)
		(layer "In5.Cu")
		(net 413)
	)
	(segment
		(start 155.821501 126.715001)
		(end 157.215001 126.715001)
		(width 0.114)
		(layer "In5.Cu")
		(net 413)
	)
	(segment
		(start 193.116423 131.100001)
		(end 183.452001 131.100001)
		(width 0.1)
		(layer "In5.Cu")
		(net 413)
	)
	(segment
		(start 199.400001 119.600001)
		(end 199.400001 118.688579)
		(width 0.1)
		(layer "In5.Cu")
		(net 413)
	)
	(segment
		(start 158.630561 108.396501)
		(end 157.396501 109.630561)
		(width 0.114)
		(layer "In5.Cu")
		(net 413)
	)
	(arc
		(start 157.215001 126.715001)
		(mid 157.343341 126.768161)
		(end 157.396501 126.896501)
		(width 0.114)
		(layer "In5.Cu")
		(net 413)
	)
	(arc
		(start 156.102392 128.185001)
		(mid 155.771112 128.322221)
		(end 155.633892 128.653501)
		(width 0.114)
		(layer "In5.Cu")
		(net 413)
	)
	(arc
		(start 157.215001 129.122001)
		(mid 157.343341 129.175161)
		(end 157.396501 129.303501)
		(width 0.114)
		(layer "In5.Cu")
		(net 413)
	)
	(arc
		(start 155.353001 126.246501)
		(mid 155.490221 126.577781)
		(end 155.821501 126.715001)
		(width 0.114)
		(layer "In5.Cu")
		(net 413)
	)
	(arc
		(start 157.396501 128.003501)
		(mid 157.343341 128.131841)
		(end 157.215001 128.185001)
		(width 0.114)
		(layer "In5.Cu")
		(net 413)
	)
	(arc
		(start 155.633892 128.653501)
		(mid 155.771112 128.984781)
		(end 156.102392 129.122001)
		(width 0.114)
		(layer "In5.Cu")
		(net 413)
	)
	(arc
		(start 157.396501 125.596501)
		(mid 157.343341 125.724841)
		(end 157.215001 125.778001)
		(width 0.114)
		(layer "In5.Cu")
		(net 413)
	)
	(arc
		(start 155.821501 125.778001)
		(mid 155.490221 125.915221)
		(end 155.353001 126.246501)
		(width 0.114)
		(layer "In5.Cu")
		(net 413)
	)
	(segment
		(start 200.5 124.5)
		(end 201 124)
		(width 0.256)
		(layer "F.Cu")
		(net 414)
	)
	(segment
		(start 160.416804 107.402001)
		(end 160.095001 107.723804)
		(width 0.16)
		(layer "F.Cu")
		(net 414)
	)
	(segment
		(start 160.095001 107.723804)
		(end 160.095001 107.905001)
		(width 0.16)
		(layer "F.Cu")
		(net 414)
	)
	(segment
		(start 160.585002 107.402002)
		(end 160.416804 107.402001)
		(width 0.16)
		(layer "F.Cu")
		(net 414)
	)
	(segment
		(start 160.585002 107.402002)
		(end 160.730001 107.547001)
		(width 0.16)
		(layer "F.Cu")
		(net 414)
	)
	(via
		(at 201 124)
		(size 0.45)
		(drill 0.2)
		(layers "F.Cu" "B.Cu")
		(net 414)
	)
	(via
		(at 160.730001 107.547001)
		(size 0.45)
		(drill 0.2)
		(layers "F.Cu" "B.Cu")
		(net 414)
	)
	(segment
		(start 201.000001 124.000001)
		(end 200.600001 124.400001)
		(width 0.1)
		(layer "In5.Cu")
		(net 414)
	)
	(segment
		(start 193.391423 127.400001)
		(end 192.891423 126.900001)
		(width 0.1)
		(layer "In5.Cu")
		(net 414)
	)
	(segment
		(start 199.733579 124.400001)
		(end 199.400001 124.733579)
		(width 0.1)
		(layer "In5.Cu")
		(net 414)
	)
	(segment
		(start 162.845142 116.570001)
		(end 164.86486 116.570001)
		(width 0.114)
		(layer "In5.Cu")
		(net 414)
	)
	(segment
		(start 164.048501 124.355561)
		(end 166.549441 126.856501)
		(width 0.114)
		(layer "In5.Cu")
		(net 414)
	)
	(segment
		(start 183.448501 126.900001)
		(end 183.405001 126.856501)
		(width 0.1)
		(layer "In5.Cu")
		(net 414)
	)
	(segment
		(start 163.422441 106.076501)
		(end 164.048501 106.702561)
		(width 0.114)
		(layer "In5.Cu")
		(net 414)
	)
	(segment
		(start 164.330001 115.433001)
		(end 164.86486 115.433001)
		(width 0.114)
		(layer "In5.Cu")
		(net 414)
	)
	(segment
		(start 159.907633 106.491818)
		(end 160.32295 106.076501)
		(width 0.114)
		(layer "In5.Cu")
		(net 414)
	)
	(segment
		(start 199.400001 124.733579)
		(end 199.400001 127.183579)
		(width 0.1)
		(layer "In5.Cu")
		(net 414)
	)
	(segment
		(start 164.048501 106.702561)
		(end 164.048501 115.151501)
		(width 0.114)
		(layer "In5.Cu")
		(net 414)
	)
	(segment
		(start 199.183579 127.400001)
		(end 193.391423 127.400001)
		(width 0.1)
		(layer "In5.Cu")
		(net 414)
	)
	(segment
		(start 159.907633 107.105573)
		(end 159.907633 106.491818)
		(width 0.114)
		(layer "In5.Cu")
		(net 414)
	)
	(segment
		(start 164.048501 117.715578)
		(end 164.048501 124.355561)
		(width 0.114)
		(layer "In5.Cu")
		(net 414)
	)
	(segment
		(start 164.048501 117.701501)
		(end 164.048501 117.715578)
		(width 0.114)
		(layer "In5.Cu")
		(net 414)
	)
	(segment
		(start 192.891423 126.900001)
		(end 183.448501 126.900001)
		(width 0.1)
		(layer "In5.Cu")
		(net 414)
	)
	(segment
		(start 199.400001 127.183579)
		(end 199.183579 127.400001)
		(width 0.1)
		(layer "In5.Cu")
		(net 414)
	)
	(segment
		(start 160.215561 107.413501)
		(end 159.907633 107.105573)
		(width 0.114)
		(layer "In5.Cu")
		(net 414)
	)
	(segment
		(start 160.730001 107.547001)
		(end 160.596501 107.413501)
		(width 0.114)
		(layer "In5.Cu")
		(net 414)
	)
	(segment
		(start 162.845142 117.133001)
		(end 163.480001 117.133001)
		(width 0.114)
		(layer "In5.Cu")
		(net 414)
	)
	(segment
		(start 160.32295 106.076501)
		(end 163.422441 106.076501)
		(width 0.114)
		(layer "In5.Cu")
		(net 414)
	)
	(segment
		(start 160.596501 107.413501)
		(end 160.215561 107.413501)
		(width 0.114)
		(layer "In5.Cu")
		(net 414)
	)
	(segment
		(start 166.549441 126.856501)
		(end 183.405001 126.856501)
		(width 0.114)
		(layer "In5.Cu")
		(net 414)
	)
	(segment
		(start 200.600001 124.400001)
		(end 199.733579 124.400001)
		(width 0.1)
		(layer "In5.Cu")
		(net 414)
	)
	(arc
		(start 163.480001 117.133001)
		(mid 163.881991 117.299511)
		(end 164.048501 117.701501)
		(width 0.114)
		(layer "In5.Cu")
		(net 414)
	)
	(arc
		(start 165.43336 116.001501)
		(mid 165.26685 116.403491)
		(end 164.86486 116.570001)
		(width 0.114)
		(layer "In5.Cu")
		(net 414)
	)
	(arc
		(start 162.563642 116.851501)
		(mid 162.646091 117.050552)
		(end 162.845142 117.133001)
		(width 0.114)
		(layer "In5.Cu")
		(net 414)
	)
	(arc
		(start 164.86486 115.433001)
		(mid 165.26685 115.599511)
		(end 165.43336 116.001501)
		(width 0.114)
		(layer "In5.Cu")
		(net 414)
	)
	(arc
		(start 162.845142 116.570001)
		(mid 162.646091 116.65245)
		(end 162.563642 116.851501)
		(width 0.114)
		(layer "In5.Cu")
		(net 414)
	)
	(arc
		(start 164.048501 115.151501)
		(mid 164.13095 115.350552)
		(end 164.330001 115.433001)
		(width 0.114)
		(layer "In5.Cu")
		(net 414)
	)
	(segment
		(start 197.015747 139.984253)
		(end 197.003669 139.984253)
		(width 0.256)
		(layer "F.Cu")
		(net 416)
	)
	(segment
		(start 197.5 139.5)
		(end 197.015747 139.984253)
		(width 0.256)
		(layer "F.Cu")
		(net 416)
	)
	(via
		(at 197.003669 139.984253)
		(size 0.45)
		(drill 0.2)
		(layers "F.Cu" "B.Cu")
		(net 416)
	)
	(via
		(at 249.075 130.3)
		(size 0.45)
		(drill 0.2)
		(layers "F.Cu" "B.Cu")
		(net 416)
	)
	(segment
		(start 250.515 129.7)
		(end 249.485 129.7)
		(width 0.184)
		(layer "B.Cu")
		(net 416)
	)
	(segment
		(start 249.485 129.7)
		(end 249.485 129.89)
		(width 0.184)
		(layer "B.Cu")
		(net 416)
	)
	(segment
		(start 249.485 129.89)
		(end 249.075 130.3)
		(width 0.184)
		(layer "B.Cu")
		(net 416)
	)
	(segment
		(start 245.775 132.225)
		(end 245.775 131.2)
		(width 0.1)
		(layer "In5.Cu")
		(net 416)
	)
	(segment
		(start 239.548526 135.8)
		(end 240.35 135.8)
		(width 0.1)
		(layer "In5.Cu")
		(net 416)
	)
	(segment
		(start 196.425 147.275)
		(end 196.425 152.55)
		(width 0.1)
		(layer "In5.Cu")
		(net 416)
	)
	(segment
		(start 198.3 140.6)
		(end 198.4 140.7)
		(width 0.1)
		(layer "In5.Cu")
		(net 416)
	)
	(segment
		(start 240.35 135.8)
		(end 242.45 133.7)
		(width 0.1)
		(layer "In5.Cu")
		(net 416)
	)
	(segment
		(start 197.084253 139.984253)
		(end 197.7 140.6)
		(width 0.1)
		(layer "In5.Cu")
		(net 416)
	)
	(segment
		(start 244.3 133.7)
		(end 245.775 132.225)
		(width 0.1)
		(layer "In5.Cu")
		(net 416)
	)
	(segment
		(start 211.2 161)
		(end 220.9 151.3)
		(width 0.1)
		(layer "In5.Cu")
		(net 416)
	)
	(segment
		(start 196.425 152.55)
		(end 199.725 155.85)
		(width 0.1)
		(layer "In5.Cu")
		(net 416)
	)
	(segment
		(start 199.725 155.85)
		(end 199.725 160.6)
		(width 0.1)
		(layer "In5.Cu")
		(net 416)
	)
	(segment
		(start 198.4 140.7)
		(end 198.4 145.3)
		(width 0.1)
		(layer "In5.Cu")
		(net 416)
	)
	(segment
		(start 220.9 151.3)
		(end 224.048526 151.3)
		(width 0.1)
		(layer "In5.Cu")
		(net 416)
	)
	(segment
		(start 224.048526 151.3)
		(end 239.548526 135.8)
		(width 0.1)
		(layer "In5.Cu")
		(net 416)
	)
	(segment
		(start 242.45 133.7)
		(end 244.3 133.7)
		(width 0.1)
		(layer "In5.Cu")
		(net 416)
	)
	(segment
		(start 197.7 140.6)
		(end 198.3 140.6)
		(width 0.1)
		(layer "In5.Cu")
		(net 416)
	)
	(segment
		(start 200.125 161)
		(end 211.2 161)
		(width 0.1)
		(layer "In5.Cu")
		(net 416)
	)
	(segment
		(start 246.675 130.3)
		(end 249.075 130.3)
		(width 0.1)
		(layer "In5.Cu")
		(net 416)
	)
	(segment
		(start 245.775 131.2)
		(end 246.675 130.3)
		(width 0.1)
		(layer "In5.Cu")
		(net 416)
	)
	(segment
		(start 198.4 145.3)
		(end 196.425 147.275)
		(width 0.1)
		(layer "In5.Cu")
		(net 416)
	)
	(segment
		(start 199.725 160.6)
		(end 200.125 161)
		(width 0.1)
		(layer "In5.Cu")
		(net 416)
	)
	(segment
		(start 197.003669 139.984253)
		(end 197.084253 139.984253)
		(width 0.1)
		(layer "In5.Cu")
		(net 416)
	)
	(segment
		(start 214.025 115.95)
		(end 214.025 115.975)
		(width 0.256)
		(layer "F.Cu")
		(net 417)
	)
	(segment
		(start 236.06 111.95)
		(end 236.385 111.625)
		(width 0.201)
		(layer "F.Cu")
		(net 417)
	)
	(segment
		(start 236.025 111.95)
		(end 236.06 111.95)
		(width 0.201)
		(layer "F.Cu")
		(net 417)
	)
	(segment
		(start 236.41 110.6)
		(end 236.385 110.625)
		(width 0.1)
		(layer "F.Cu")
		(net 417)
	)
	(segment
		(start 236.385 110.625)
		(end 236.385 111.625)
		(width 0.1)
		(layer "F.Cu")
		(net 417)
	)
	(segment
		(start 214.025 115.975)
		(end 213.5 116.5)
		(width 0.256)
		(layer "F.Cu")
		(net 417)
	)
	(via
		(at 214.025 115.95)
		(size 0.45)
		(drill 0.2)
		(layers "F.Cu" "B.Cu")
		(net 417)
	)
	(via
		(at 236.025 111.95)
		(size 0.45)
		(drill 0.2)
		(layers "F.Cu" "B.Cu")
		(net 417)
	)
	(segment
		(start 235.2 114.1)
		(end 235.2 112.775)
		(width 0.1)
		(layer "In7.Cu")
		(net 417)
	)
	(segment
		(start 235.2 112.775)
		(end 236.025 111.95)
		(width 0.1)
		(layer "In7.Cu")
		(net 417)
	)
	(segment
		(start 214.025 115.95)
		(end 214.125 115.85)
		(width 0.1)
		(layer "In7.Cu")
		(net 417)
	)
	(segment
		(start 214.125 115.85)
		(end 233.45 115.85)
		(width 0.1)
		(layer "In7.Cu")
		(net 417)
	)
	(segment
		(start 233.45 115.85)
		(end 235.2 114.1)
		(width 0.1)
		(layer "In7.Cu")
		(net 417)
	)
	(segment
		(start 160.095001 106.635001)
		(end 160.095001 106.816198)
		(width 0.16)
		(layer "F.Cu")
		(net 418)
	)
	(segment
		(start 160.585002 107.138)
		(end 160.730001 106.993001)
		(width 0.16)
		(layer "F.Cu")
		(net 418)
	)
	(segment
		(start 160.095001 106.816198)
		(end 160.416804 107.138001)
		(width 0.16)
		(layer "F.Cu")
		(net 418)
	)
	(segment
		(start 200.5 125.5)
		(end 201 125)
		(width 0.256)
		(layer "F.Cu")
		(net 418)
	)
	(segment
		(start 160.585002 107.138)
		(end 160.416804 107.138001)
		(width 0.16)
		(layer "F.Cu")
		(net 418)
	)
	(via
		(at 160.730001 106.993001)
		(size 0.45)
		(drill 0.2)
		(layers "F.Cu" "B.Cu")
		(net 418)
	)
	(via
		(at 201 125)
		(size 0.45)
		(drill 0.2)
		(layers "F.Cu" "B.Cu")
		(net 418)
	)
	(segment
		(start 162.845142 116.283001)
		(end 164.86486 116.283001)
		(width 0.114)
		(layer "In5.Cu")
		(net 418)
	)
	(segment
		(start 193.308579 127.600001)
		(end 192.808579 127.100001)
		(width 0.1)
		(layer "In5.Cu")
		(net 418)
	)
	(segment
		(start 199.816423 124.600001)
		(end 199.600001 124.816423)
		(width 0.1)
		(layer "In5.Cu")
		(net 418)
	)
	(segment
		(start 183.448501 127.100001)
		(end 183.405001 127.143501)
		(width 0.1)
		(layer "In5.Cu")
		(net 418)
	)
	(segment
		(start 160.44183 106.363501)
		(end 163.303561 106.363501)
		(width 0.114)
		(layer "In5.Cu")
		(net 418)
	)
	(segment
		(start 166.430561 127.143501)
		(end 183.405001 127.143501)
		(width 0.114)
		(layer "In5.Cu")
		(net 418)
	)
	(segment
		(start 192.808579 127.100001)
		(end 183.448501 127.100001)
		(width 0.1)
		(layer "In5.Cu")
		(net 418)
	)
	(segment
		(start 163.761501 124.474441)
		(end 166.430561 127.143501)
		(width 0.114)
		(layer "In5.Cu")
		(net 418)
	)
	(segment
		(start 199.600001 124.816423)
		(end 199.600001 127.266423)
		(width 0.1)
		(layer "In5.Cu")
		(net 418)
	)
	(segment
		(start 162.845142 117.420001)
		(end 163.480001 117.420001)
		(width 0.114)
		(layer "In5.Cu")
		(net 418)
	)
	(segment
		(start 160.334441 107.126501)
		(end 160.194633 106.986693)
		(width 0.114)
		(layer "In5.Cu")
		(net 418)
	)
	(segment
		(start 163.761501 106.821441)
		(end 163.761501 115.151501)
		(width 0.114)
		(layer "In5.Cu")
		(net 418)
	)
	(segment
		(start 200.600001 124.600001)
		(end 199.816423 124.600001)
		(width 0.1)
		(layer "In5.Cu")
		(net 418)
	)
	(segment
		(start 199.600001 127.266423)
		(end 199.266423 127.600001)
		(width 0.1)
		(layer "In5.Cu")
		(net 418)
	)
	(segment
		(start 164.330001 115.720001)
		(end 164.86486 115.720001)
		(width 0.114)
		(layer "In5.Cu")
		(net 418)
	)
	(segment
		(start 199.266423 127.600001)
		(end 193.308579 127.600001)
		(width 0.1)
		(layer "In5.Cu")
		(net 418)
	)
	(segment
		(start 163.761501 117.715578)
		(end 163.761501 124.474441)
		(width 0.114)
		(layer "In5.Cu")
		(net 418)
	)
	(segment
		(start 160.596501 107.126501)
		(end 160.334441 107.126501)
		(width 0.114)
		(layer "In5.Cu")
		(net 418)
	)
	(segment
		(start 160.194633 106.986693)
		(end 160.194633 106.610698)
		(width 0.114)
		(layer "In5.Cu")
		(net 418)
	)
	(segment
		(start 160.194633 106.610698)
		(end 160.44183 106.363501)
		(width 0.114)
		(layer "In5.Cu")
		(net 418)
	)
	(segment
		(start 160.730001 106.993001)
		(end 160.596501 107.126501)
		(width 0.114)
		(layer "In5.Cu")
		(net 418)
	)
	(segment
		(start 163.761501 117.701501)
		(end 163.761501 117.715578)
		(width 0.114)
		(layer "In5.Cu")
		(net 418)
	)
	(segment
		(start 201.000001 125.000001)
		(end 200.600001 124.600001)
		(width 0.1)
		(layer "In5.Cu")
		(net 418)
	)
	(segment
		(start 163.303561 106.363501)
		(end 163.761501 106.821441)
		(width 0.114)
		(layer "In5.Cu")
		(net 418)
	)
	(arc
		(start 163.761501 115.151501)
		(mid 163.928011 115.553491)
		(end 164.330001 115.720001)
		(width 0.114)
		(layer "In5.Cu")
		(net 418)
	)
	(arc
		(start 164.86486 115.720001)
		(mid 165.063911 115.80245)
		(end 165.14636 116.001501)
		(width 0.114)
		(layer "In5.Cu")
		(net 418)
	)
	(arc
		(start 162.276642 116.851501)
		(mid 162.443152 117.253491)
		(end 162.845142 117.420001)
		(width 0.114)
		(layer "In5.Cu")
		(net 418)
	)
	(arc
		(start 165.14636 116.001501)
		(mid 165.063911 116.200552)
		(end 164.86486 116.283001)
		(width 0.114)
		(layer "In5.Cu")
		(net 418)
	)
	(arc
		(start 163.480001 117.420001)
		(mid 163.679052 117.50245)
		(end 163.761501 117.701501)
		(width 0.114)
		(layer "In5.Cu")
		(net 418)
	)
	(arc
		(start 162.845142 116.283001)
		(mid 162.443152 116.449511)
		(end 162.276642 116.851501)
		(width 0.114)
		(layer "In5.Cu")
		(net 418)
	)
	(segment
		(start 224.1 116.75)
		(end 224.1 115.715)
		(width 0.1)
		(layer "F.Cu")
		(net 419)
	)
	(segment
		(start 210.5 122.5)
		(end 211 122)
		(width 0.256)
		(layer "F.Cu")
		(net 419)
	)
	(segment
		(start 224.1 115.715)
		(end 224.615 115.2)
		(width 0.1)
		(layer "F.Cu")
		(net 419)
	)
	(segment
		(start 224.615 114.2)
		(end 224.615 115.2)
		(width 0.1)
		(layer "F.Cu")
		(net 419)
	)
	(via
		(at 224.1 116.75)
		(size 0.45)
		(drill 0.2)
		(layers "F.Cu" "B.Cu")
		(net 419)
	)
	(via
		(at 211 122)
		(size 0.45)
		(drill 0.2)
		(layers "F.Cu" "B.Cu")
		(net 419)
	)
	(segment
		(start 211.575 121.425)
		(end 211 122)
		(width 0.1)
		(layer "In7.Cu")
		(net 419)
	)
	(segment
		(start 223.7 117.15)
		(end 224.1 116.75)
		(width 0.1)
		(layer "In7.Cu")
		(net 419)
	)
	(segment
		(start 220.05 117.15)
		(end 223.7 117.15)
		(width 0.1)
		(layer "In7.Cu")
		(net 419)
	)
	(segment
		(start 215.775 121.425)
		(end 211.575 121.425)
		(width 0.1)
		(layer "In7.Cu")
		(net 419)
	)
	(segment
		(start 220.05 117.15)
		(end 215.775 121.425)
		(width 0.1)
		(layer "In7.Cu")
		(net 419)
	)
	(segment
		(start 213.5 117.5)
		(end 214 117)
		(width 0.256)
		(layer "F.Cu")
		(net 420)
	)
	(segment
		(start 224.615 111.2)
		(end 224.615 112.2)
		(width 0.1)
		(layer "F.Cu")
		(net 420)
	)
	(segment
		(start 223.05 116.25)
		(end 223.05 113.765)
		(width 0.1)
		(layer "F.Cu")
		(net 420)
	)
	(segment
		(start 223.05 113.765)
		(end 224.615 112.2)
		(width 0.1)
		(layer "F.Cu")
		(net 420)
	)
	(via
		(at 223.05 116.25)
		(size 0.45)
		(drill 0.2)
		(layers "F.Cu" "B.Cu")
		(net 420)
	)
	(via
		(at 214 117)
		(size 0.45)
		(drill 0.2)
		(layers "F.Cu" "B.Cu")
		(net 420)
	)
	(segment
		(start 214 117)
		(end 214.9 116.1)
		(width 0.1)
		(layer "In7.Cu")
		(net 420)
	)
	(segment
		(start 214.9 116.1)
		(end 222.9 116.1)
		(width 0.1)
		(layer "In7.Cu")
		(net 420)
	)
	(segment
		(start 222.9 116.1)
		(end 223.05 116.25)
		(width 0.1)
		(layer "In7.Cu")
		(net 420)
	)
	(segment
		(start 156.606804 104.862001)
		(end 156.285001 105.183804)
		(width 0.16)
		(layer "F.Cu")
		(net 423)
	)
	(segment
		(start 156.775002 104.862002)
		(end 156.606804 104.862001)
		(width 0.16)
		(layer "F.Cu")
		(net 423)
	)
	(segment
		(start 156.775002 104.862002)
		(end 156.920001 105.007001)
		(width 0.16)
		(layer "F.Cu")
		(net 423)
	)
	(segment
		(start 156.285001 105.183804)
		(end 156.285001 105.365001)
		(width 0.16)
		(layer "F.Cu")
		(net 423)
	)
	(segment
		(start 197.5 118.5)
		(end 197 118)
		(width 0.256)
		(layer "F.Cu")
		(net 423)
	)
	(via
		(at 197 118)
		(size 0.45)
		(drill 0.2)
		(layers "F.Cu" "B.Cu")
		(net 423)
	)
	(via
		(at 156.920001 105.007001)
		(size 0.45)
		(drill 0.2)
		(layers "F.Cu" "B.Cu")
		(net 423)
	)
	(segment
		(start 197.000001 118.000001)
		(end 196.600001 117.600001)
		(width 0.1)
		(layer "In7.Cu")
		(net 423)
	)
	(segment
		(start 155.465001 95.518001)
		(end 157.058501 95.518001)
		(width 0.114)
		(layer "In7.Cu")
		(net 423)
	)
	(segment
		(start 166.556001 90.956501)
		(end 166.556001 91.100001)
		(width 0.114)
		(layer "In7.Cu")
		(net 423)
	)
	(segment
		(start 167.049501 90.513001)
		(end 166.999501 90.513001)
		(width 0.114)
		(layer "In7.Cu")
		(net 423)
	)
	(segment
		(start 155.365001 100.714001)
		(end 155.808501 100.714001)
		(width 0.114)
		(layer "In7.Cu")
		(net 423)
	)
	(segment
		(start 154.871501 96.724501)
		(end 154.871501 97.635501)
		(width 0.114)
		(layer "In7.Cu")
		(net 423)
	)
	(segment
		(start 169.156001 90.956501)
		(end 169.156001 91.100001)
		(width 0.114)
		(layer "In7.Cu")
		(net 423)
	)
	(segment
		(start 155.470561 90.926501)
		(end 154.871501 91.525561)
		(width 0.114)
		(layer "In7.Cu")
		(net 423)
	)
	(segment
		(start 157.058501 96.131001)
		(end 155.465001 96.131001)
		(width 0.114)
		(layer "In7.Cu")
		(net 423)
	)
	(segment
		(start 168.793001 91.100001)
		(end 168.793001 90.956501)
		(width 0.114)
		(layer "In7.Cu")
		(net 423)
	)
	(segment
		(start 163.799501 91.256501)
		(end 158.809441 91.256501)
		(width 0.114)
		(layer "In7.Cu")
		(net 423)
	)
	(segment
		(start 167.699501 91.256501)
		(end 167.649501 91.256501)
		(width 0.114)
		(layer "In7.Cu")
		(net 423)
	)
	(segment
		(start 195.600001 116.188579)
		(end 195.600001 113.448501)
		(width 0.1)
		(layer "In7.Cu")
		(net 423)
	)
	(segment
		(start 167.493001 91.100001)
		(end 167.493001 90.956501)
		(width 0.114)
		(layer "In7.Cu")
		(net 423)
	)
	(segment
		(start 154.871501 99.035501)
		(end 154.871501 99.102045)
		(width 0.114)
		(layer "In7.Cu")
		(net 423)
	)
	(segment
		(start 195.643501 112.670561)
		(end 174.229441 91.256501)
		(width 0.114)
		(layer "In7.Cu")
		(net 423)
	)
	(segment
		(start 155.365001 98.129001)
		(end 160.076678 98.129001)
		(width 0.114)
		(layer "In7.Cu")
		(net 423)
	)
	(segment
		(start 196.600001 116.748579)
		(end 196.251423 116.400001)
		(width 0.1)
		(layer "In7.Cu")
		(net 423)
	)
	(segment
		(start 158.809441 91.256501)
		(end 158.479441 90.926501)
		(width 0.114)
		(layer "In7.Cu")
		(net 423)
	)
	(segment
		(start 167.856001 90.956501)
		(end 167.856001 91.100001)
		(width 0.114)
		(layer "In7.Cu")
		(net 423)
	)
	(segment
		(start 155.808501 101.127001)
		(end 155.365001 101.127001)
		(width 0.114)
		(layer "In7.Cu")
		(net 423)
	)
	(segment
		(start 168.349501 90.513001)
		(end 168.299501 90.513001)
		(width 0.114)
		(layer "In7.Cu")
		(net 423)
	)
	(segment
		(start 154.871501 104.099441)
		(end 155.645561 104.873501)
		(width 0.114)
		(layer "In7.Cu")
		(net 423)
	)
	(segment
		(start 154.871501 99.102045)
		(end 154.871501 100.220501)
		(width 0.114)
		(layer "In7.Cu")
		(net 423)
	)
	(segment
		(start 170.093001 91.100001)
		(end 170.093001 90.956501)
		(width 0.114)
		(layer "In7.Cu")
		(net 423)
	)
	(segment
		(start 174.229441 91.256501)
		(end 170.249501 91.256501)
		(width 0.114)
		(layer "In7.Cu")
		(net 423)
	)
	(segment
		(start 154.871501 91.525561)
		(end 154.871501 92.363501)
		(width 0.114)
		(layer "In7.Cu")
		(net 423)
	)
	(segment
		(start 169.649501 90.513001)
		(end 169.599501 90.513001)
		(width 0.114)
		(layer "In7.Cu")
		(net 423)
	)
	(segment
		(start 155.390001 92.882001)
		(end 155.783501 92.882001)
		(width 0.114)
		(layer "In7.Cu")
		(net 423)
	)
	(segment
		(start 158.479441 90.926501)
		(end 155.470561 90.926501)
		(width 0.114)
		(layer "In7.Cu")
		(net 423)
	)
	(segment
		(start 195.643501 113.405001)
		(end 195.643501 112.670561)
		(width 0.114)
		(layer "In7.Cu")
		(net 423)
	)
	(segment
		(start 164.449501 90.513001)
		(end 164.399501 90.513001)
		(width 0.114)
		(layer "In7.Cu")
		(net 423)
	)
	(segment
		(start 166.193001 91.100001)
		(end 166.193001 90.956501)
		(width 0.114)
		(layer "In7.Cu")
		(net 423)
	)
	(segment
		(start 195.600001 113.448501)
		(end 195.643501 113.405001)
		(width 0.1)
		(layer "In7.Cu")
		(net 423)
	)
	(segment
		(start 196.251423 116.400001)
		(end 195.811423 116.400001)
		(width 0.1)
		(layer "In7.Cu")
		(net 423)
	)
	(segment
		(start 155.645561 104.873501)
		(end 156.786501 104.873501)
		(width 0.114)
		(layer "In7.Cu")
		(net 423)
	)
	(segment
		(start 155.783501 93.345001)
		(end 155.390001 93.345001)
		(width 0.114)
		(layer "In7.Cu")
		(net 423)
	)
	(segment
		(start 164.893001 91.100001)
		(end 164.893001 90.956501)
		(width 0.114)
		(layer "In7.Cu")
		(net 423)
	)
	(segment
		(start 195.811423 116.400001)
		(end 195.600001 116.188579)
		(width 0.1)
		(layer "In7.Cu")
		(net 423)
	)
	(segment
		(start 154.871501 93.910207)
		(end 154.871501 94.924501)
		(width 0.114)
		(layer "In7.Cu")
		(net 423)
	)
	(segment
		(start 165.749501 90.513001)
		(end 165.699501 90.513001)
		(width 0.114)
		(layer "In7.Cu")
		(net 423)
	)
	(segment
		(start 163.956001 90.956501)
		(end 163.956001 91.100001)
		(width 0.114)
		(layer "In7.Cu")
		(net 423)
	)
	(segment
		(start 154.871501 93.863501)
		(end 154.871501 93.910207)
		(width 0.114)
		(layer "In7.Cu")
		(net 423)
	)
	(segment
		(start 165.099501 91.256501)
		(end 165.049501 91.256501)
		(width 0.114)
		(layer "In7.Cu")
		(net 423)
	)
	(segment
		(start 154.871501 101.620501)
		(end 154.871501 104.099441)
		(width 0.114)
		(layer "In7.Cu")
		(net 423)
	)
	(segment
		(start 166.399501 91.256501)
		(end 166.349501 91.256501)
		(width 0.114)
		(layer "In7.Cu")
		(net 423)
	)
	(segment
		(start 160.076678 98.542001)
		(end 155.365001 98.542001)
		(width 0.114)
		(layer "In7.Cu")
		(net 423)
	)
	(segment
		(start 165.256001 90.956501)
		(end 165.256001 91.100001)
		(width 0.114)
		(layer "In7.Cu")
		(net 423)
	)
	(segment
		(start 156.786501 104.873501)
		(end 156.920001 105.007001)
		(width 0.114)
		(layer "In7.Cu")
		(net 423)
	)
	(segment
		(start 168.999501 91.256501)
		(end 168.949501 91.256501)
		(width 0.114)
		(layer "In7.Cu")
		(net 423)
	)
	(segment
		(start 196.600001 117.600001)
		(end 196.600001 116.748579)
		(width 0.1)
		(layer "In7.Cu")
		(net 423)
	)
	(arc
		(start 154.871501 94.924501)
		(mid 155.045333 95.344169)
		(end 155.465001 95.518001)
		(width 0.114)
		(layer "In7.Cu")
		(net 423)
	)
	(arc
		(start 167.649501 91.256501)
		(mid 167.538839 91.210663)
		(end 167.493001 91.100001)
		(width 0.114)
		(layer "In7.Cu")
		(net 423)
	)
	(arc
		(start 160.076678 98.129001)
		(mid 160.222696 98.189483)
		(end 160.283178 98.335501)
		(width 0.114)
		(layer "In7.Cu")
		(net 423)
	)
	(arc
		(start 167.493001 90.956501)
		(mid 167.363103 90.642899)
		(end 167.049501 90.513001)
		(width 0.114)
		(layer "In7.Cu")
		(net 423)
	)
	(arc
		(start 168.299501 90.513001)
		(mid 167.985899 90.642899)
		(end 167.856001 90.956501)
		(width 0.114)
		(layer "In7.Cu")
		(net 423)
	)
	(arc
		(start 157.058501 95.518001)
		(mid 157.275229 95.607773)
		(end 157.365001 95.824501)
		(width 0.114)
		(layer "In7.Cu")
		(net 423)
	)
	(arc
		(start 167.856001 91.100001)
		(mid 167.810163 91.210663)
		(end 167.699501 91.256501)
		(width 0.114)
		(layer "In7.Cu")
		(net 423)
	)
	(arc
		(start 168.793001 90.956501)
		(mid 168.663103 90.642899)
		(end 168.349501 90.513001)
		(width 0.114)
		(layer "In7.Cu")
		(net 423)
	)
	(arc
		(start 155.465001 96.131001)
		(mid 155.045333 96.304833)
		(end 154.871501 96.724501)
		(width 0.114)
		(layer "In7.Cu")
		(net 423)
	)
	(arc
		(start 154.871501 97.635501)
		(mid 155.016044 97.984458)
		(end 155.365001 98.129001)
		(width 0.114)
		(layer "In7.Cu")
		(net 423)
	)
	(arc
		(start 155.390001 93.345001)
		(mid 155.023366 93.496866)
		(end 154.871501 93.863501)
		(width 0.114)
		(layer "In7.Cu")
		(net 423)
	)
	(arc
		(start 165.699501 90.513001)
		(mid 165.385899 90.642899)
		(end 165.256001 90.956501)
		(width 0.114)
		(layer "In7.Cu")
		(net 423)
	)
	(arc
		(start 155.783501 92.882001)
		(mid 155.947196 92.949806)
		(end 156.015001 93.113501)
		(width 0.114)
		(layer "In7.Cu")
		(net 423)
	)
	(arc
		(start 156.015001 93.113501)
		(mid 155.947196 93.277196)
		(end 155.783501 93.345001)
		(width 0.114)
		(layer "In7.Cu")
		(net 423)
	)
	(arc
		(start 155.808501 100.714001)
		(mid 155.954519 100.774483)
		(end 156.015001 100.920501)
		(width 0.114)
		(layer "In7.Cu")
		(net 423)
	)
	(arc
		(start 170.249501 91.256501)
		(mid 170.138839 91.210663)
		(end 170.093001 91.100001)
		(width 0.114)
		(layer "In7.Cu")
		(net 423)
	)
	(arc
		(start 168.949501 91.256501)
		(mid 168.838839 91.210663)
		(end 168.793001 91.100001)
		(width 0.114)
		(layer "In7.Cu")
		(net 423)
	)
	(arc
		(start 165.256001 91.100001)
		(mid 165.210163 91.210663)
		(end 165.099501 91.256501)
		(width 0.114)
		(layer "In7.Cu")
		(net 423)
	)
	(arc
		(start 160.283178 98.335501)
		(mid 160.222696 98.481519)
		(end 160.076678 98.542001)
		(width 0.114)
		(layer "In7.Cu")
		(net 423)
	)
	(arc
		(start 156.015001 100.920501)
		(mid 155.954519 101.066519)
		(end 155.808501 101.127001)
		(width 0.114)
		(layer "In7.Cu")
		(net 423)
	)
	(arc
		(start 163.956001 91.100001)
		(mid 163.910163 91.210663)
		(end 163.799501 91.256501)
		(width 0.114)
		(layer "In7.Cu")
		(net 423)
	)
	(arc
		(start 164.399501 90.513001)
		(mid 164.085899 90.642899)
		(end 163.956001 90.956501)
		(width 0.114)
		(layer "In7.Cu")
		(net 423)
	)
	(arc
		(start 166.349501 91.256501)
		(mid 166.238839 91.210663)
		(end 166.193001 91.100001)
		(width 0.114)
		(layer "In7.Cu")
		(net 423)
	)
	(arc
		(start 166.193001 90.956501)
		(mid 166.063103 90.642899)
		(end 165.749501 90.513001)
		(width 0.114)
		(layer "In7.Cu")
		(net 423)
	)
	(arc
		(start 169.156001 91.100001)
		(mid 169.110163 91.210663)
		(end 168.999501 91.256501)
		(width 0.114)
		(layer "In7.Cu")
		(net 423)
	)
	(arc
		(start 157.365001 95.824501)
		(mid 157.275229 96.041229)
		(end 157.058501 96.131001)
		(width 0.114)
		(layer "In7.Cu")
		(net 423)
	)
	(arc
		(start 155.365001 98.542001)
		(mid 155.016044 98.686544)
		(end 154.871501 99.035501)
		(width 0.114)
		(layer "In7.Cu")
		(net 423)
	)
	(arc
		(start 166.999501 90.513001)
		(mid 166.685899 90.642899)
		(end 166.556001 90.956501)
		(width 0.114)
		(layer "In7.Cu")
		(net 423)
	)
	(arc
		(start 169.599501 90.513001)
		(mid 169.285899 90.642899)
		(end 169.156001 90.956501)
		(width 0.114)
		(layer "In7.Cu")
		(net 423)
	)
	(arc
		(start 155.365001 101.127001)
		(mid 155.016044 101.271544)
		(end 154.871501 101.620501)
		(width 0.114)
		(layer "In7.Cu")
		(net 423)
	)
	(arc
		(start 154.871501 92.363501)
		(mid 155.023366 92.730136)
		(end 155.390001 92.882001)
		(width 0.114)
		(layer "In7.Cu")
		(net 423)
	)
	(arc
		(start 164.893001 90.956501)
		(mid 164.763103 90.642899)
		(end 164.449501 90.513001)
		(width 0.114)
		(layer "In7.Cu")
		(net 423)
	)
	(arc
		(start 154.871501 100.220501)
		(mid 155.016044 100.569458)
		(end 155.365001 100.714001)
		(width 0.114)
		(layer "In7.Cu")
		(net 423)
	)
	(arc
		(start 165.049501 91.256501)
		(mid 164.938839 91.210663)
		(end 164.893001 91.100001)
		(width 0.114)
		(layer "In7.Cu")
		(net 423)
	)
	(arc
		(start 166.556001 91.100001)
		(mid 166.510163 91.210663)
		(end 166.399501 91.256501)
		(width 0.114)
		(layer "In7.Cu")
		(net 423)
	)
	(arc
		(start 170.093001 90.956501)
		(mid 169.963103 90.642899)
		(end 169.649501 90.513001)
		(width 0.114)
		(layer "In7.Cu")
		(net 423)
	)
	(segment
		(start 196.5 118.5)
		(end 196 118)
		(width 0.256)
		(layer "F.Cu")
		(net 424)
	)
	(segment
		(start 156.775002 104.598)
		(end 156.920001 104.453001)
		(width 0.16)
		(layer "F.Cu")
		(net 424)
	)
	(segment
		(start 156.285001 104.276198)
		(end 156.606804 104.598001)
		(width 0.16)
		(layer "F.Cu")
		(net 424)
	)
	(segment
		(start 156.775002 104.598)
		(end 156.606804 104.598001)
		(width 0.16)
		(layer "F.Cu")
		(net 424)
	)
	(segment
		(start 156.285001 104.095001)
		(end 156.285001 104.276198)
		(width 0.16)
		(layer "F.Cu")
		(net 424)
	)
	(via
		(at 196 118)
		(size 0.45)
		(drill 0.2)
		(layers "F.Cu" "B.Cu")
		(net 424)
	)
	(via
		(at 156.920001 104.453001)
		(size 0.45)
		(drill 0.2)
		(layers "F.Cu" "B.Cu")
		(net 424)
	)
	(segment
		(start 155.158501 99.035501)
		(end 155.158501 99.102045)
		(width 0.114)
		(layer "In7.Cu")
		(net 424)
	)
	(segment
		(start 156.786501 104.586501)
		(end 156.920001 104.453001)
		(width 0.114)
		(layer "In7.Cu")
		(net 424)
	)
	(segment
		(start 155.158501 93.863501)
		(end 155.158501 93.910207)
		(width 0.114)
		(layer "In7.Cu")
		(net 424)
	)
	(segment
		(start 155.158501 103.700501)
		(end 155.158501 103.980561)
		(width 0.114)
		(layer "In7.Cu")
		(net 424)
	)
	(segment
		(start 165.099501 91.543501)
		(end 165.049501 91.543501)
		(width 0.114)
		(layer "In7.Cu")
		(net 424)
	)
	(segment
		(start 155.458501 102.800501)
		(end 155.858501 102.800501)
		(width 0.114)
		(layer "In7.Cu")
		(net 424)
	)
	(segment
		(start 155.858501 103.400501)
		(end 155.458501 103.400501)
		(width 0.114)
		(layer "In7.Cu")
		(net 424)
	)
	(segment
		(start 167.049501 90.800001)
		(end 166.999501 90.800001)
		(width 0.114)
		(layer "In7.Cu")
		(net 424)
	)
	(segment
		(start 174.110561 91.543501)
		(end 170.249501 91.543501)
		(width 0.114)
		(layer "In7.Cu")
		(net 424)
	)
	(segment
		(start 155.158501 101.620501)
		(end 155.158501 102.500501)
		(width 0.114)
		(layer "In7.Cu")
		(net 424)
	)
	(segment
		(start 158.690561 91.543501)
		(end 158.360561 91.213501)
		(width 0.114)
		(layer "In7.Cu")
		(net 424)
	)
	(segment
		(start 155.465001 95.231001)
		(end 157.058501 95.231001)
		(width 0.114)
		(layer "In7.Cu")
		(net 424)
	)
	(segment
		(start 168.999501 91.543501)
		(end 168.949501 91.543501)
		(width 0.114)
		(layer "In7.Cu")
		(net 424)
	)
	(segment
		(start 165.906001 91.100001)
		(end 165.906001 90.956501)
		(width 0.114)
		(layer "In7.Cu")
		(net 424)
	)
	(segment
		(start 167.206001 91.100001)
		(end 167.206001 90.956501)
		(width 0.114)
		(layer "In7.Cu")
		(net 424)
	)
	(segment
		(start 196.000001 118.000001)
		(end 196.400001 117.600001)
		(width 0.1)
		(layer "In7.Cu")
		(net 424)
	)
	(segment
		(start 157.058501 96.418001)
		(end 155.465001 96.418001)
		(width 0.114)
		(layer "In7.Cu")
		(net 424)
	)
	(segment
		(start 164.606001 91.100001)
		(end 164.606001 90.956501)
		(width 0.114)
		(layer "In7.Cu")
		(net 424)
	)
	(segment
		(start 155.158501 99.102045)
		(end 155.158501 100.220501)
		(width 0.114)
		(layer "In7.Cu")
		(net 424)
	)
	(segment
		(start 155.365001 100.427001)
		(end 155.808501 100.427001)
		(width 0.114)
		(layer "In7.Cu")
		(net 424)
	)
	(segment
		(start 164.449501 90.800001)
		(end 164.399501 90.800001)
		(width 0.114)
		(layer "In7.Cu")
		(net 424)
	)
	(segment
		(start 163.799501 91.543501)
		(end 158.690561 91.543501)
		(width 0.114)
		(layer "In7.Cu")
		(net 424)
	)
	(segment
		(start 168.143001 90.956501)
		(end 168.143001 91.100001)
		(width 0.114)
		(layer "In7.Cu")
		(net 424)
	)
	(segment
		(start 160.076678 98.829001)
		(end 155.365001 98.829001)
		(width 0.114)
		(layer "In7.Cu")
		(net 424)
	)
	(segment
		(start 155.783501 93.632001)
		(end 155.390001 93.632001)
		(width 0.114)
		(layer "In7.Cu")
		(net 424)
	)
	(segment
		(start 155.158501 96.724501)
		(end 155.158501 97.635501)
		(width 0.114)
		(layer "In7.Cu")
		(net 424)
	)
	(segment
		(start 195.356501 112.789441)
		(end 174.110561 91.543501)
		(width 0.114)
		(layer "In7.Cu")
		(net 424)
	)
	(segment
		(start 155.808501 101.414001)
		(end 155.365001 101.414001)
		(width 0.114)
		(layer "In7.Cu")
		(net 424)
	)
	(segment
		(start 169.649501 90.800001)
		(end 169.599501 90.800001)
		(width 0.114)
		(layer "In7.Cu")
		(net 424)
	)
	(segment
		(start 166.399501 91.543501)
		(end 166.349501 91.543501)
		(width 0.114)
		(layer "In7.Cu")
		(net 424)
	)
	(segment
		(start 168.506001 91.100001)
		(end 168.506001 90.956501)
		(width 0.114)
		(layer "In7.Cu")
		(net 424)
	)
	(segment
		(start 196.400001 116.831423)
		(end 196.168579 116.600001)
		(width 0.1)
		(layer "In7.Cu")
		(net 424)
	)
	(segment
		(start 165.749501 90.800001)
		(end 165.699501 90.800001)
		(width 0.114)
		(layer "In7.Cu")
		(net 424)
	)
	(segment
		(start 155.390001 92.595001)
		(end 155.783501 92.595001)
		(width 0.114)
		(layer "In7.Cu")
		(net 424)
	)
	(segment
		(start 155.764441 104.586501)
		(end 156.786501 104.586501)
		(width 0.114)
		(layer "In7.Cu")
		(net 424)
	)
	(segment
		(start 169.806001 91.100001)
		(end 169.806001 90.956501)
		(width 0.114)
		(layer "In7.Cu")
		(net 424)
	)
	(segment
		(start 155.365001 97.842001)
		(end 160.076678 97.842001)
		(width 0.114)
		(layer "In7.Cu")
		(net 424)
	)
	(segment
		(start 155.158501 93.910207)
		(end 155.158501 94.924501)
		(width 0.114)
		(layer "In7.Cu")
		(net 424)
	)
	(segment
		(start 158.360561 91.213501)
		(end 155.589441 91.213501)
		(width 0.114)
		(layer "In7.Cu")
		(net 424)
	)
	(segment
		(start 167.699501 91.543501)
		(end 167.649501 91.543501)
		(width 0.114)
		(layer "In7.Cu")
		(net 424)
	)
	(segment
		(start 168.349501 90.800001)
		(end 168.299501 90.800001)
		(width 0.114)
		(layer "In7.Cu")
		(net 424)
	)
	(segment
		(start 155.158501 91.644441)
		(end 155.158501 92.363501)
		(width 0.114)
		(layer "In7.Cu")
		(net 424)
	)
	(segment
		(start 196.400001 117.600001)
		(end 196.400001 116.831423)
		(width 0.1)
		(layer "In7.Cu")
		(net 424)
	)
	(segment
		(start 195.728579 116.600001)
		(end 195.400001 116.271423)
		(width 0.1)
		(layer "In7.Cu")
		(net 424)
	)
	(segment
		(start 196.168579 116.600001)
		(end 195.728579 116.600001)
		(width 0.1)
		(layer "In7.Cu")
		(net 424)
	)
	(segment
		(start 155.589441 91.213501)
		(end 155.158501 91.644441)
		(width 0.114)
		(layer "In7.Cu")
		(net 424)
	)
	(segment
		(start 195.400001 113.448501)
		(end 195.356501 113.405001)
		(width 0.1)
		(layer "In7.Cu")
		(net 424)
	)
	(segment
		(start 164.243001 90.956501)
		(end 164.243001 91.100001)
		(width 0.114)
		(layer "In7.Cu")
		(net 424)
	)
	(segment
		(start 195.400001 116.271423)
		(end 195.400001 113.448501)
		(width 0.1)
		(layer "In7.Cu")
		(net 424)
	)
	(segment
		(start 166.843001 90.956501)
		(end 166.843001 91.100001)
		(width 0.114)
		(layer "In7.Cu")
		(net 424)
	)
	(segment
		(start 165.543001 90.956501)
		(end 165.543001 91.100001)
		(width 0.114)
		(layer "In7.Cu")
		(net 424)
	)
	(segment
		(start 169.443001 90.956501)
		(end 169.443001 91.100001)
		(width 0.114)
		(layer "In7.Cu")
		(net 424)
	)
	(segment
		(start 155.158501 103.980561)
		(end 155.764441 104.586501)
		(width 0.114)
		(layer "In7.Cu")
		(net 424)
	)
	(segment
		(start 195.356501 113.405001)
		(end 195.356501 112.789441)
		(width 0.114)
		(layer "In7.Cu")
		(net 424)
	)
	(arc
		(start 166.349501 91.543501)
		(mid 166.035899 91.413603)
		(end 165.906001 91.100001)
		(width 0.114)
		(layer "In7.Cu")
		(net 424)
	)
	(arc
		(start 169.599501 90.800001)
		(mid 169.488839 90.845839)
		(end 169.443001 90.956501)
		(width 0.114)
		(layer "In7.Cu")
		(net 424)
	)
	(arc
		(start 157.652001 95.824501)
		(mid 157.478169 96.244169)
		(end 157.058501 96.418001)
		(width 0.114)
		(layer "In7.Cu")
		(net 424)
	)
	(arc
		(start 155.783501 92.595001)
		(mid 156.150136 92.746866)
		(end 156.302001 93.113501)
		(width 0.114)
		(layer "In7.Cu")
		(net 424)
	)
	(arc
		(start 164.399501 90.800001)
		(mid 164.288839 90.845839)
		(end 164.243001 90.956501)
		(width 0.114)
		(layer "In7.Cu")
		(net 424)
	)
	(arc
		(start 156.302001 100.920501)
		(mid 156.157458 101.269458)
		(end 155.808501 101.414001)
		(width 0.114)
		(layer "In7.Cu")
		(net 424)
	)
	(arc
		(start 155.158501 94.924501)
		(mid 155.248273 95.141229)
		(end 155.465001 95.231001)
		(width 0.114)
		(layer "In7.Cu")
		(net 424)
	)
	(arc
		(start 165.543001 91.100001)
		(mid 165.413103 91.413603)
		(end 165.099501 91.543501)
		(width 0.114)
		(layer "In7.Cu")
		(net 424)
	)
	(arc
		(start 168.143001 91.100001)
		(mid 168.013103 91.413603)
		(end 167.699501 91.543501)
		(width 0.114)
		(layer "In7.Cu")
		(net 424)
	)
	(arc
		(start 155.158501 92.363501)
		(mid 155.226306 92.527196)
		(end 155.390001 92.595001)
		(width 0.114)
		(layer "In7.Cu")
		(net 424)
	)
	(arc
		(start 169.443001 91.100001)
		(mid 169.313103 91.413603)
		(end 168.999501 91.543501)
		(width 0.114)
		(layer "In7.Cu")
		(net 424)
	)
	(arc
		(start 155.858501 102.800501)
		(mid 156.070633 102.888369)
		(end 156.158501 103.100501)
		(width 0.114)
		(layer "In7.Cu")
		(net 424)
	)
	(arc
		(start 155.365001 98.829001)
		(mid 155.218983 98.889483)
		(end 155.158501 99.035501)
		(width 0.114)
		(layer "In7.Cu")
		(net 424)
	)
	(arc
		(start 155.158501 102.500501)
		(mid 155.246369 102.712633)
		(end 155.458501 102.800501)
		(width 0.114)
		(layer "In7.Cu")
		(net 424)
	)
	(arc
		(start 160.570178 98.335501)
		(mid 160.425635 98.684458)
		(end 160.076678 98.829001)
		(width 0.114)
		(layer "In7.Cu")
		(net 424)
	)
	(arc
		(start 167.206001 90.956501)
		(mid 167.160163 90.845839)
		(end 167.049501 90.800001)
		(width 0.114)
		(layer "In7.Cu")
		(net 424)
	)
	(arc
		(start 169.806001 90.956501)
		(mid 169.760163 90.845839)
		(end 169.649501 90.800001)
		(width 0.114)
		(layer "In7.Cu")
		(net 424)
	)
	(arc
		(start 166.999501 90.800001)
		(mid 166.888839 90.845839)
		(end 166.843001 90.956501)
		(width 0.114)
		(layer "In7.Cu")
		(net 424)
	)
	(arc
		(start 155.158501 97.635501)
		(mid 155.218983 97.781519)
		(end 155.365001 97.842001)
		(width 0.114)
		(layer "In7.Cu")
		(net 424)
	)
	(arc
		(start 165.906001 90.956501)
		(mid 165.860163 90.845839)
		(end 165.749501 90.800001)
		(width 0.114)
		(layer "In7.Cu")
		(net 424)
	)
	(arc
		(start 170.249501 91.543501)
		(mid 169.935899 91.413603)
		(end 169.806001 91.100001)
		(width 0.114)
		(layer "In7.Cu")
		(net 424)
	)
	(arc
		(start 155.158501 100.220501)
		(mid 155.218983 100.366519)
		(end 155.365001 100.427001)
		(width 0.114)
		(layer "In7.Cu")
		(net 424)
	)
	(arc
		(start 160.076678 97.842001)
		(mid 160.425635 97.986544)
		(end 160.570178 98.335501)
		(width 0.114)
		(layer "In7.Cu")
		(net 424)
	)
	(arc
		(start 155.365001 101.414001)
		(mid 155.218983 101.474483)
		(end 155.158501 101.620501)
		(width 0.114)
		(layer "In7.Cu")
		(net 424)
	)
	(arc
		(start 155.390001 93.632001)
		(mid 155.226306 93.699806)
		(end 155.158501 93.863501)
		(width 0.114)
		(layer "In7.Cu")
		(net 424)
	)
	(arc
		(start 167.649501 91.543501)
		(mid 167.335899 91.413603)
		(end 167.206001 91.100001)
		(width 0.114)
		(layer "In7.Cu")
		(net 424)
	)
	(arc
		(start 156.158501 103.100501)
		(mid 156.070633 103.312633)
		(end 155.858501 103.400501)
		(width 0.114)
		(layer "In7.Cu")
		(net 424)
	)
	(arc
		(start 168.506001 90.956501)
		(mid 168.460163 90.845839)
		(end 168.349501 90.800001)
		(width 0.114)
		(layer "In7.Cu")
		(net 424)
	)
	(arc
		(start 157.058501 95.231001)
		(mid 157.478169 95.404833)
		(end 157.652001 95.824501)
		(width 0.114)
		(layer "In7.Cu")
		(net 424)
	)
	(arc
		(start 155.458501 103.400501)
		(mid 155.246369 103.488369)
		(end 155.158501 103.700501)
		(width 0.114)
		(layer "In7.Cu")
		(net 424)
	)
	(arc
		(start 156.302001 93.113501)
		(mid 156.150136 93.480136)
		(end 155.783501 93.632001)
		(width 0.114)
		(layer "In7.Cu")
		(net 424)
	)
	(arc
		(start 168.949501 91.543501)
		(mid 168.635899 91.413603)
		(end 168.506001 91.100001)
		(width 0.114)
		(layer "In7.Cu")
		(net 424)
	)
	(arc
		(start 165.699501 90.800001)
		(mid 165.588839 90.845839)
		(end 165.543001 90.956501)
		(width 0.114)
		(layer "In7.Cu")
		(net 424)
	)
	(arc
		(start 164.606001 90.956501)
		(mid 164.560163 90.845839)
		(end 164.449501 90.800001)
		(width 0.114)
		(layer "In7.Cu")
		(net 424)
	)
	(arc
		(start 168.299501 90.800001)
		(mid 168.188839 90.845839)
		(end 168.143001 90.956501)
		(width 0.114)
		(layer "In7.Cu")
		(net 424)
	)
	(arc
		(start 166.843001 91.100001)
		(mid 166.713103 91.413603)
		(end 166.399501 91.543501)
		(width 0.114)
		(layer "In7.Cu")
		(net 424)
	)
	(arc
		(start 165.049501 91.543501)
		(mid 164.735899 91.413603)
		(end 164.606001 91.100001)
		(width 0.114)
		(layer "In7.Cu")
		(net 424)
	)
	(arc
		(start 164.243001 91.100001)
		(mid 164.113103 91.413603)
		(end 163.799501 91.543501)
		(width 0.114)
		(layer "In7.Cu")
		(net 424)
	)
	(arc
		(start 155.465001 96.418001)
		(mid 155.248273 96.507773)
		(end 155.158501 96.724501)
		(width 0.114)
		(layer "In7.Cu")
		(net 424)
	)
	(arc
		(start 155.808501 100.427001)
		(mid 156.157458 100.571544)
		(end 156.302001 100.920501)
		(width 0.114)
		(layer "In7.Cu")
		(net 424)
	)
	(segment
		(start 156.775002 101.052002)
		(end 156.606804 101.052001)
		(width 0.16)
		(layer "F.Cu")
		(net 426)
	)
	(segment
		(start 156.606804 101.052001)
		(end 156.285001 101.373804)
		(width 0.16)
		(layer "F.Cu")
		(net 426)
	)
	(segment
		(start 156.775002 101.052002)
		(end 156.920001 101.197001)
		(width 0.16)
		(layer "F.Cu")
		(net 426)
	)
	(segment
		(start 156.285001 101.373804)
		(end 156.285001 101.555001)
		(width 0.16)
		(layer "F.Cu")
		(net 426)
	)
	(segment
		(start 196.5 115.5)
		(end 196 115)
		(width 0.256)
		(layer "F.Cu")
		(net 426)
	)
	(via
		(at 174.079737 101.320265)
		(size 0.45)
		(drill 0.2)
		(layers "F.Cu" "B.Cu")
		(net 426)
	)
	(via
		(at 196 115)
		(size 0.45)
		(drill 0.2)
		(layers "F.Cu" "B.Cu")
		(net 426)
	)
	(via
		(at 156.920001 101.197001)
		(size 0.45)
		(drill 0.2)
		(layers "F.Cu" "B.Cu")
		(net 426)
	)
	(segment
		(start 156.920001 101.197001)
		(end 157.053501 101.063501)
		(width 0.114)
		(layer "In3.Cu")
		(net 426)
	)
	(segment
		(start 158.362891 100.784929)
		(end 158.336111 100.758149)
		(width 0.114)
		(layer "In3.Cu")
		(net 426)
	)
	(segment
		(start 173.359441 100.843501)
		(end 173.840561 100.843501)
		(width 0.114)
		(layer "In3.Cu")
		(net 426)
	)
	(segment
		(start 173.840561 100.843501)
		(end 174.079737 101.082677)
		(width 0.114)
		(layer "In3.Cu")
		(net 426)
	)
	(segment
		(start 174.079737 101.082677)
		(end 174.079737 101.320265)
		(width 0.114)
		(layer "In3.Cu")
		(net 426)
	)
	(segment
		(start 158.362891 100.784928)
		(end 158.362891 100.784929)
		(width 0.114)
		(layer "In3.Cu")
		(net 426)
	)
	(segment
		(start 157.053501 101.063501)
		(end 157.879441 101.063501)
		(width 0.114)
		(layer "In3.Cu")
		(net 426)
	)
	(segment
		(start 158.336111 100.606829)
		(end 158.336111 100.606828)
		(width 0.114)
		(layer "In3.Cu")
		(net 426)
	)
	(segment
		(start 158.36289 100.93625)
		(end 158.362891 100.93625)
		(width 0.114)
		(layer "In3.Cu")
		(net 426)
	)
	(segment
		(start 158.336111 100.606828)
		(end 158.929441 100.013501)
		(width 0.114)
		(layer "In3.Cu")
		(net 426)
	)
	(segment
		(start 171.759441 102.443501)
		(end 173.359441 100.843501)
		(width 0.114)
		(layer "In3.Cu")
		(net 426)
	)
	(segment
		(start 159.630561 100.013501)
		(end 160.050561 100.433501)
		(width 0.114)
		(layer "In3.Cu")
		(net 426)
	)
	(segment
		(start 157.879441 101.063501)
		(end 158.033471 100.909471)
		(width 0.114)
		(layer "In3.Cu")
		(net 426)
	)
	(segment
		(start 158.929441 100.013501)
		(end 159.630561 100.013501)
		(width 0.114)
		(layer "In3.Cu")
		(net 426)
	)
	(segment
		(start 168.930561 100.433501)
		(end 170.940561 102.443501)
		(width 0.114)
		(layer "In3.Cu")
		(net 426)
	)
	(segment
		(start 170.940561 102.443501)
		(end 171.759441 102.443501)
		(width 0.114)
		(layer "In3.Cu")
		(net 426)
	)
	(segment
		(start 160.050561 100.433501)
		(end 168.930561 100.433501)
		(width 0.114)
		(layer "In3.Cu")
		(net 426)
	)
	(segment
		(start 158.184791 100.909471)
		(end 158.21157 100.93625)
		(width 0.114)
		(layer "In3.Cu")
		(net 426)
	)
	(arc
		(start 158.033471 100.909471)
		(mid 158.109131 100.878132)
		(end 158.184791 100.909471)
		(width 0.114)
		(layer "In3.Cu")
		(net 426)
	)
	(arc
		(start 158.362891 100.93625)
		(mid 158.394231 100.860589)
		(end 158.362891 100.784928)
		(width 0.114)
		(layer "In3.Cu")
		(net 426)
	)
	(arc
		(start 158.336111 100.758149)
		(mid 158.304772 100.682489)
		(end 158.336111 100.606829)
		(width 0.114)
		(layer "In3.Cu")
		(net 426)
	)
	(arc
		(start 158.21157 100.93625)
		(mid 158.28723 100.967589)
		(end 158.36289 100.93625)
		(width 0.114)
		(layer "In3.Cu")
		(net 426)
	)
	(segment
		(start 195.600001 114.600001)
		(end 195.600001 113.448501)
		(width 0.1)
		(layer "In5.Cu")
		(net 426)
	)
	(segment
		(start 174.937866 99.298531)
		(end 175.307376 99.668041)
		(width 0.114)
		(layer "In5.Cu")
		(net 426)
	)
	(segment
		(start 174.937867 99.298531)
		(end 174.937866 99.298531)
		(width 0.114)
		(layer "In5.Cu")
		(net 426)
	)
	(segment
		(start 175.740832 99.668041)
		(end 175.740833 99.668041)
		(width 0.114)
		(layer "In5.Cu")
		(net 426)
	)
	(segment
		(start 175.371323 98.025738)
		(end 175.740561 97.656501)
		(width 0.114)
		(layer "In5.Cu")
		(net 426)
	)
	(segment
		(start 196.000001 115.000001)
		(end 195.600001 114.600001)
		(width 0.1)
		(layer "In5.Cu")
		(net 426)
	)
	(segment
		(start 182.034441 97.656501)
		(end 195.643501 111.265561)
		(width 0.114)
		(layer "In5.Cu")
		(net 426)
	)
	(segment
		(start 175.371322 98.025737)
		(end 175.371323 98.025738)
		(width 0.114)
		(layer "In5.Cu")
		(net 426)
	)
	(segment
		(start 177.925001 98.125001)
		(end 177.925001 98.668501)
		(width 0.114)
		(layer "In5.Cu")
		(net 426)
	)
	(segment
		(start 179.588001 98.668501)
		(end 179.588001 98.125001)
		(width 0.114)
		(layer "In5.Cu")
		(net 426)
	)
	(segment
		(start 174.079737 101.320265)
		(end 174.079737 101.082677)
		(width 0.114)
		(layer "In5.Cu")
		(net 426)
	)
	(segment
		(start 175.740833 99.234584)
		(end 175.371322 98.865073)
		(width 0.114)
		(layer "In5.Cu")
		(net 426)
	)
	(segment
		(start 173.756501 99.640561)
		(end 174.098531 99.298531)
		(width 0.114)
		(layer "In5.Cu")
		(net 426)
	)
	(segment
		(start 173.756501 100.759441)
		(end 173.756501 99.640561)
		(width 0.114)
		(layer "In5.Cu")
		(net 426)
	)
	(segment
		(start 174.079737 101.082677)
		(end 173.756501 100.759441)
		(width 0.114)
		(layer "In5.Cu")
		(net 426)
	)
	(segment
		(start 175.740561 97.656501)
		(end 177.456501 97.656501)
		(width 0.114)
		(layer "In5.Cu")
		(net 426)
	)
	(segment
		(start 175.740833 99.234583)
		(end 175.740833 99.234584)
		(width 0.114)
		(layer "In5.Cu")
		(net 426)
	)
	(segment
		(start 181.356501 97.656501)
		(end 182.034441 97.656501)
		(width 0.114)
		(layer "In5.Cu")
		(net 426)
	)
	(segment
		(start 180.525001 98.125001)
		(end 180.525001 98.668501)
		(width 0.114)
		(layer "In5.Cu")
		(net 426)
	)
	(segment
		(start 179.225001 98.125001)
		(end 179.225001 98.668501)
		(width 0.114)
		(layer "In5.Cu")
		(net 426)
	)
	(segment
		(start 195.643501 111.265561)
		(end 195.643501 113.405001)
		(width 0.114)
		(layer "In5.Cu")
		(net 426)
	)
	(segment
		(start 178.288001 98.668501)
		(end 178.288001 98.125001)
		(width 0.114)
		(layer "In5.Cu")
		(net 426)
	)
	(segment
		(start 180.888001 98.668501)
		(end 180.888001 98.125001)
		(width 0.114)
		(layer "In5.Cu")
		(net 426)
	)
	(segment
		(start 195.600001 113.448501)
		(end 195.643501 113.405001)
		(width 0.1)
		(layer "In5.Cu")
		(net 426)
	)
	(arc
		(start 179.225001 98.668501)
		(mid 179.278161 98.796841)
		(end 179.406501 98.850001)
		(width 0.114)
		(layer "In5.Cu")
		(net 426)
	)
	(arc
		(start 180.706501 98.850001)
		(mid 180.834841 98.796841)
		(end 180.888001 98.668501)
		(width 0.114)
		(layer "In5.Cu")
		(net 426)
	)
	(arc
		(start 178.756501 97.656501)
		(mid 179.087781 97.793721)
		(end 179.225001 98.125001)
		(width 0.114)
		(layer "In5.Cu")
		(net 426)
	)
	(arc
		(start 178.288001 98.125001)
		(mid 178.425221 97.793721)
		(end 178.756501 97.656501)
		(width 0.114)
		(layer "In5.Cu")
		(net 426)
	)
	(arc
		(start 180.888001 98.125001)
		(mid 181.025221 97.793721)
		(end 181.356501 97.656501)
		(width 0.114)
		(layer "In5.Cu")
		(net 426)
	)
	(arc
		(start 174.098531 99.298531)
		(mid 174.518199 99.124699)
		(end 174.937867 99.298531)
		(width 0.114)
		(layer "In5.Cu")
		(net 426)
	)
	(arc
		(start 175.740833 99.668041)
		(mid 175.830605 99.451312)
		(end 175.740833 99.234583)
		(width 0.114)
		(layer "In5.Cu")
		(net 426)
	)
	(arc
		(start 177.925001 98.668501)
		(mid 177.978161 98.796841)
		(end 178.106501 98.850001)
		(width 0.114)
		(layer "In5.Cu")
		(net 426)
	)
	(arc
		(start 180.056501 97.656501)
		(mid 180.387781 97.793721)
		(end 180.525001 98.125001)
		(width 0.114)
		(layer "In5.Cu")
		(net 426)
	)
	(arc
		(start 179.406501 98.850001)
		(mid 179.534841 98.796841)
		(end 179.588001 98.668501)
		(width 0.114)
		(layer "In5.Cu")
		(net 426)
	)
	(arc
		(start 178.106501 98.850001)
		(mid 178.234841 98.796841)
		(end 178.288001 98.668501)
		(width 0.114)
		(layer "In5.Cu")
		(net 426)
	)
	(arc
		(start 175.307376 99.668041)
		(mid 175.524104 99.757813)
		(end 175.740832 99.668041)
		(width 0.114)
		(layer "In5.Cu")
		(net 426)
	)
	(arc
		(start 179.588001 98.125001)
		(mid 179.725221 97.793721)
		(end 180.056501 97.656501)
		(width 0.114)
		(layer "In5.Cu")
		(net 426)
	)
	(arc
		(start 180.525001 98.668501)
		(mid 180.578161 98.796841)
		(end 180.706501 98.850001)
		(width 0.114)
		(layer "In5.Cu")
		(net 426)
	)
	(arc
		(start 177.456501 97.656501)
		(mid 177.787781 97.793721)
		(end 177.925001 98.125001)
		(width 0.114)
		(layer "In5.Cu")
		(net 426)
	)
	(arc
		(start 175.371322 98.865073)
		(mid 175.19749 98.445405)
		(end 175.371322 98.025737)
		(width 0.114)
		(layer "In5.Cu")
		(net 426)
	)
	(segment
		(start 214.5 117.5)
		(end 215 117)
		(width 0.256)
		(layer "F.Cu")
		(net 427)
	)
	(segment
		(start 236.385 113.565)
		(end 236.385 112.6)
		(width 0.1)
		(layer "F.Cu")
		(net 427)
	)
	(segment
		(start 236.385 114.575)
		(end 236.385 113.6)
		(width 0.1)
		(layer "F.Cu")
		(net 427)
	)
	(segment
		(start 236.375 113.575)
		(end 236.385 113.565)
		(width 0.1)
		(layer "F.Cu")
		(net 427)
	)
	(via
		(at 215 117)
		(size 0.45)
		(drill 0.2)
		(layers "F.Cu" "B.Cu")
		(net 427)
	)
	(via
		(at 236.375 113.575)
		(size 0.45)
		(drill 0.2)
		(layers "F.Cu" "B.Cu")
		(net 427)
	)
	(segment
		(start 236.375 114.645)
		(end 234.92 116.1)
		(width 0.1)
		(layer "In7.Cu")
		(net 427)
	)
	(segment
		(start 222.55 116.35)
		(end 215.65 116.35)
		(width 0.1)
		(layer "In7.Cu")
		(net 427)
	)
	(segment
		(start 223.25 116.65)
		(end 222.85 116.65)
		(width 0.1)
		(layer "In7.Cu")
		(net 427)
	)
	(segment
		(start 234.92 116.1)
		(end 223.8 116.1)
		(width 0.1)
		(layer "In7.Cu")
		(net 427)
	)
	(segment
		(start 223.8 116.1)
		(end 223.25 116.65)
		(width 0.1)
		(layer "In7.Cu")
		(net 427)
	)
	(segment
		(start 222.85 116.65)
		(end 222.55 116.35)
		(width 0.1)
		(layer "In7.Cu")
		(net 427)
	)
	(segment
		(start 236.375 113.575)
		(end 236.375 114.645)
		(width 0.1)
		(layer "In7.Cu")
		(net 427)
	)
	(segment
		(start 215.65 116.35)
		(end 215 117)
		(width 0.1)
		(layer "In7.Cu")
		(net 427)
	)
	(segment
		(start 195.5 115.5)
		(end 195 115)
		(width 0.256)
		(layer "F.Cu")
		(net 428)
	)
	(segment
		(start 156.775002 100.788)
		(end 156.606804 100.788001)
		(width 0.16)
		(layer "F.Cu")
		(net 428)
	)
	(segment
		(start 156.285001 100.466198)
		(end 156.606804 100.788001)
		(width 0.16)
		(layer "F.Cu")
		(net 428)
	)
	(segment
		(start 156.285001 100.285001)
		(end 156.285001 100.466198)
		(width 0.16)
		(layer "F.Cu")
		(net 428)
	)
	(segment
		(start 156.775002 100.788)
		(end 156.920001 100.643001)
		(width 0.16)
		(layer "F.Cu")
		(net 428)
	)
	(via
		(at 195 115)
		(size 0.45)
		(drill 0.2)
		(layers "F.Cu" "B.Cu")
		(net 428)
	)
	(via
		(at 156.920001 100.643001)
		(size 0.45)
		(drill 0.2)
		(layers "F.Cu" "B.Cu")
		(net 428)
	)
	(via
		(at 174.520265 100.879737)
		(size 0.45)
		(drill 0.2)
		(layers "F.Cu" "B.Cu")
		(net 428)
	)
	(segment
		(start 171.059441 102.156501)
		(end 169.049441 100.146501)
		(width 0.114)
		(layer "In3.Cu")
		(net 428)
	)
	(segment
		(start 174.282677 100.879737)
		(end 173.959441 100.556501)
		(width 0.114)
		(layer "In3.Cu")
		(net 428)
	)
	(segment
		(start 157.053501 100.776501)
		(end 156.920001 100.643001)
		(width 0.114)
		(layer "In3.Cu")
		(net 428)
	)
	(segment
		(start 173.959441 100.556501)
		(end 173.240561 100.556501)
		(width 0.114)
		(layer "In3.Cu")
		(net 428)
	)
	(segment
		(start 173.240561 100.556501)
		(end 171.640561 102.156501)
		(width 0.114)
		(layer "In3.Cu")
		(net 428)
	)
	(segment
		(start 159.749441 99.726501)
		(end 158.810561 99.726501)
		(width 0.114)
		(layer "In3.Cu")
		(net 428)
	)
	(segment
		(start 157.760561 100.776501)
		(end 157.053501 100.776501)
		(width 0.114)
		(layer "In3.Cu")
		(net 428)
	)
	(segment
		(start 158.810561 99.726501)
		(end 157.760561 100.776501)
		(width 0.114)
		(layer "In3.Cu")
		(net 428)
	)
	(segment
		(start 174.520265 100.879737)
		(end 174.282677 100.879737)
		(width 0.114)
		(layer "In3.Cu")
		(net 428)
	)
	(segment
		(start 169.049441 100.146501)
		(end 160.169441 100.146501)
		(width 0.114)
		(layer "In3.Cu")
		(net 428)
	)
	(segment
		(start 160.169441 100.146501)
		(end 159.749441 99.726501)
		(width 0.114)
		(layer "In3.Cu")
		(net 428)
	)
	(segment
		(start 171.640561 102.156501)
		(end 171.059441 102.156501)
		(width 0.114)
		(layer "In3.Cu")
		(net 428)
	)
	(segment
		(start 177.638001 98.125001)
		(end 177.638001 98.668501)
		(width 0.114)
		(layer "In5.Cu")
		(net 428)
	)
	(segment
		(start 181.175001 98.668501)
		(end 181.175001 98.125001)
		(width 0.114)
		(layer "In5.Cu")
		(net 428)
	)
	(segment
		(start 181.915561 97.943501)
		(end 195.356501 111.384441)
		(width 0.114)
		(layer "In5.Cu")
		(net 428)
	)
	(segment
		(start 180.238001 98.125001)
		(end 180.238001 98.668501)
		(width 0.114)
		(layer "In5.Cu")
		(net 428)
	)
	(segment
		(start 195.356501 111.384441)
		(end 195.356501 113.405001)
		(width 0.114)
		(layer "In5.Cu")
		(net 428)
	)
	(segment
		(start 174.282677 100.879737)
		(end 174.043501 100.640561)
		(width 0.114)
		(layer "In5.Cu")
		(net 428)
	)
	(segment
		(start 175.574262 98.228677)
		(end 175.574262 98.228676)
		(width 0.114)
		(layer "In5.Cu")
		(net 428)
	)
	(segment
		(start 179.875001 98.668501)
		(end 179.875001 98.125001)
		(width 0.114)
		(layer "In5.Cu")
		(net 428)
	)
	(segment
		(start 178.938001 98.125001)
		(end 178.938001 98.668501)
		(width 0.114)
		(layer "In5.Cu")
		(net 428)
	)
	(segment
		(start 181.356501 97.943501)
		(end 181.915561 97.943501)
		(width 0.114)
		(layer "In5.Cu")
		(net 428)
	)
	(segment
		(start 175.574263 98.228678)
		(end 175.859441 97.943501)
		(width 0.114)
		(layer "In5.Cu")
		(net 428)
	)
	(segment
		(start 195.000001 115.000001)
		(end 195.400001 114.600001)
		(width 0.1)
		(layer "In5.Cu")
		(net 428)
	)
	(segment
		(start 174.734928 99.50147)
		(end 174.734927 99.50147)
		(width 0.114)
		(layer "In5.Cu")
		(net 428)
	)
	(segment
		(start 175.943773 99.031644)
		(end 175.574262 98.662133)
		(width 0.114)
		(layer "In5.Cu")
		(net 428)
	)
	(segment
		(start 195.400001 113.448501)
		(end 195.356501 113.405001)
		(width 0.1)
		(layer "In5.Cu")
		(net 428)
	)
	(segment
		(start 174.043501 100.640561)
		(end 174.043501 99.759441)
		(width 0.114)
		(layer "In5.Cu")
		(net 428)
	)
	(segment
		(start 175.574262 98.228676)
		(end 175.574263 98.228678)
		(width 0.114)
		(layer "In5.Cu")
		(net 428)
	)
	(segment
		(start 174.043501 99.759441)
		(end 174.30147 99.50147)
		(width 0.114)
		(layer "In5.Cu")
		(net 428)
	)
	(segment
		(start 195.400001 114.600001)
		(end 195.400001 113.448501)
		(width 0.1)
		(layer "In5.Cu")
		(net 428)
	)
	(segment
		(start 174.734927 99.50147)
		(end 175.104437 99.87098)
		(width 0.114)
		(layer "In5.Cu")
		(net 428)
	)
	(segment
		(start 178.575001 98.668501)
		(end 178.575001 98.125001)
		(width 0.114)
		(layer "In5.Cu")
		(net 428)
	)
	(segment
		(start 174.520265 100.879737)
		(end 174.282677 100.879737)
		(width 0.114)
		(layer "In5.Cu")
		(net 428)
	)
	(segment
		(start 175.859441 97.943501)
		(end 177.456501 97.943501)
		(width 0.114)
		(layer "In5.Cu")
		(net 428)
	)
	(arc
		(start 181.175001 98.125001)
		(mid 181.228161 97.996661)
		(end 181.356501 97.943501)
		(width 0.114)
		(layer "In5.Cu")
		(net 428)
	)
	(arc
		(start 180.056501 97.943501)
		(mid 180.184841 97.996661)
		(end 180.238001 98.125001)
		(width 0.114)
		(layer "In5.Cu")
		(net 428)
	)
	(arc
		(start 179.406501 99.137001)
		(mid 179.737781 98.999781)
		(end 179.875001 98.668501)
		(width 0.114)
		(layer "In5.Cu")
		(net 428)
	)
	(arc
		(start 175.574262 98.662133)
		(mid 175.48449 98.445405)
		(end 175.574262 98.228677)
		(width 0.114)
		(layer "In5.Cu")
		(net 428)
	)
	(arc
		(start 178.106501 99.137001)
		(mid 178.437781 98.999781)
		(end 178.575001 98.668501)
		(width 0.114)
		(layer "In5.Cu")
		(net 428)
	)
	(arc
		(start 175.104437 99.87098)
		(mid 175.524105 100.044812)
		(end 175.943773 99.87098)
		(width 0.114)
		(layer "In5.Cu")
		(net 428)
	)
	(arc
		(start 178.938001 98.668501)
		(mid 179.075221 98.999781)
		(end 179.406501 99.137001)
		(width 0.114)
		(layer "In5.Cu")
		(net 428)
	)
	(arc
		(start 180.238001 98.668501)
		(mid 180.375221 98.999781)
		(end 180.706501 99.137001)
		(width 0.114)
		(layer "In5.Cu")
		(net 428)
	)
	(arc
		(start 180.706501 99.137001)
		(mid 181.037781 98.999781)
		(end 181.175001 98.668501)
		(width 0.114)
		(layer "In5.Cu")
		(net 428)
	)
	(arc
		(start 175.943773 99.87098)
		(mid 176.117605 99.451312)
		(end 175.943773 99.031644)
		(width 0.114)
		(layer "In5.Cu")
		(net 428)
	)
	(arc
		(start 178.756501 97.943501)
		(mid 178.884841 97.996661)
		(end 178.938001 98.125001)
		(width 0.114)
		(layer "In5.Cu")
		(net 428)
	)
	(arc
		(start 177.456501 97.943501)
		(mid 177.584841 97.996661)
		(end 177.638001 98.125001)
		(width 0.114)
		(layer "In5.Cu")
		(net 428)
	)
	(arc
		(start 174.30147 99.50147)
		(mid 174.518199 99.411698)
		(end 174.734928 99.50147)
		(width 0.114)
		(layer "In5.Cu")
		(net 428)
	)
	(arc
		(start 179.875001 98.125001)
		(mid 179.928161 97.996661)
		(end 180.056501 97.943501)
		(width 0.114)
		(layer "In5.Cu")
		(net 428)
	)
	(arc
		(start 177.638001 98.668501)
		(mid 177.775221 98.999781)
		(end 178.106501 99.137001)
		(width 0.114)
		(layer "In5.Cu")
		(net 428)
	)
	(arc
		(start 178.575001 98.125001)
		(mid 178.628161 97.996661)
		(end 178.756501 97.943501)
		(width 0.114)
		(layer "In5.Cu")
		(net 428)
	)
	(segment
		(start 236.675 115.55)
		(end 236.385 115.55)
		(width 0.201)
		(layer "F.Cu")
		(net 429)
	)
	(segment
		(start 212.5 119.5)
		(end 213 119)
		(width 0.256)
		(layer "F.Cu")
		(net 429)
	)
	(via
		(at 213 119)
		(size 0.45)
		(drill 0.2)
		(layers "F.Cu" "B.Cu")
		(net 429)
	)
	(via
		(at 236.675 115.55)
		(size 0.45)
		(drill 0.2)
		(layers "F.Cu" "B.Cu")
		(net 429)
	)
	(segment
		(start 223.35 116.9)
		(end 219.9 116.9)
		(width 0.1)
		(layer "In7.Cu")
		(net 429)
	)
	(segment
		(start 213 119)
		(end 213.515 118.485)
		(width 0.1)
		(layer "In7.Cu")
		(net 429)
	)
	(segment
		(start 219.9 116.9)
		(end 218.315 118.485)
		(width 0.1)
		(layer "In7.Cu")
		(net 429)
	)
	(segment
		(start 236.675 115.55)
		(end 235.875 116.35)
		(width 0.1)
		(layer "In7.Cu")
		(net 429)
	)
	(segment
		(start 223.9 116.35)
		(end 223.35 116.9)
		(width 0.1)
		(layer "In7.Cu")
		(net 429)
	)
	(segment
		(start 235.875 116.35)
		(end 223.9 116.35)
		(width 0.1)
		(layer "In7.Cu")
		(net 429)
	)
	(segment
		(start 213.515 118.485)
		(end 218.315 118.485)
		(width 0.1)
		(layer "In7.Cu")
		(net 429)
	)
	(segment
		(start 211.5 122.5)
		(end 212 122)
		(width 0.256)
		(layer "F.Cu")
		(net 430)
	)
	(segment
		(start 223.4 117.55)
		(end 223.55 117.4)
		(width 0.1)
		(layer "F.Cu")
		(net 430)
	)
	(segment
		(start 223.55 114.265)
		(end 224.615 113.2)
		(width 0.1)
		(layer "F.Cu")
		(net 430)
	)
	(segment
		(start 223.55 117.4)
		(end 223.55 114.265)
		(width 0.1)
		(layer "F.Cu")
		(net 430)
	)
	(via
		(at 212 122)
		(size 0.45)
		(drill 0.2)
		(layers "F.Cu" "B.Cu")
		(net 430)
	)
	(via
		(at 223.4 117.55)
		(size 0.45)
		(drill 0.2)
		(layers "F.Cu" "B.Cu")
		(net 430)
	)
	(segment
		(start 220.2 117.4)
		(end 223.25 117.4)
		(width 0.1)
		(layer "In7.Cu")
		(net 430)
	)
	(segment
		(start 223.25 117.4)
		(end 223.4 117.55)
		(width 0.1)
		(layer "In7.Cu")
		(net 430)
	)
	(segment
		(start 215.975 121.625)
		(end 220.2 117.4)
		(width 0.1)
		(layer "In7.Cu")
		(net 430)
	)
	(segment
		(start 212.375 121.625)
		(end 215.975 121.625)
		(width 0.1)
		(layer "In7.Cu")
		(net 430)
	)
	(segment
		(start 212 122)
		(end 212.375 121.625)
		(width 0.1)
		(layer "In7.Cu")
		(net 430)
	)
	(segment
		(start 164.55 123.79)
		(end 164.55 126.325)
		(width 0.1)
		(layer "F.Cu")
		(net 431)
	)
	(segment
		(start 163.905001 123.145001)
		(end 164.55 123.79)
		(width 0.1)
		(layer "F.Cu")
		(net 431)
	)
	(via
		(at 255.625 119.925)
		(size 0.45)
		(drill 0.2)
		(layers "F.Cu" "B.Cu")
		(net 431)
	)
	(via
		(at 185 76.15)
		(size 0.45)
		(drill 0.2)
		(layers "F.Cu" "B.Cu")
		(net 431)
	)
	(via
		(at 164.55 126.325)
		(size 0.45)
		(drill 0.2)
		(layers "F.Cu" "B.Cu")
		(net 431)
	)
	(via
		(at 166.45 78.625)
		(size 0.45)
		(drill 0.2)
		(layers "F.Cu" "B.Cu")
		(net 431)
	)
	(segment
		(start 255.625 120.145)
		(end 258.25 122.77)
		(width 0.1)
		(layer "B.Cu")
		(net 431)
	)
	(segment
		(start 258.25 122.77)
		(end 258.25 122.8125)
		(width 0.1)
		(layer "B.Cu")
		(net 431)
	)
	(segment
		(start 255.625 119.925)
		(end 255.625 120.145)
		(width 0.1)
		(layer "B.Cu")
		(net 431)
	)
	(segment
		(start 164.55 126.325)
		(end 164.55 124.875)
		(width 0.1)
		(layer "In3.Cu")
		(net 431)
	)
	(segment
		(start 155.25 83.8)
		(end 155.25 120.725)
		(width 0.1)
		(layer "In3.Cu")
		(net 431)
	)
	(segment
		(start 167.65 79.825)
		(end 167.65 80.65)
		(width 0.1)
		(layer "In3.Cu")
		(net 431)
	)
	(segment
		(start 157.925 123.4)
		(end 163.075 123.4)
		(width 0.1)
		(layer "In3.Cu")
		(net 431)
	)
	(segment
		(start 167.65 80.65)
		(end 165.9 82.4)
		(width 0.1)
		(layer "In3.Cu")
		(net 431)
	)
	(segment
		(start 155.25 120.725)
		(end 157.925 123.4)
		(width 0.1)
		(layer "In3.Cu")
		(net 431)
	)
	(segment
		(start 163.075 123.4)
		(end 164.55 124.875)
		(width 0.1)
		(layer "In3.Cu")
		(net 431)
	)
	(segment
		(start 165.9 82.4)
		(end 156.65 82.4)
		(width 0.1)
		(layer "In3.Cu")
		(net 431)
	)
	(segment
		(start 166.45 78.625)
		(end 167.65 79.825)
		(width 0.1)
		(layer "In3.Cu")
		(net 431)
	)
	(segment
		(start 156.65 82.4)
		(end 155.25 83.8)
		(width 0.1)
		(layer "In3.Cu")
		(net 431)
	)
	(segment
		(start 200.98 80.4)
		(end 195.23 74.65)
		(width 0.1)
		(layer "In7.Cu")
		(net 431)
	)
	(segment
		(start 202.15 85.02)
		(end 200.98 83.85)
		(width 0.1)
		(layer "In7.Cu")
		(net 431)
	)
	(segment
		(start 169.6 75.5)
		(end 184.35 75.5)
		(width 0.1)
		(layer "In7.Cu")
		(net 431)
	)
	(segment
		(start 195.23 74.65)
		(end 186.5 74.65)
		(width 0.1)
		(layer "In7.Cu")
		(net 431)
	)
	(segment
		(start 254.58 118.88)
		(end 249.01 118.88)
		(width 0.1)
		(layer "In7.Cu")
		(net 431)
	)
	(segment
		(start 211.9 101.39)
		(end 211.9 89.57)
		(width 0.1)
		(layer "In7.Cu")
		(net 431)
	)
	(segment
		(start 207.35 85.02)
		(end 202.15 85.02)
		(width 0.1)
		(layer "In7.Cu")
		(net 431)
	)
	(segment
		(start 236.68 106.55)
		(end 217.06 106.55)
		(width 0.1)
		(layer "In7.Cu")
		(net 431)
	)
	(segment
		(start 200.98 83.85)
		(end 200.98 80.4)
		(width 0.1)
		(layer "In7.Cu")
		(net 431)
	)
	(segment
		(start 217.06 106.55)
		(end 211.9 101.39)
		(width 0.1)
		(layer "In7.Cu")
		(net 431)
	)
	(segment
		(start 166.475 78.625)
		(end 169.6 75.5)
		(width 0.1)
		(layer "In7.Cu")
		(net 431)
	)
	(segment
		(start 184.35 75.5)
		(end 185 76.15)
		(width 0.1)
		(layer "In7.Cu")
		(net 431)
	)
	(segment
		(start 211.9 89.57)
		(end 207.35 85.02)
		(width 0.1)
		(layer "In7.Cu")
		(net 431)
	)
	(segment
		(start 166.45 78.625)
		(end 166.475 78.625)
		(width 0.1)
		(layer "In7.Cu")
		(net 431)
	)
	(segment
		(start 255.625 119.925)
		(end 254.58 118.88)
		(width 0.1)
		(layer "In7.Cu")
		(net 431)
	)
	(segment
		(start 186.5 74.65)
		(end 185 76.15)
		(width 0.1)
		(layer "In7.Cu")
		(net 431)
	)
	(segment
		(start 249.01 118.88)
		(end 236.68 106.55)
		(width 0.1)
		(layer "In7.Cu")
		(net 431)
	)
	(segment
		(start 210.5 139.5)
		(end 211 140)
		(width 0.256)
		(layer "F.Cu")
		(net 432)
	)
	(via
		(at 211 140)
		(size 0.45)
		(drill 0.2)
		(layers "F.Cu" "B.Cu")
		(net 432)
	)
	(segment
		(start 209.3 134.5)
		(end 208.85 134.5)
		(width 0.1)
		(layer "B.Cu")
		(net 432)
	)
	(segment
		(start 209.73 131.375)
		(end 212.200331 131.375)
		(width 0.1)
		(layer "B.Cu")
		(net 432)
	)
	(segment
		(start 209.5 138.275)
		(end 209.5 134.7)
		(width 0.1)
		(layer "B.Cu")
		(net 432)
	)
	(segment
		(start 212.8 130.65)
		(end 214.35 130.65)
		(width 0.1)
		(layer "B.Cu")
		(net 432)
	)
	(segment
		(start 217.8 130.025)
		(end 217.8 127.95)
		(width 0.1)
		(layer "B.Cu")
		(net 432)
	)
	(segment
		(start 215.05 131.35)
		(end 216.475 131.35)
		(width 0.1)
		(layer "B.Cu")
		(net 432)
	)
	(segment
		(start 219.275 126.475)
		(end 219.44 126.475)
		(width 0.1)
		(layer "B.Cu")
		(net 432)
	)
	(segment
		(start 209.1 133.575)
		(end 209.375 133.3)
		(width 0.1)
		(layer "B.Cu")
		(net 432)
	)
	(segment
		(start 208.6 133.825)
		(end 208.85 133.575)
		(width 0.1)
		(layer "B.Cu")
		(net 432)
	)
	(segment
		(start 209.725 138.5)
		(end 209.5 138.275)
		(width 0.1)
		(layer "B.Cu")
		(net 432)
	)
	(segment
		(start 212.475 131.100331)
		(end 212.475 130.975)
		(width 0.1)
		(layer "B.Cu")
		(net 432)
	)
	(segment
		(start 208.85 133.575)
		(end 209.1 133.575)
		(width 0.1)
		(layer "B.Cu")
		(net 432)
	)
	(segment
		(start 209.5 134.7)
		(end 209.3 134.5)
		(width 0.1)
		(layer "B.Cu")
		(net 432)
	)
	(segment
		(start 208.6 134.25)
		(end 208.6 133.825)
		(width 0.1)
		(layer "B.Cu")
		(net 432)
	)
	(segment
		(start 217.8 127.95)
		(end 219.275 126.475)
		(width 0.1)
		(layer "B.Cu")
		(net 432)
	)
	(segment
		(start 214.35 130.65)
		(end 215.05 131.35)
		(width 0.1)
		(layer "B.Cu")
		(net 432)
	)
	(segment
		(start 209.375 133.3)
		(end 209.375 131.73)
		(width 0.1)
		(layer "B.Cu")
		(net 432)
	)
	(segment
		(start 212.475 130.975)
		(end 212.8 130.65)
		(width 0.1)
		(layer "B.Cu")
		(net 432)
	)
	(segment
		(start 211 140)
		(end 211 139.075)
		(width 0.1)
		(layer "B.Cu")
		(net 432)
	)
	(segment
		(start 210.425 138.5)
		(end 209.725 138.5)
		(width 0.1)
		(layer "B.Cu")
		(net 432)
	)
	(segment
		(start 209.375 131.73)
		(end 209.73 131.375)
		(width 0.1)
		(layer "B.Cu")
		(net 432)
	)
	(segment
		(start 216.475 131.35)
		(end 217.8 130.025)
		(width 0.1)
		(layer "B.Cu")
		(net 432)
	)
	(segment
		(start 208.85 134.5)
		(end 208.6 134.25)
		(width 0.1)
		(layer "B.Cu")
		(net 432)
	)
	(segment
		(start 219.44 126.475)
		(end 220.115 125.8)
		(width 0.1)
		(layer "B.Cu")
		(net 432)
	)
	(segment
		(start 212.200331 131.375)
		(end 212.475 131.100331)
		(width 0.1)
		(layer "B.Cu")
		(net 432)
	)
	(segment
		(start 211 139.075)
		(end 210.425 138.5)
		(width 0.1)
		(layer "B.Cu")
		(net 432)
	)
	(segment
		(start 209.5 135.5)
		(end 210 136)
		(width 0.256)
		(layer "F.Cu")
		(net 433)
	)
	(via
		(at 210 136)
		(size 0.45)
		(drill 0.2)
		(layers "F.Cu" "B.Cu")
		(net 433)
	)
	(via
		(at 212.9 76.7)
		(size 0.45)
		(drill 0.2)
		(layers "F.Cu" "B.Cu")
		(net 433)
	)
	(segment
		(start 212.9 76.7)
		(end 212.899999 77.414999)
		(width 0.1)
		(layer "B.Cu")
		(net 433)
	)
	(segment
		(start 226.05 134.25)
		(end 221 134.25)
		(width 0.1)
		(layer "In3.Cu")
		(net 433)
	)
	(segment
		(start 210.6 132.817157)
		(end 210.6 135.4)
		(width 0.1)
		(layer "In3.Cu")
		(net 433)
	)
	(segment
		(start 213.4 77.2)
		(end 222.8 77.2)
		(width 0.1)
		(layer "In3.Cu")
		(net 433)
	)
	(segment
		(start 215.391421 132.4)
		(end 213.582841 132.4)
		(width 0.1)
		(layer "In3.Cu")
		(net 433)
	)
	(segment
		(start 210.6 135.4)
		(end 210 136)
		(width 0.1)
		(layer "In3.Cu")
		(net 433)
	)
	(segment
		(start 251.4 85.451993)
		(end 251.4 92.775)
		(width 0.1)
		(layer "In3.Cu")
		(net 433)
	)
	(segment
		(start 212.9 76.7)
		(end 213.4 77.2)
		(width 0.1)
		(layer "In3.Cu")
		(net 433)
	)
	(segment
		(start 219.475 132.725)
		(end 215.71642 132.725)
		(width 0.1)
		(layer "In3.Cu")
		(net 433)
	)
	(segment
		(start 213.582841 132.4)
		(end 213.357842 132.625)
		(width 0.1)
		(layer "In3.Cu")
		(net 433)
	)
	(segment
		(start 251.4 92.775)
		(end 242.675 101.5)
		(width 0.1)
		(layer "In3.Cu")
		(net 433)
	)
	(segment
		(start 215.71642 132.725)
		(end 215.391421 132.4)
		(width 0.1)
		(layer "In3.Cu")
		(net 433)
	)
	(segment
		(start 242.675 101.5)
		(end 232.4 101.5)
		(width 0.1)
		(layer "In3.Cu")
		(net 433)
	)
	(segment
		(start 252.1 84.751993)
		(end 251.4 85.451993)
		(width 0.1)
		(layer "In3.Cu")
		(net 433)
	)
	(segment
		(start 252.1 77.6)
		(end 252.1 84.751993)
		(width 0.1)
		(layer "In3.Cu")
		(net 433)
	)
	(segment
		(start 210.792157 132.625)
		(end 210.6 132.817157)
		(width 0.1)
		(layer "In3.Cu")
		(net 433)
	)
	(segment
		(start 227.4 106.5)
		(end 227.4 132.9)
		(width 0.1)
		(layer "In3.Cu")
		(net 433)
	)
	(segment
		(start 223.2 76.8)
		(end 251.3 76.8)
		(width 0.1)
		(layer "In3.Cu")
		(net 433)
	)
	(segment
		(start 227.4 132.9)
		(end 226.05 134.25)
		(width 0.1)
		(layer "In3.Cu")
		(net 433)
	)
	(segment
		(start 213.357842 132.625)
		(end 210.792157 132.625)
		(width 0.1)
		(layer "In3.Cu")
		(net 433)
	)
	(segment
		(start 232.4 101.5)
		(end 227.4 106.5)
		(width 0.1)
		(layer "In3.Cu")
		(net 433)
	)
	(segment
		(start 221 134.25)
		(end 219.475 132.725)
		(width 0.1)
		(layer "In3.Cu")
		(net 433)
	)
	(segment
		(start 251.3 76.8)
		(end 252.1 77.6)
		(width 0.1)
		(layer "In3.Cu")
		(net 433)
	)
	(segment
		(start 222.8 77.2)
		(end 223.2 76.8)
		(width 0.1)
		(layer "In3.Cu")
		(net 433)
	)
	(segment
		(start 213.5 133.5)
		(end 214 134)
		(width 0.256)
		(layer "F.Cu")
		(net 434)
	)
	(via
		(at 214 134)
		(size 0.45)
		(drill 0.2)
		(layers "F.Cu" "B.Cu")
		(net 434)
	)
	(via
		(at 215.5 75.8)
		(size 0.45)
		(drill 0.2)
		(layers "F.Cu" "B.Cu")
		(net 434)
	)
	(segment
		(start 215.499999 77.414999)
		(end 215.5 75.8)
		(width 0.1)
		(layer "B.Cu")
		(net 434)
	)
	(segment
		(start 216.3 134.6)
		(end 220.501474 134.6)
		(width 0.1)
		(layer "In3.Cu")
		(net 434)
	)
	(segment
		(start 251.5 76.4)
		(end 222.95 76.4)
		(width 0.1)
		(layer "In3.Cu")
		(net 434)
	)
	(segment
		(start 222.55 76.8)
		(end 218 76.8)
		(width 0.1)
		(layer "In3.Cu")
		(net 434)
	)
	(segment
		(start 252 87.3)
		(end 254.9 84.4)
		(width 0.1)
		(layer "In3.Cu")
		(net 434)
	)
	(segment
		(start 252 93.5)
		(end 252 87.3)
		(width 0.1)
		(layer "In3.Cu")
		(net 434)
	)
	(segment
		(start 254.9 79.8)
		(end 251.5 76.4)
		(width 0.1)
		(layer "In3.Cu")
		(net 434)
	)
	(segment
		(start 217 75.8)
		(end 215.5 75.8)
		(width 0.1)
		(layer "In3.Cu")
		(net 434)
	)
	(segment
		(start 214.375 133.625)
		(end 215.325 133.625)
		(width 0.1)
		(layer "In3.Cu")
		(net 434)
	)
	(segment
		(start 226.35 134.85)
		(end 228.3 132.9)
		(width 0.1)
		(layer "In3.Cu")
		(net 434)
	)
	(segment
		(start 214 134)
		(end 214.375 133.625)
		(width 0.1)
		(layer "In3.Cu")
		(net 434)
	)
	(segment
		(start 254.9 84.4)
		(end 254.9 79.8)
		(width 0.1)
		(layer "In3.Cu")
		(net 434)
	)
	(segment
		(start 228.3 106.799998)
		(end 232.699998 102.4)
		(width 0.1)
		(layer "In3.Cu")
		(net 434)
	)
	(segment
		(start 232.699998 102.4)
		(end 243.1 102.4)
		(width 0.1)
		(layer "In3.Cu")
		(net 434)
	)
	(segment
		(start 222.95 76.4)
		(end 222.55 76.8)
		(width 0.1)
		(layer "In3.Cu")
		(net 434)
	)
	(segment
		(start 220.501474 134.6)
		(end 220.751474 134.85)
		(width 0.1)
		(layer "In3.Cu")
		(net 434)
	)
	(segment
		(start 243.1 102.4)
		(end 252 93.5)
		(width 0.1)
		(layer "In3.Cu")
		(net 434)
	)
	(segment
		(start 218 76.8)
		(end 217 75.8)
		(width 0.1)
		(layer "In3.Cu")
		(net 434)
	)
	(segment
		(start 215.325 133.625)
		(end 216.3 134.6)
		(width 0.1)
		(layer "In3.Cu")
		(net 434)
	)
	(segment
		(start 228.3 132.9)
		(end 228.3 106.799998)
		(width 0.1)
		(layer "In3.Cu")
		(net 434)
	)
	(segment
		(start 220.751474 134.85)
		(end 226.35 134.85)
		(width 0.1)
		(layer "In3.Cu")
		(net 434)
	)
	(segment
		(start 156.775002 93.432002)
		(end 156.920001 93.577001)
		(width 0.16)
		(layer "F.Cu")
		(net 437)
	)
	(segment
		(start 198.009838 117.009838)
		(end 198.009838 116.978606)
		(width 0.256)
		(layer "F.Cu")
		(net 437)
	)
	(segment
		(start 198.5 117.5)
		(end 198.009838 117.009838)
		(width 0.256)
		(layer "F.Cu")
		(net 437)
	)
	(segment
		(start 156.606804 93.432001)
		(end 156.285001 93.753804)
		(width 0.16)
		(layer "F.Cu")
		(net 437)
	)
	(segment
		(start 156.285001 93.753804)
		(end 156.285001 93.935001)
		(width 0.16)
		(layer "F.Cu")
		(net 437)
	)
	(segment
		(start 156.775002 93.432002)
		(end 156.606804 93.432001)
		(width 0.16)
		(layer "F.Cu")
		(net 437)
	)
	(via
		(at 156.920001 93.577001)
		(size 0.45)
		(drill 0.2)
		(layers "F.Cu" "B.Cu")
		(net 437)
	)
	(via
		(at 198.009838 116.978606)
		(size 0.45)
		(drill 0.2)
		(layers "F.Cu" "B.Cu")
		(net 437)
	)
	(segment
		(start 157.762501 93.668501)
		(end 157.762501 93.764088)
		(width 0.114)
		(layer "In5.Cu")
		(net 437)
	)
	(segment
		(start 158.212501 93.764088)
		(end 158.212501 93.668501)
		(width 0.114)
		(layer "In5.Cu")
		(net 437)
	)
	(segment
		(start 157.053501 93.443501)
		(end 157.537501 93.443501)
		(width 0.114)
		(layer "In5.Cu")
		(net 437)
	)
	(segment
		(start 158.487501 93.443501)
		(end 158.959441 93.443501)
		(width 0.114)
		(layer "In5.Cu")
		(net 437)
	)
	(segment
		(start 182.900562 92.881422)
		(end 182.68848 93.093505)
		(width 0.114)
		(layer "In5.Cu")
		(net 437)
	)
	(segment
		(start 183.890511 93.871372)
		(end 183.890511 93.871371)
		(width 0.114)
		(layer "In5.Cu")
		(net 437)
	)
	(segment
		(start 198.400001 117.400001)
		(end 200.313579 117.400001)
		(width 0.1)
		(layer "In5.Cu")
		(net 437)
	)
	(segment
		(start 159.599441 92.803501)
		(end 167.799441 92.803501)
		(width 0.114)
		(layer "In5.Cu")
		(net 437)
	)
	(segment
		(start 182.900562 92.881423)
		(end 182.900562 92.881422)
		(width 0.114)
		(layer "In5.Cu")
		(net 437)
	)
	(segment
		(start 183.890512 93.579336)
		(end 183.890512 93.579337)
		(width 0.114)
		(layer "In5.Cu")
		(net 437)
	)
	(segment
		(start 183.678429 94.781369)
		(end 200.406501 111.509441)
		(width 0.114)
		(layer "In5.Cu")
		(net 437)
	)
	(segment
		(start 156.920001 93.577001)
		(end 157.053501 93.443501)
		(width 0.114)
		(layer "In5.Cu")
		(net 437)
	)
	(segment
		(start 200.406501 111.509441)
		(end 200.406501 113.405001)
		(width 0.114)
		(layer "In5.Cu")
		(net 437)
	)
	(segment
		(start 182.396446 92.801471)
		(end 182.608527 92.589387)
		(width 0.114)
		(layer "In5.Cu")
		(net 437)
	)
	(segment
		(start 200.450001 117.263579)
		(end 200.450001 113.448501)
		(width 0.1)
		(layer "In5.Cu")
		(net 437)
	)
	(segment
		(start 182.900563 92.589387)
		(end 182.900563 92.589388)
		(width 0.114)
		(layer "In5.Cu")
		(net 437)
	)
	(segment
		(start 183.386395 93.79142)
		(end 183.598476 93.579336)
		(width 0.114)
		(layer "In5.Cu")
		(net 437)
	)
	(segment
		(start 167.799441 92.803501)
		(end 169.059441 91.543501)
		(width 0.114)
		(layer "In5.Cu")
		(net 437)
	)
	(segment
		(start 198.000001 117.000001)
		(end 198.400001 117.400001)
		(width 0.1)
		(layer "In5.Cu")
		(net 437)
	)
	(segment
		(start 158.959441 93.443501)
		(end 159.599441 92.803501)
		(width 0.114)
		(layer "In5.Cu")
		(net 437)
	)
	(segment
		(start 158.437501 93.443501)
		(end 158.487501 93.443501)
		(width 0.114)
		(layer "In5.Cu")
		(net 437)
	)
	(segment
		(start 180.440561 91.543501)
		(end 181.69853 92.801469)
		(width 0.114)
		(layer "In5.Cu")
		(net 437)
	)
	(segment
		(start 200.450001 113.448501)
		(end 200.406501 113.405001)
		(width 0.1)
		(layer "In5.Cu")
		(net 437)
	)
	(segment
		(start 200.313579 117.400001)
		(end 200.450001 117.263579)
		(width 0.1)
		(layer "In5.Cu")
		(net 437)
	)
	(segment
		(start 169.059441 91.543501)
		(end 180.440561 91.543501)
		(width 0.114)
		(layer "In5.Cu")
		(net 437)
	)
	(segment
		(start 182.68848 93.791419)
		(end 182.68848 93.79142)
		(width 0.114)
		(layer "In5.Cu")
		(net 437)
	)
	(segment
		(start 183.678429 94.781368)
		(end 183.678429 94.781369)
		(width 0.114)
		(layer "In5.Cu")
		(net 437)
	)
	(segment
		(start 183.890511 93.871371)
		(end 183.678429 94.083454)
		(width 0.114)
		(layer "In5.Cu")
		(net 437)
	)
	(segment
		(start 182.68848 93.79142)
		(end 182.688479 93.791418)
		(width 0.114)
		(layer "In5.Cu")
		(net 437)
	)
	(arc
		(start 157.987501 93.989088)
		(mid 158.1466 93.923187)
		(end 158.212501 93.764088)
		(width 0.114)
		(layer "In5.Cu")
		(net 437)
	)
	(arc
		(start 157.537501 93.443501)
		(mid 157.6966 93.509402)
		(end 157.762501 93.668501)
		(width 0.114)
		(layer "In5.Cu")
		(net 437)
	)
	(arc
		(start 183.678429 94.083454)
		(mid 183.533886 94.432411)
		(end 183.678429 94.781368)
		(width 0.114)
		(layer "In5.Cu")
		(net 437)
	)
	(arc
		(start 182.688479 93.791418)
		(mid 183.037438 93.935963)
		(end 183.386395 93.79142)
		(width 0.114)
		(layer "In5.Cu")
		(net 437)
	)
	(arc
		(start 182.900563 92.589388)
		(mid 182.961045 92.735406)
		(end 182.900562 92.881423)
		(width 0.114)
		(layer "In5.Cu")
		(net 437)
	)
	(arc
		(start 182.68848 93.093505)
		(mid 182.543937 93.442462)
		(end 182.68848 93.791419)
		(width 0.114)
		(layer "In5.Cu")
		(net 437)
	)
	(arc
		(start 181.69853 92.801469)
		(mid 182.047489 92.946014)
		(end 182.396446 92.801471)
		(width 0.114)
		(layer "In5.Cu")
		(net 437)
	)
	(arc
		(start 182.608527 92.589387)
		(mid 182.754546 92.528905)
		(end 182.900563 92.589387)
		(width 0.114)
		(layer "In5.Cu")
		(net 437)
	)
	(arc
		(start 157.762501 93.764088)
		(mid 157.828402 93.923187)
		(end 157.987501 93.989088)
		(width 0.114)
		(layer "In5.Cu")
		(net 437)
	)
	(arc
		(start 183.598476 93.579336)
		(mid 183.744495 93.518854)
		(end 183.890512 93.579336)
		(width 0.114)
		(layer "In5.Cu")
		(net 437)
	)
	(arc
		(start 183.890512 93.579337)
		(mid 183.950994 93.725355)
		(end 183.890511 93.871372)
		(width 0.114)
		(layer "In5.Cu")
		(net 437)
	)
	(arc
		(start 158.212501 93.668501)
		(mid 158.278402 93.509402)
		(end 158.437501 93.443501)
		(width 0.114)
		(layer "In5.Cu")
		(net 437)
	)
	(segment
		(start 211.5 138.5)
		(end 212 139)
		(width 0.256)
		(layer "F.Cu")
		(net 438)
	)
	(via
		(at 218.1 76.2)
		(size 0.45)
		(drill 0.2)
		(layers "F.Cu" "B.Cu")
		(net 438)
	)
	(via
		(at 212 139)
		(size 0.45)
		(drill 0.2)
		(layers "F.Cu" "B.Cu")
		(net 438)
	)
	(segment
		(start 218.099999 77.414999)
		(end 218.1 76.2)
		(width 0.1)
		(layer "B.Cu")
		(net 438)
	)
	(segment
		(start 254.099998 97.3)
		(end 253.8 97.3)
		(width 0.1)
		(layer "In3.Cu")
		(net 438)
	)
	(segment
		(start 222.8 76.2)
		(end 251.6 76.2)
		(width 0.1)
		(layer "In3.Cu")
		(net 438)
	)
	(segment
		(start 218.1 76.2)
		(end 218.5 76.6)
		(width 0.1)
		(layer "In3.Cu")
		(net 438)
	)
	(segment
		(start 218.5 76.6)
		(end 222.4 76.6)
		(width 0.1)
		(layer "In3.Cu")
		(net 438)
	)
	(segment
		(start 227.2 137.8)
		(end 222.252946 137.8)
		(width 0.1)
		(layer "In3.Cu")
		(net 438)
	)
	(segment
		(start 255.9 87.6)
		(end 255.9 95.499998)
		(width 0.1)
		(layer "In3.Cu")
		(net 438)
	)
	(segment
		(start 244.8 106.3)
		(end 233.999998 106.3)
		(width 0.1)
		(layer "In3.Cu")
		(net 438)
	)
	(segment
		(start 222.252946 137.8)
		(end 222.052947 138)
		(width 0.1)
		(layer "In3.Cu")
		(net 438)
	)
	(segment
		(start 233.999998 106.3)
		(end 232.2 108.099998)
		(width 0.1)
		(layer "In3.Cu")
		(net 438)
	)
	(segment
		(start 256.3 85.3)
		(end 255.5 86.1)
		(width 0.1)
		(layer "In3.Cu")
		(net 438)
	)
	(segment
		(start 212.625 138.375)
		(end 212 139)
		(width 0.1)
		(layer "In3.Cu")
		(net 438)
	)
	(segment
		(start 255.9 95.499998)
		(end 254.099998 97.3)
		(width 0.1)
		(layer "In3.Cu")
		(net 438)
	)
	(segment
		(start 251.6 76.2)
		(end 256.3 80.9)
		(width 0.1)
		(layer "In3.Cu")
		(net 438)
	)
	(segment
		(start 216.025 138.375)
		(end 212.625 138.375)
		(width 0.1)
		(layer "In3.Cu")
		(net 438)
	)
	(segment
		(start 232.2 108.099998)
		(end 232.2 132.8)
		(width 0.1)
		(layer "In3.Cu")
		(net 438)
	)
	(segment
		(start 255.5 87.2)
		(end 255.9 87.6)
		(width 0.1)
		(layer "In3.Cu")
		(net 438)
	)
	(segment
		(start 222.4 76.6)
		(end 222.8 76.2)
		(width 0.1)
		(layer "In3.Cu")
		(net 438)
	)
	(segment
		(start 222.052947 138)
		(end 216.4 138)
		(width 0.1)
		(layer "In3.Cu")
		(net 438)
	)
	(segment
		(start 253.8 97.3)
		(end 244.8 106.3)
		(width 0.1)
		(layer "In3.Cu")
		(net 438)
	)
	(segment
		(start 256.3 80.9)
		(end 256.3 85.3)
		(width 0.1)
		(layer "In3.Cu")
		(net 438)
	)
	(segment
		(start 232.2 132.8)
		(end 227.2 137.8)
		(width 0.1)
		(layer "In3.Cu")
		(net 438)
	)
	(segment
		(start 255.5 86.1)
		(end 255.5 87.2)
		(width 0.1)
		(layer "In3.Cu")
		(net 438)
	)
	(segment
		(start 216.4 138)
		(end 216.025 138.375)
		(width 0.1)
		(layer "In3.Cu")
		(net 438)
	)
	(segment
		(start 215.3 143)
		(end 215.6 142.7)
		(width 0.1)
		(layer "F.Cu")
		(net 439)
	)
	(segment
		(start 215.6 142.7)
		(end 215.6 140)
		(width 0.1)
		(layer "F.Cu")
		(net 439)
	)
	(segment
		(start 213.5 143.5)
		(end 214 143)
		(width 0.1)
		(layer "F.Cu")
		(net 439)
	)
	(segment
		(start 214 143)
		(end 215.3 143)
		(width 0.1)
		(layer "F.Cu")
		(net 439)
	)
	(via
		(at 220.7 75.6)
		(size 0.45)
		(drill 0.2)
		(layers "F.Cu" "B.Cu")
		(net 439)
	)
	(via
		(at 215.6 140)
		(size 0.45)
		(drill 0.2)
		(layers "F.Cu" "B.Cu")
		(net 439)
	)
	(segment
		(start 220.699999 77.414999)
		(end 220.7 75.6)
		(width 0.1)
		(layer "B.Cu")
		(net 439)
	)
	(segment
		(start 252 75.4)
		(end 220.9 75.4)
		(width 0.1)
		(layer "In3.Cu")
		(net 439)
	)
	(segment
		(start 217.431586 140.4)
		(end 218.031586 141)
		(width 0.1)
		(layer "In3.Cu")
		(net 439)
	)
	(segment
		(start 233.75 108.95)
		(end 234.6 108.1)
		(width 0.1)
		(layer "In3.Cu")
		(net 439)
	)
	(segment
		(start 218.031586 141)
		(end 225.799999 141)
		(width 0.1)
		(layer "In3.Cu")
		(net 439)
	)
	(segment
		(start 234.2 125.625)
		(end 233.75 125.175)
		(width 0.1)
		(layer "In3.Cu")
		(net 439)
	)
	(segment
		(start 220.9 75.4)
		(end 220.7 75.6)
		(width 0.1)
		(layer "In3.Cu")
		(net 439)
	)
	(segment
		(start 225.799999 141)
		(end 227.749999 139.05)
		(width 0.1)
		(layer "In3.Cu")
		(net 439)
	)
	(segment
		(start 229.180331 139.05)
		(end 230.625 137.605331)
		(width 0.1)
		(layer "In3.Cu")
		(net 439)
	)
	(segment
		(start 230.625 136.311827)
		(end 234.2 132.736827)
		(width 0.1)
		(layer "In3.Cu")
		(net 439)
	)
	(segment
		(start 227.749999 139.05)
		(end 229.180331 139.05)
		(width 0.1)
		(layer "In3.Cu")
		(net 439)
	)
	(segment
		(start 247.6 108.1)
		(end 257.1 98.6)
		(width 0.1)
		(layer "In3.Cu")
		(net 439)
	)
	(segment
		(start 215.6 140)
		(end 216 140.4)
		(width 0.1)
		(layer "In3.Cu")
		(net 439)
	)
	(segment
		(start 230.625 137.605331)
		(end 230.625 136.311827)
		(width 0.1)
		(layer "In3.Cu")
		(net 439)
	)
	(segment
		(start 234.6 108.1)
		(end 247.6 108.1)
		(width 0.1)
		(layer "In3.Cu")
		(net 439)
	)
	(segment
		(start 233.75 125.175)
		(end 233.75 108.95)
		(width 0.1)
		(layer "In3.Cu")
		(net 439)
	)
	(segment
		(start 257.1 80.5)
		(end 252 75.4)
		(width 0.1)
		(layer "In3.Cu")
		(net 439)
	)
	(segment
		(start 234.2 132.736827)
		(end 234.2 125.625)
		(width 0.1)
		(layer "In3.Cu")
		(net 439)
	)
	(segment
		(start 257.1 98.6)
		(end 257.1 80.5)
		(width 0.1)
		(layer "In3.Cu")
		(net 439)
	)
	(segment
		(start 216 140.4)
		(end 217.431586 140.4)
		(width 0.1)
		(layer "In3.Cu")
		(net 439)
	)
	(segment
		(start 158.045002 103.592002)
		(end 157.876804 103.592001)
		(width 0.16)
		(layer "F.Cu")
		(net 440)
	)
	(segment
		(start 198.045 123.045)
		(end 198.5 123.5)
		(width 0.256)
		(layer "F.Cu")
		(net 440)
	)
	(segment
		(start 158.045002 103.592002)
		(end 158.190001 103.737001)
		(width 0.16)
		(layer "F.Cu")
		(net 440)
	)
	(segment
		(start 157.876804 103.592001)
		(end 157.555001 103.913804)
		(width 0.16)
		(layer "F.Cu")
		(net 440)
	)
	(segment
		(start 157.555001 103.913804)
		(end 157.555001 104.095001)
		(width 0.16)
		(layer "F.Cu")
		(net 440)
	)
	(segment
		(start 198.025001 123.045)
		(end 198.045 123.045)
		(width 0.256)
		(layer "F.Cu")
		(net 440)
	)
	(via
		(at 158.190001 103.737001)
		(size 0.45)
		(drill 0.2)
		(layers "F.Cu" "B.Cu")
		(net 440)
	)
	(via
		(at 198.025001 123.045)
		(size 0.45)
		(drill 0.2)
		(layers "F.Cu" "B.Cu")
		(net 440)
	)
	(segment
		(start 197.600001 123.400001)
		(end 196.816423 123.400001)
		(width 0.1)
		(layer "In7.Cu")
		(net 440)
	)
	(segment
		(start 172.590561 123.556501)
		(end 173.290561 122.856501)
		(width 0.114)
		(layer "In7.Cu")
		(net 440)
	)
	(segment
		(start 159.940561 101.406501)
		(end 161.856501 101.406501)
		(width 0.114)
		(layer "In7.Cu")
		(net 440)
	)
	(segment
		(start 158.455441 101.406501)
		(end 158.698601 101.649661)
		(width 0.114)
		(layer "In7.Cu")
		(net 440)
	)
	(segment
		(start 162.975001 101.550001)
		(end 162.975001 102.015452)
		(width 0.114)
		(layer "In7.Cu")
		(net 440)
	)
	(segment
		(start 169.128501 101.975561)
		(end 169.128501 123.225079)
		(width 0.114)
		(layer "In7.Cu")
		(net 440)
	)
	(segment
		(start 157.940561 101.406501)
		(end 158.455441 101.406501)
		(width 0.114)
		(layer "In7.Cu")
		(net 440)
	)
	(segment
		(start 173.290561 122.856501)
		(end 183.405001 122.856501)
		(width 0.114)
		(layer "In7.Cu")
		(net 440)
	)
	(segment
		(start 196.266423 122.400001)
		(end 193.658579 122.400001)
		(width 0.1)
		(layer "In7.Cu")
		(net 440)
	)
	(segment
		(start 162.971951 101.550001)
		(end 162.975001 101.550001)
		(width 0.114)
		(layer "In7.Cu")
		(net 440)
	)
	(segment
		(start 183.448501 122.900001)
		(end 183.405001 122.856501)
		(width 0.1)
		(layer "In7.Cu")
		(net 440)
	)
	(segment
		(start 169.128501 123.225079)
		(end 169.459923 123.556501)
		(width 0.114)
		(layer "In7.Cu")
		(net 440)
	)
	(segment
		(start 168.559441 101.406501)
		(end 169.128501 101.975561)
		(width 0.114)
		(layer "In7.Cu")
		(net 440)
	)
	(segment
		(start 158.698601 101.649661)
		(end 159.697401 101.649661)
		(width 0.114)
		(layer "In7.Cu")
		(net 440)
	)
	(segment
		(start 162.971951 101.08455)
		(end 162.971951 101.550001)
		(width 0.114)
		(layer "In7.Cu")
		(net 440)
	)
	(segment
		(start 163.338001 102.015452)
		(end 163.338001 101.871951)
		(width 0.114)
		(layer "In7.Cu")
		(net 440)
	)
	(segment
		(start 158.056501 103.603501)
		(end 157.750561 103.603501)
		(width 0.114)
		(layer "In7.Cu")
		(net 440)
	)
	(segment
		(start 163.153451 102.193902)
		(end 163.159551 102.193902)
		(width 0.114)
		(layer "In7.Cu")
		(net 440)
	)
	(segment
		(start 196.600001 123.183579)
		(end 196.600001 122.733579)
		(width 0.1)
		(layer "In7.Cu")
		(net 440)
	)
	(segment
		(start 162.500401 100.6191)
		(end 162.506501 100.6191)
		(width 0.114)
		(layer "In7.Cu")
		(net 440)
	)
	(segment
		(start 162.034951 101.228051)
		(end 162.034951 101.08455)
		(width 0.114)
		(layer "In7.Cu")
		(net 440)
	)
	(segment
		(start 196.816423 123.400001)
		(end 196.600001 123.183579)
		(width 0.1)
		(layer "In7.Cu")
		(net 440)
	)
	(segment
		(start 163.803451 101.406501)
		(end 168.559441 101.406501)
		(width 0.114)
		(layer "In7.Cu")
		(net 440)
	)
	(segment
		(start 169.459923 123.556501)
		(end 172.590561 123.556501)
		(width 0.114)
		(layer "In7.Cu")
		(net 440)
	)
	(segment
		(start 198.000001 123.000001)
		(end 197.600001 123.400001)
		(width 0.1)
		(layer "In7.Cu")
		(net 440)
	)
	(segment
		(start 159.697401 101.649661)
		(end 159.940561 101.406501)
		(width 0.114)
		(layer "In7.Cu")
		(net 440)
	)
	(segment
		(start 157.395497 103.248437)
		(end 157.395497 101.951565)
		(width 0.114)
		(layer "In7.Cu")
		(net 440)
	)
	(segment
		(start 193.158579 122.900001)
		(end 183.448501 122.900001)
		(width 0.1)
		(layer "In7.Cu")
		(net 440)
	)
	(segment
		(start 158.190001 103.737001)
		(end 158.056501 103.603501)
		(width 0.114)
		(layer "In7.Cu")
		(net 440)
	)
	(segment
		(start 157.750561 103.603501)
		(end 157.395497 103.248437)
		(width 0.114)
		(layer "In7.Cu")
		(net 440)
	)
	(segment
		(start 196.600001 122.733579)
		(end 196.266423 122.400001)
		(width 0.1)
		(layer "In7.Cu")
		(net 440)
	)
	(segment
		(start 193.658579 122.400001)
		(end 193.158579 122.900001)
		(width 0.1)
		(layer "In7.Cu")
		(net 440)
	)
	(segment
		(start 157.395497 101.951565)
		(end 157.940561 101.406501)
		(width 0.114)
		(layer "In7.Cu")
		(net 440)
	)
	(arc
		(start 163.159551 102.193902)
		(mid 163.285734 102.141635)
		(end 163.338001 102.015452)
		(width 0.114)
		(layer "In7.Cu")
		(net 440)
	)
	(arc
		(start 162.506501 100.6191)
		(mid 162.835624 100.755427)
		(end 162.971951 101.08455)
		(width 0.114)
		(layer "In7.Cu")
		(net 440)
	)
	(arc
		(start 161.856501 101.406501)
		(mid 161.982684 101.354234)
		(end 162.034951 101.228051)
		(width 0.114)
		(layer "In7.Cu")
		(net 440)
	)
	(arc
		(start 162.034951 101.08455)
		(mid 162.171278 100.755427)
		(end 162.500401 100.6191)
		(width 0.114)
		(layer "In7.Cu")
		(net 440)
	)
	(arc
		(start 163.338001 101.871951)
		(mid 163.474328 101.542828)
		(end 163.803451 101.406501)
		(width 0.114)
		(layer "In7.Cu")
		(net 440)
	)
	(arc
		(start 162.975001 102.015452)
		(mid 163.027268 102.141635)
		(end 163.153451 102.193902)
		(width 0.114)
		(layer "In7.Cu")
		(net 440)
	)
	(segment
		(start 157.555001 103.006198)
		(end 157.876804 103.328001)
		(width 0.16)
		(layer "F.Cu")
		(net 441)
	)
	(segment
		(start 158.045002 103.328)
		(end 158.190001 103.183001)
		(width 0.16)
		(layer "F.Cu")
		(net 441)
	)
	(segment
		(start 157.555001 102.825001)
		(end 157.555001 103.006198)
		(width 0.16)
		(layer "F.Cu")
		(net 441)
	)
	(segment
		(start 198.5 124.5)
		(end 198 124)
		(width 0.256)
		(layer "F.Cu")
		(net 441)
	)
	(segment
		(start 158.045002 103.328)
		(end 157.876804 103.328001)
		(width 0.16)
		(layer "F.Cu")
		(net 441)
	)
	(via
		(at 198 124)
		(size 0.45)
		(drill 0.2)
		(layers "F.Cu" "B.Cu")
		(net 441)
	)
	(via
		(at 158.190001 103.183001)
		(size 0.45)
		(drill 0.2)
		(layers "F.Cu" "B.Cu")
		(net 441)
	)
	(segment
		(start 196.183579 122.600001)
		(end 193.741423 122.600001)
		(width 0.1)
		(layer "In7.Cu")
		(net 441)
	)
	(segment
		(start 173.409441 123.143501)
		(end 183.405001 123.143501)
		(width 0.114)
		(layer "In7.Cu")
		(net 441)
	)
	(segment
		(start 162.500401 100.9061)
		(end 162.506501 100.9061)
		(width 0.114)
		(layer "In7.Cu")
		(net 441)
	)
	(segment
		(start 198.000001 124.000001)
		(end 197.600001 123.600001)
		(width 0.1)
		(layer "In7.Cu")
		(net 441)
	)
	(segment
		(start 162.684951 101.550001)
		(end 162.688001 101.550001)
		(width 0.114)
		(layer "In7.Cu")
		(net 441)
	)
	(segment
		(start 158.855661 102.211661)
		(end 158.855661 102.502804)
		(width 0.114)
		(layer "In7.Cu")
		(net 441)
	)
	(segment
		(start 197.600001 123.600001)
		(end 196.733579 123.600001)
		(width 0.1)
		(layer "In7.Cu")
		(net 441)
	)
	(segment
		(start 157.869441 103.316501)
		(end 157.682497 103.129557)
		(width 0.114)
		(layer "In7.Cu")
		(net 441)
	)
	(segment
		(start 193.741423 122.600001)
		(end 193.241423 123.100001)
		(width 0.1)
		(layer "In7.Cu")
		(net 441)
	)
	(segment
		(start 157.682497 102.070445)
		(end 158.059441 101.693501)
		(width 0.114)
		(layer "In7.Cu")
		(net 441)
	)
	(segment
		(start 158.059441 101.693501)
		(end 158.336561 101.693501)
		(width 0.114)
		(layer "In7.Cu")
		(net 441)
	)
	(segment
		(start 183.448501 123.100001)
		(end 183.405001 123.143501)
		(width 0.1)
		(layer "In7.Cu")
		(net 441)
	)
	(segment
		(start 162.684951 101.08455)
		(end 162.684951 101.550001)
		(width 0.114)
		(layer "In7.Cu")
		(net 441)
	)
	(segment
		(start 163.803451 101.693501)
		(end 168.440561 101.693501)
		(width 0.114)
		(layer "In7.Cu")
		(net 441)
	)
	(segment
		(start 160.059441 101.693501)
		(end 161.856501 101.693501)
		(width 0.114)
		(layer "In7.Cu")
		(net 441)
	)
	(segment
		(start 158.336561 101.693501)
		(end 158.579721 101.936661)
		(width 0.114)
		(layer "In7.Cu")
		(net 441)
	)
	(segment
		(start 196.400001 122.816423)
		(end 196.183579 122.600001)
		(width 0.1)
		(layer "In7.Cu")
		(net 441)
	)
	(segment
		(start 159.816281 101.936661)
		(end 160.059441 101.693501)
		(width 0.114)
		(layer "In7.Cu")
		(net 441)
	)
	(segment
		(start 168.841501 123.343959)
		(end 169.341043 123.843501)
		(width 0.114)
		(layer "In7.Cu")
		(net 441)
	)
	(segment
		(start 172.709441 123.843501)
		(end 173.409441 123.143501)
		(width 0.114)
		(layer "In7.Cu")
		(net 441)
	)
	(segment
		(start 163.153451 102.480902)
		(end 163.159551 102.480902)
		(width 0.114)
		(layer "In7.Cu")
		(net 441)
	)
	(segment
		(start 162.688001 101.550001)
		(end 162.688001 102.015452)
		(width 0.114)
		(layer "In7.Cu")
		(net 441)
	)
	(segment
		(start 162.321951 101.228051)
		(end 162.321951 101.08455)
		(width 0.114)
		(layer "In7.Cu")
		(net 441)
	)
	(segment
		(start 158.190001 103.183001)
		(end 158.056501 103.316501)
		(width 0.114)
		(layer "In7.Cu")
		(net 441)
	)
	(segment
		(start 193.241423 123.100001)
		(end 183.448501 123.100001)
		(width 0.1)
		(layer "In7.Cu")
		(net 441)
	)
	(segment
		(start 158.056501 103.316501)
		(end 157.869441 103.316501)
		(width 0.114)
		(layer "In7.Cu")
		(net 441)
	)
	(segment
		(start 168.440561 101.693501)
		(end 168.841501 102.094441)
		(width 0.114)
		(layer "In7.Cu")
		(net 441)
	)
	(segment
		(start 196.400001 123.266423)
		(end 196.400001 122.816423)
		(width 0.1)
		(layer "In7.Cu")
		(net 441)
	)
	(segment
		(start 169.341043 123.843501)
		(end 172.709441 123.843501)
		(width 0.114)
		(layer "In7.Cu")
		(net 441)
	)
	(segment
		(start 159.680661 101.936661)
		(end 159.816281 101.936661)
		(width 0.114)
		(layer "In7.Cu")
		(net 441)
	)
	(segment
		(start 157.682497 103.129557)
		(end 157.682497 102.070445)
		(width 0.114)
		(layer "In7.Cu")
		(net 441)
	)
	(segment
		(start 158.579721 101.936661)
		(end 158.580661 101.936661)
		(width 0.114)
		(layer "In7.Cu")
		(net 441)
	)
	(segment
		(start 159.405661 102.502804)
		(end 159.405661 102.211661)
		(width 0.114)
		(layer "In7.Cu")
		(net 441)
	)
	(segment
		(start 168.841501 102.094441)
		(end 168.841501 123.343959)
		(width 0.114)
		(layer "In7.Cu")
		(net 441)
	)
	(segment
		(start 163.625001 102.015452)
		(end 163.625001 101.871951)
		(width 0.114)
		(layer "In7.Cu")
		(net 441)
	)
	(segment
		(start 196.733579 123.600001)
		(end 196.400001 123.266423)
		(width 0.1)
		(layer "In7.Cu")
		(net 441)
	)
	(arc
		(start 158.855661 102.502804)
		(mid 158.936207 102.697258)
		(end 159.130661 102.777804)
		(width 0.114)
		(layer "In7.Cu")
		(net 441)
	)
	(arc
		(start 162.506501 100.9061)
		(mid 162.632684 100.958367)
		(end 162.684951 101.08455)
		(width 0.114)
		(layer "In7.Cu")
		(net 441)
	)
	(arc
		(start 163.625001 101.871951)
		(mid 163.677268 101.745768)
		(end 163.803451 101.693501)
		(width 0.114)
		(layer "In7.Cu")
		(net 441)
	)
	(arc
		(start 162.688001 102.015452)
		(mid 162.824328 102.344575)
		(end 163.153451 102.480902)
		(width 0.114)
		(layer "In7.Cu")
		(net 441)
	)
	(arc
		(start 161.856501 101.693501)
		(mid 162.185624 101.557174)
		(end 162.321951 101.228051)
		(width 0.114)
		(layer "In7.Cu")
		(net 441)
	)
	(arc
		(start 159.405661 102.211661)
		(mid 159.486207 102.017207)
		(end 159.680661 101.936661)
		(width 0.114)
		(layer "In7.Cu")
		(net 441)
	)
	(arc
		(start 163.159551 102.480902)
		(mid 163.488674 102.344575)
		(end 163.625001 102.015452)
		(width 0.114)
		(layer "In7.Cu")
		(net 441)
	)
	(arc
		(start 162.321951 101.08455)
		(mid 162.374218 100.958367)
		(end 162.500401 100.9061)
		(width 0.114)
		(layer "In7.Cu")
		(net 441)
	)
	(arc
		(start 158.580661 101.936661)
		(mid 158.775115 102.017207)
		(end 158.855661 102.211661)
		(width 0.114)
		(layer "In7.Cu")
		(net 441)
	)
	(arc
		(start 159.130661 102.777804)
		(mid 159.325115 102.697258)
		(end 159.405661 102.502804)
		(width 0.114)
		(layer "In7.Cu")
		(net 441)
	)
	(segment
		(start 212.5 138.5)
		(end 213 139)
		(width 0.256)
		(layer "F.Cu")
		(net 442)
	)
	(via
		(at 255.9 87)
		(size 0.45)
		(drill 0.2)
		(layers "F.Cu" "B.Cu")
		(net 442)
	)
	(via
		(at 213 139)
		(size 0.45)
		(drill 0.2)
		(layers "F.Cu" "B.Cu")
		(net 442)
	)
	(segment
		(start 255.9 87)
		(end 254.8 88.1)
		(width 0.1)
		(layer "B.Cu")
		(net 442)
	)
	(segment
		(start 254.1 88.1)
		(end 253.9 87.9)
		(width 0.1)
		(layer "B.Cu")
		(net 442)
	)
	(segment
		(start 240.315 87.9)
		(end 237.599999 85.184999)
		(width 0.1)
		(layer "B.Cu")
		(net 442)
	)
	(segment
		(start 253.9 87.9)
		(end 240.315 87.9)
		(width 0.1)
		(layer "B.Cu")
		(net 442)
	)
	(segment
		(start 254.8 88.1)
		(end 254.1 88.1)
		(width 0.1)
		(layer "B.Cu")
		(net 442)
	)
	(segment
		(start 246.3 106.6)
		(end 234.099998 106.6)
		(width 0.1)
		(layer "In3.Cu")
		(net 442)
	)
	(segment
		(start 234.099998 106.6)
		(end 232.5 108.199998)
		(width 0.1)
		(layer "In3.Cu")
		(net 442)
	)
	(segment
		(start 213.425 138.575)
		(end 213 139)
		(width 0.1)
		(layer "In3.Cu")
		(net 442)
	)
	(segment
		(start 232.5 108.199998)
		(end 232.5 132.782843)
		(width 0.1)
		(layer "In3.Cu")
		(net 442)
	)
	(segment
		(start 232.5 132.782843)
		(end 227.282843 138)
		(width 0.1)
		(layer "In3.Cu")
		(net 442)
	)
	(segment
		(start 227.282843 138)
		(end 222.335789 138)
		(width 0.1)
		(layer "In3.Cu")
		(net 442)
	)
	(segment
		(start 256.1 96.8)
		(end 246.3 106.6)
		(width 0.1)
		(layer "In3.Cu")
		(net 442)
	)
	(segment
		(start 256.1 87.2)
		(end 256.1 96.8)
		(width 0.1)
		(layer "In3.Cu")
		(net 442)
	)
	(segment
		(start 222.13579 138.2)
		(end 216.5 138.2)
		(width 0.1)
		(layer "In3.Cu")
		(net 442)
	)
	(segment
		(start 216.5 138.2)
		(end 216.125 138.575)
		(width 0.1)
		(layer "In3.Cu")
		(net 442)
	)
	(segment
		(start 216.125 138.575)
		(end 213.425 138.575)
		(width 0.1)
		(layer "In3.Cu")
		(net 442)
	)
	(segment
		(start 222.335789 138)
		(end 222.13579 138.2)
		(width 0.1)
		(layer "In3.Cu")
		(net 442)
	)
	(segment
		(start 255.9 87)
		(end 256.1 87.2)
		(width 0.1)
		(layer "In3.Cu")
		(net 442)
	)
	(segment
		(start 199.5 116.5)
		(end 199 116)
		(width 0.256)
		(layer "F.Cu")
		(net 444)
	)
	(segment
		(start 158.045002 95.972002)
		(end 158.190001 96.117001)
		(width 0.16)
		(layer "F.Cu")
		(net 444)
	)
	(segment
		(start 158.045002 95.972002)
		(end 157.876804 95.972001)
		(width 0.16)
		(layer "F.Cu")
		(net 444)
	)
	(segment
		(start 157.555001 96.293804)
		(end 157.555001 96.475001)
		(width 0.16)
		(layer "F.Cu")
		(net 444)
	)
	(segment
		(start 157.876804 95.972001)
		(end 157.555001 96.293804)
		(width 0.16)
		(layer "F.Cu")
		(net 444)
	)
	(via
		(at 199 116)
		(size 0.45)
		(drill 0.2)
		(layers "F.Cu" "B.Cu")
		(net 444)
	)
	(via
		(at 158.190001 96.117001)
		(size 0.45)
		(drill 0.2)
		(layers "F.Cu" "B.Cu")
		(net 444)
	)
	(segment
		(start 179.550001 94.850001)
		(end 179.550001 94.519466)
		(width 0.114)
		(layer "In5.Cu")
		(net 444)
	)
	(segment
		(start 167.670561 94.073501)
		(end 168.940561 95.343501)
		(width 0.114)
		(layer "In5.Cu")
		(net 444)
	)
	(segment
		(start 158.323501 95.983501)
		(end 158.909441 95.983501)
		(width 0.114)
		(layer "In5.Cu")
		(net 444)
	)
	(segment
		(start 199.000001 116.000001)
		(end 199.400001 116.400001)
		(width 0.1)
		(layer "In5.Cu")
		(net 444)
	)
	(segment
		(start 159.549441 95.343501)
		(end 160.104501 95.343501)
		(width 0.114)
		(layer "In5.Cu")
		(net 444)
	)
	(segment
		(start 178.150001 94.850001)
		(end 178.150001 94.519466)
		(width 0.114)
		(layer "In5.Cu")
		(net 444)
	)
	(segment
		(start 158.190001 96.117001)
		(end 158.323501 95.983501)
		(width 0.114)
		(layer "In5.Cu")
		(net 444)
	)
	(segment
		(start 199.400001 116.400001)
		(end 199.608579 116.400001)
		(width 0.1)
		(layer "In5.Cu")
		(net 444)
	)
	(segment
		(start 163.939441 94.073501)
		(end 167.670561 94.073501)
		(width 0.114)
		(layer "In5.Cu")
		(net 444)
	)
	(segment
		(start 172.963001 94.519466)
		(end 172.963001 94.850001)
		(width 0.114)
		(layer "In5.Cu")
		(net 444)
	)
	(segment
		(start 175.763001 94.519466)
		(end 175.763001 94.850001)
		(width 0.114)
		(layer "In5.Cu")
		(net 444)
	)
	(segment
		(start 176.750001 94.850001)
		(end 176.750001 94.519466)
		(width 0.114)
		(layer "In5.Cu")
		(net 444)
	)
	(segment
		(start 160.704501 95.567628)
		(end 160.704501 95.543501)
		(width 0.114)
		(layer "In5.Cu")
		(net 444)
	)
	(segment
		(start 177.163001 94.519466)
		(end 177.163001 94.850001)
		(width 0.114)
		(layer "In5.Cu")
		(net 444)
	)
	(segment
		(start 173.950001 94.850001)
		(end 173.950001 94.519466)
		(width 0.114)
		(layer "In5.Cu")
		(net 444)
	)
	(segment
		(start 180.456501 95.343501)
		(end 182.790561 95.343501)
		(width 0.114)
		(layer "In5.Cu")
		(net 444)
	)
	(segment
		(start 199.608579 116.400001)
		(end 199.820001 116.188579)
		(width 0.1)
		(layer "In5.Cu")
		(net 444)
	)
	(segment
		(start 162.669441 95.343501)
		(end 163.939441 94.073501)
		(width 0.114)
		(layer "In5.Cu")
		(net 444)
	)
	(segment
		(start 172.550001 94.850001)
		(end 172.550001 94.519466)
		(width 0.114)
		(layer "In5.Cu")
		(net 444)
	)
	(segment
		(start 178.563001 94.519466)
		(end 178.563001 94.850001)
		(width 0.114)
		(layer "In5.Cu")
		(net 444)
	)
	(segment
		(start 175.350001 94.850001)
		(end 175.350001 94.519466)
		(width 0.114)
		(layer "In5.Cu")
		(net 444)
	)
	(segment
		(start 160.904501 95.343501)
		(end 162.669441 95.343501)
		(width 0.114)
		(layer "In5.Cu")
		(net 444)
	)
	(segment
		(start 158.909441 95.983501)
		(end 159.549441 95.343501)
		(width 0.114)
		(layer "In5.Cu")
		(net 444)
	)
	(segment
		(start 199.776501 112.329441)
		(end 199.776501 113.405001)
		(width 0.114)
		(layer "In5.Cu")
		(net 444)
	)
	(segment
		(start 179.963001 94.519466)
		(end 179.963001 94.850001)
		(width 0.114)
		(layer "In5.Cu")
		(net 444)
	)
	(segment
		(start 160.304501 95.543501)
		(end 160.304501 95.567628)
		(width 0.114)
		(layer "In5.Cu")
		(net 444)
	)
	(segment
		(start 174.363001 94.519466)
		(end 174.363001 94.850001)
		(width 0.114)
		(layer "In5.Cu")
		(net 444)
	)
	(segment
		(start 199.820001 116.188579)
		(end 199.820001 113.448501)
		(width 0.1)
		(layer "In5.Cu")
		(net 444)
	)
	(segment
		(start 168.940561 95.343501)
		(end 172.056501 95.343501)
		(width 0.114)
		(layer "In5.Cu")
		(net 444)
	)
	(segment
		(start 199.820001 113.448501)
		(end 199.776501 113.405001)
		(width 0.1)
		(layer "In5.Cu")
		(net 444)
	)
	(segment
		(start 182.790561 95.343501)
		(end 199.776501 112.329441)
		(width 0.114)
		(layer "In5.Cu")
		(net 444)
	)
	(arc
		(start 175.763001 94.850001)
		(mid 175.907544 95.198958)
		(end 176.256501 95.343501)
		(width 0.114)
		(layer "In5.Cu")
		(net 444)
	)
	(arc
		(start 175.556501 94.312966)
		(mid 175.702519 94.373448)
		(end 175.763001 94.519466)
		(width 0.114)
		(layer "In5.Cu")
		(net 444)
	)
	(arc
		(start 178.563001 94.850001)
		(mid 178.707544 95.198958)
		(end 179.056501 95.343501)
		(width 0.114)
		(layer "In5.Cu")
		(net 444)
	)
	(arc
		(start 179.056501 95.343501)
		(mid 179.405458 95.198958)
		(end 179.550001 94.850001)
		(width 0.114)
		(layer "In5.Cu")
		(net 444)
	)
	(arc
		(start 179.756501 94.312966)
		(mid 179.902519 94.373448)
		(end 179.963001 94.519466)
		(width 0.114)
		(layer "In5.Cu")
		(net 444)
	)
	(arc
		(start 160.704501 95.543501)
		(mid 160.76308 95.40208)
		(end 160.904501 95.343501)
		(width 0.114)
		(layer "In5.Cu")
		(net 444)
	)
	(arc
		(start 176.256501 95.343501)
		(mid 176.605458 95.198958)
		(end 176.750001 94.850001)
		(width 0.114)
		(layer "In5.Cu")
		(net 444)
	)
	(arc
		(start 160.304501 95.567628)
		(mid 160.36308 95.709049)
		(end 160.504501 95.767628)
		(width 0.114)
		(layer "In5.Cu")
		(net 444)
	)
	(arc
		(start 176.956501 94.312966)
		(mid 177.102519 94.373448)
		(end 177.163001 94.519466)
		(width 0.114)
		(layer "In5.Cu")
		(net 444)
	)
	(arc
		(start 178.150001 94.519466)
		(mid 178.210483 94.373448)
		(end 178.356501 94.312966)
		(width 0.114)
		(layer "In5.Cu")
		(net 444)
	)
	(arc
		(start 179.963001 94.850001)
		(mid 180.107544 95.198958)
		(end 180.456501 95.343501)
		(width 0.114)
		(layer "In5.Cu")
		(net 444)
	)
	(arc
		(start 173.456501 95.343501)
		(mid 173.805458 95.198958)
		(end 173.950001 94.850001)
		(width 0.114)
		(layer "In5.Cu")
		(net 444)
	)
	(arc
		(start 172.550001 94.519466)
		(mid 172.610483 94.373448)
		(end 172.756501 94.312966)
		(width 0.114)
		(layer "In5.Cu")
		(net 444)
	)
	(arc
		(start 176.750001 94.519466)
		(mid 176.810483 94.373448)
		(end 176.956501 94.312966)
		(width 0.114)
		(layer "In5.Cu")
		(net 444)
	)
	(arc
		(start 174.363001 94.850001)
		(mid 174.507544 95.198958)
		(end 174.856501 95.343501)
		(width 0.114)
		(layer "In5.Cu")
		(net 444)
	)
	(arc
		(start 160.104501 95.343501)
		(mid 160.245922 95.40208)
		(end 160.304501 95.543501)
		(width 0.114)
		(layer "In5.Cu")
		(net 444)
	)
	(arc
		(start 174.856501 95.343501)
		(mid 175.205458 95.198958)
		(end 175.350001 94.850001)
		(width 0.114)
		(layer "In5.Cu")
		(net 444)
	)
	(arc
		(start 174.156501 94.312966)
		(mid 174.302519 94.373448)
		(end 174.363001 94.519466)
		(width 0.114)
		(layer "In5.Cu")
		(net 444)
	)
	(arc
		(start 172.756501 94.312966)
		(mid 172.902519 94.373448)
		(end 172.963001 94.519466)
		(width 0.114)
		(layer "In5.Cu")
		(net 444)
	)
	(arc
		(start 172.056501 95.343501)
		(mid 172.405458 95.198958)
		(end 172.550001 94.850001)
		(width 0.114)
		(layer "In5.Cu")
		(net 444)
	)
	(arc
		(start 175.350001 94.519466)
		(mid 175.410483 94.373448)
		(end 175.556501 94.312966)
		(width 0.114)
		(layer "In5.Cu")
		(net 444)
	)
	(arc
		(start 160.504501 95.767628)
		(mid 160.645922 95.709049)
		(end 160.704501 95.567628)
		(width 0.114)
		(layer "In5.Cu")
		(net 444)
	)
	(arc
		(start 179.550001 94.519466)
		(mid 179.610483 94.373448)
		(end 179.756501 94.312966)
		(width 0.114)
		(layer "In5.Cu")
		(net 444)
	)
	(arc
		(start 177.163001 94.850001)
		(mid 177.307544 95.198958)
		(end 177.656501 95.343501)
		(width 0.114)
		(layer "In5.Cu")
		(net 444)
	)
	(arc
		(start 177.656501 95.343501)
		(mid 178.005458 95.198958)
		(end 178.150001 94.850001)
		(width 0.114)
		(layer "In5.Cu")
		(net 444)
	)
	(arc
		(start 172.963001 94.850001)
		(mid 173.107544 95.198958)
		(end 173.456501 95.343501)
		(width 0.114)
		(layer "In5.Cu")
		(net 444)
	)
	(arc
		(start 173.950001 94.519466)
		(mid 174.010483 94.373448)
		(end 174.156501 94.312966)
		(width 0.114)
		(layer "In5.Cu")
		(net 444)
	)
	(arc
		(start 178.356501 94.312966)
		(mid 178.502519 94.373448)
		(end 178.563001 94.519466)
		(width 0.114)
		(layer "In5.Cu")
		(net 444)
	)
	(segment
		(start 199.5 117.5)
		(end 199 117)
		(width 0.256)
		(layer "F.Cu")
		(net 445)
	)
	(segment
		(start 157.555001 95.386198)
		(end 157.876804 95.708001)
		(width 0.16)
		(layer "F.Cu")
		(net 445)
	)
	(segment
		(start 158.045002 95.708)
		(end 158.190001 95.563001)
		(width 0.16)
		(layer "F.Cu")
		(net 445)
	)
	(segment
		(start 158.045002 95.708)
		(end 157.876804 95.708001)
		(width 0.16)
		(layer "F.Cu")
		(net 445)
	)
	(segment
		(start 157.555001 95.205001)
		(end 157.555001 95.386198)
		(width 0.16)
		(layer "F.Cu")
		(net 445)
	)
	(via
		(at 199 117)
		(size 0.45)
		(drill 0.2)
		(layers "F.Cu" "B.Cu")
		(net 445)
	)
	(via
		(at 158.190001 95.563001)
		(size 0.45)
		(drill 0.2)
		(layers "F.Cu" "B.Cu")
		(net 445)
	)
	(segment
		(start 172.263001 94.850001)
		(end 172.263001 94.519466)
		(width 0.114)
		(layer "In5.Cu")
		(net 445)
	)
	(segment
		(start 162.550561 95.056501)
		(end 163.820561 93.786501)
		(width 0.114)
		(layer "In5.Cu")
		(net 445)
	)
	(segment
		(start 200.020001 113.448501)
		(end 200.063501 113.405001)
		(width 0.1)
		(layer "In5.Cu")
		(net 445)
	)
	(segment
		(start 173.250001 94.519466)
		(end 173.250001 94.850001)
		(width 0.114)
		(layer "In5.Cu")
		(net 445)
	)
	(segment
		(start 200.020001 116.271423)
		(end 200.020001 113.448501)
		(width 0.1)
		(layer "In5.Cu")
		(net 445)
	)
	(segment
		(start 199.400001 116.600001)
		(end 199.691423 116.600001)
		(width 0.1)
		(layer "In5.Cu")
		(net 445)
	)
	(segment
		(start 179.263001 94.850001)
		(end 179.263001 94.519466)
		(width 0.114)
		(layer "In5.Cu")
		(net 445)
	)
	(segment
		(start 167.789441 93.786501)
		(end 169.059441 95.056501)
		(width 0.114)
		(layer "In5.Cu")
		(net 445)
	)
	(segment
		(start 176.050001 94.519466)
		(end 176.050001 94.850001)
		(width 0.114)
		(layer "In5.Cu")
		(net 445)
	)
	(segment
		(start 174.650001 94.519466)
		(end 174.650001 94.850001)
		(width 0.114)
		(layer "In5.Cu")
		(net 445)
	)
	(segment
		(start 177.450001 94.519466)
		(end 177.450001 94.850001)
		(width 0.114)
		(layer "In5.Cu")
		(net 445)
	)
	(segment
		(start 176.463001 94.850001)
		(end 176.463001 94.519466)
		(width 0.114)
		(layer "In5.Cu")
		(net 445)
	)
	(segment
		(start 163.820561 93.786501)
		(end 167.789441 93.786501)
		(width 0.114)
		(layer "In5.Cu")
		(net 445)
	)
	(segment
		(start 158.190001 95.563001)
		(end 158.323501 95.696501)
		(width 0.114)
		(layer "In5.Cu")
		(net 445)
	)
	(segment
		(start 177.863001 94.850001)
		(end 177.863001 94.519466)
		(width 0.114)
		(layer "In5.Cu")
		(net 445)
	)
	(segment
		(start 158.790561 95.696501)
		(end 159.430561 95.056501)
		(width 0.114)
		(layer "In5.Cu")
		(net 445)
	)
	(segment
		(start 180.250001 94.519466)
		(end 180.250001 94.850001)
		(width 0.114)
		(layer "In5.Cu")
		(net 445)
	)
	(segment
		(start 199.691423 116.600001)
		(end 200.020001 116.271423)
		(width 0.1)
		(layer "In5.Cu")
		(net 445)
	)
	(segment
		(start 180.456501 95.056501)
		(end 182.909441 95.056501)
		(width 0.114)
		(layer "In5.Cu")
		(net 445)
	)
	(segment
		(start 159.430561 95.056501)
		(end 162.550561 95.056501)
		(width 0.114)
		(layer "In5.Cu")
		(net 445)
	)
	(segment
		(start 173.663001 94.850001)
		(end 173.663001 94.519466)
		(width 0.114)
		(layer "In5.Cu")
		(net 445)
	)
	(segment
		(start 178.850001 94.519466)
		(end 178.850001 94.850001)
		(width 0.114)
		(layer "In5.Cu")
		(net 445)
	)
	(segment
		(start 158.323501 95.696501)
		(end 158.790561 95.696501)
		(width 0.114)
		(layer "In5.Cu")
		(net 445)
	)
	(segment
		(start 199.000001 117.000001)
		(end 199.400001 116.600001)
		(width 0.1)
		(layer "In5.Cu")
		(net 445)
	)
	(segment
		(start 182.909441 95.056501)
		(end 200.063501 112.210561)
		(width 0.114)
		(layer "In5.Cu")
		(net 445)
	)
	(segment
		(start 169.059441 95.056501)
		(end 172.056501 95.056501)
		(width 0.114)
		(layer "In5.Cu")
		(net 445)
	)
	(segment
		(start 200.063501 112.210561)
		(end 200.063501 113.405001)
		(width 0.114)
		(layer "In5.Cu")
		(net 445)
	)
	(segment
		(start 175.063001 94.850001)
		(end 175.063001 94.519466)
		(width 0.114)
		(layer "In5.Cu")
		(net 445)
	)
	(arc
		(start 179.263001 94.519466)
		(mid 179.407544 94.170509)
		(end 179.756501 94.025966)
		(width 0.114)
		(layer "In5.Cu")
		(net 445)
	)
	(arc
		(start 180.250001 94.850001)
		(mid 180.310483 94.996019)
		(end 180.456501 95.056501)
		(width 0.114)
		(layer "In5.Cu")
		(net 445)
	)
	(arc
		(start 172.263001 94.519466)
		(mid 172.407544 94.170509)
		(end 172.756501 94.025966)
		(width 0.114)
		(layer "In5.Cu")
		(net 445)
	)
	(arc
		(start 177.450001 94.850001)
		(mid 177.510483 94.996019)
		(end 177.656501 95.056501)
		(width 0.114)
		(layer "In5.Cu")
		(net 445)
	)
	(arc
		(start 176.956501 94.025966)
		(mid 177.305458 94.170509)
		(end 177.450001 94.519466)
		(width 0.114)
		(layer "In5.Cu")
		(net 445)
	)
	(arc
		(start 177.863001 94.519466)
		(mid 178.007544 94.170509)
		(end 178.356501 94.025966)
		(width 0.114)
		(layer "In5.Cu")
		(net 445)
	)
	(arc
		(start 173.250001 94.850001)
		(mid 173.310483 94.996019)
		(end 173.456501 95.056501)
		(width 0.114)
		(layer "In5.Cu")
		(net 445)
	)
	(arc
		(start 179.756501 94.025966)
		(mid 180.105458 94.170509)
		(end 180.250001 94.519466)
		(width 0.114)
		(layer "In5.Cu")
		(net 445)
	)
	(arc
		(start 178.850001 94.850001)
		(mid 178.910483 94.996019)
		(end 179.056501 95.056501)
		(width 0.114)
		(layer "In5.Cu")
		(net 445)
	)
	(arc
		(start 176.050001 94.850001)
		(mid 176.110483 94.996019)
		(end 176.256501 95.056501)
		(width 0.114)
		(layer "In5.Cu")
		(net 445)
	)
	(arc
		(start 174.856501 95.056501)
		(mid 175.002519 94.996019)
		(end 175.063001 94.850001)
		(width 0.114)
		(layer "In5.Cu")
		(net 445)
	)
	(arc
		(start 177.656501 95.056501)
		(mid 177.802519 94.996019)
		(end 177.863001 94.850001)
		(width 0.114)
		(layer "In5.Cu")
		(net 445)
	)
	(arc
		(start 173.663001 94.519466)
		(mid 173.807544 94.170509)
		(end 174.156501 94.025966)
		(width 0.114)
		(layer "In5.Cu")
		(net 445)
	)
	(arc
		(start 172.056501 95.056501)
		(mid 172.202519 94.996019)
		(end 172.263001 94.850001)
		(width 0.114)
		(layer "In5.Cu")
		(net 445)
	)
	(arc
		(start 175.556501 94.025966)
		(mid 175.905458 94.170509)
		(end 176.050001 94.519466)
		(width 0.114)
		(layer "In5.Cu")
		(net 445)
	)
	(arc
		(start 172.756501 94.025966)
		(mid 173.105458 94.170509)
		(end 173.250001 94.519466)
		(width 0.114)
		(layer "In5.Cu")
		(net 445)
	)
	(arc
		(start 176.463001 94.519466)
		(mid 176.607544 94.170509)
		(end 176.956501 94.025966)
		(width 0.114)
		(layer "In5.Cu")
		(net 445)
	)
	(arc
		(start 179.056501 95.056501)
		(mid 179.202519 94.996019)
		(end 179.263001 94.850001)
		(width 0.114)
		(layer "In5.Cu")
		(net 445)
	)
	(arc
		(start 174.156501 94.025966)
		(mid 174.505458 94.170509)
		(end 174.650001 94.519466)
		(width 0.114)
		(layer "In5.Cu")
		(net 445)
	)
	(arc
		(start 175.063001 94.519466)
		(mid 175.207544 94.170509)
		(end 175.556501 94.025966)
		(width 0.114)
		(layer "In5.Cu")
		(net 445)
	)
	(arc
		(start 176.256501 95.056501)
		(mid 176.402519 94.996019)
		(end 176.463001 94.850001)
		(width 0.114)
		(layer "In5.Cu")
		(net 445)
	)
	(arc
		(start 174.650001 94.850001)
		(mid 174.710483 94.996019)
		(end 174.856501 95.056501)
		(width 0.114)
		(layer "In5.Cu")
		(net 445)
	)
	(arc
		(start 178.356501 94.025966)
		(mid 178.705458 94.170509)
		(end 178.850001 94.519466)
		(width 0.114)
		(layer "In5.Cu")
		(net 445)
	)
	(arc
		(start 173.456501 95.056501)
		(mid 173.602519 94.996019)
		(end 173.663001 94.850001)
		(width 0.114)
		(layer "In5.Cu")
		(net 445)
	)
	(segment
		(start 159.146804 104.862001)
		(end 158.825001 105.183804)
		(width 0.16)
		(layer "F.Cu")
		(net 446)
	)
	(segment
		(start 158.825001 105.183804)
		(end 158.825001 105.365001)
		(width 0.16)
		(layer "F.Cu")
		(net 446)
	)
	(segment
		(start 159.315002 104.862002)
		(end 159.460001 105.007001)
		(width 0.16)
		(layer "F.Cu")
		(net 446)
	)
	(segment
		(start 197.5 125.5)
		(end 197.038456 125.038456)
		(width 0.256)
		(layer "F.Cu")
		(net 446)
	)
	(segment
		(start 197.038456 125.038456)
		(end 197.025 125.038456)
		(width 0.256)
		(layer "F.Cu")
		(net 446)
	)
	(segment
		(start 159.315002 104.862002)
		(end 159.146804 104.862001)
		(width 0.16)
		(layer "F.Cu")
		(net 446)
	)
	(via
		(at 197.025 125.038456)
		(size 0.45)
		(drill 0.2)
		(layers "F.Cu" "B.Cu")
		(net 446)
	)
	(via
		(at 159.460001 105.007001)
		(size 0.45)
		(drill 0.2)
		(layers "F.Cu" "B.Cu")
		(net 446)
	)
	(segment
		(start 164.976501 108.957001)
		(end 166.070001 108.957001)
		(width 0.114)
		(layer "In5.Cu")
		(net 446)
	)
	(segment
		(start 164.976501 111.480001)
		(end 166.070001 111.480001)
		(width 0.114)
		(layer "In5.Cu")
		(net 446)
	)
	(segment
		(start 166.070001 110.443001)
		(end 164.976501 110.443001)
		(width 0.114)
		(layer "In5.Cu")
		(net 446)
	)
	(segment
		(start 166.301501 125.617441)
		(end 166.827561 126.143501)
		(width 0.114)
		(layer "In5.Cu")
		(net 446)
	)
	(segment
		(start 165.100561 105.493501)
		(end 166.301501 106.694441)
		(width 0.114)
		(layer "In5.Cu")
		(net 446)
	)
	(segment
		(start 166.301501 106.694441)
		(end 166.301501 107.688501)
		(width 0.114)
		(layer "In5.Cu")
		(net 446)
	)
	(segment
		(start 159.460001 105.007001)
		(end 159.593501 104.873501)
		(width 0.114)
		(layer "In5.Cu")
		(net 446)
	)
	(segment
		(start 192.808579 126.100001)
		(end 183.448501 126.100001)
		(width 0.1)
		(layer "In5.Cu")
		(net 446)
	)
	(segment
		(start 196.600001 126.266423)
		(end 196.266423 126.600001)
		(width 0.1)
		(layer "In5.Cu")
		(net 446)
	)
	(segment
		(start 166.827561 126.143501)
		(end 183.405001 126.143501)
		(width 0.114)
		(layer "In5.Cu")
		(net 446)
	)
	(segment
		(start 166.301501 109.188501)
		(end 166.301501 110.211501)
		(width 0.114)
		(layer "In5.Cu")
		(net 446)
	)
	(segment
		(start 183.448501 126.100001)
		(end 183.405001 126.143501)
		(width 0.1)
		(layer "In5.Cu")
		(net 446)
	)
	(segment
		(start 159.593501 104.873501)
		(end 159.820561 104.873501)
		(width 0.114)
		(layer "In5.Cu")
		(net 446)
	)
	(segment
		(start 166.301501 114.211501)
		(end 166.301501 125.617441)
		(width 0.114)
		(layer "In5.Cu")
		(net 446)
	)
	(segment
		(start 166.301501 111.711501)
		(end 166.301501 112.711501)
		(width 0.114)
		(layer "In5.Cu")
		(net 446)
	)
	(segment
		(start 160.440561 105.493501)
		(end 165.100561 105.493501)
		(width 0.114)
		(layer "In5.Cu")
		(net 446)
	)
	(segment
		(start 166.070001 112.943001)
		(end 165.095122 112.943001)
		(width 0.114)
		(layer "In5.Cu")
		(net 446)
	)
	(segment
		(start 197.000001 125.000001)
		(end 196.600001 125.400001)
		(width 0.1)
		(layer "In5.Cu")
		(net 446)
	)
	(segment
		(start 193.308579 126.600001)
		(end 192.808579 126.100001)
		(width 0.1)
		(layer "In5.Cu")
		(net 446)
	)
	(segment
		(start 166.070001 107.920001)
		(end 164.976501 107.920001)
		(width 0.114)
		(layer "In5.Cu")
		(net 446)
	)
	(segment
		(start 196.266423 126.600001)
		(end 193.308579 126.600001)
		(width 0.1)
		(layer "In5.Cu")
		(net 446)
	)
	(segment
		(start 159.820561 104.873501)
		(end 160.440561 105.493501)
		(width 0.114)
		(layer "In5.Cu")
		(net 446)
	)
	(segment
		(start 165.095122 113.980001)
		(end 166.070001 113.980001)
		(width 0.114)
		(layer "In5.Cu")
		(net 446)
	)
	(segment
		(start 196.600001 125.400001)
		(end 196.600001 126.266423)
		(width 0.1)
		(layer "In5.Cu")
		(net 446)
	)
	(arc
		(start 164.976501 110.443001)
		(mid 164.609866 110.594866)
		(end 164.458001 110.961501)
		(width 0.114)
		(layer "In5.Cu")
		(net 446)
	)
	(arc
		(start 166.301501 112.711501)
		(mid 166.233696 112.875196)
		(end 166.070001 112.943001)
		(width 0.114)
		(layer "In5.Cu")
		(net 446)
	)
	(arc
		(start 164.576622 113.461501)
		(mid 164.728487 113.828136)
		(end 165.095122 113.980001)
		(width 0.114)
		(layer "In5.Cu")
		(net 446)
	)
	(arc
		(start 166.301501 110.211501)
		(mid 166.233696 110.375196)
		(end 166.070001 110.443001)
		(width 0.114)
		(layer "In5.Cu")
		(net 446)
	)
	(arc
		(start 166.070001 113.980001)
		(mid 166.233696 114.047806)
		(end 166.301501 114.211501)
		(width 0.114)
		(layer "In5.Cu")
		(net 446)
	)
	(arc
		(start 164.458001 108.438501)
		(mid 164.609866 108.805136)
		(end 164.976501 108.957001)
		(width 0.114)
		(layer "In5.Cu")
		(net 446)
	)
	(arc
		(start 164.976501 107.920001)
		(mid 164.609866 108.071866)
		(end 164.458001 108.438501)
		(width 0.114)
		(layer "In5.Cu")
		(net 446)
	)
	(arc
		(start 166.070001 111.480001)
		(mid 166.233696 111.547806)
		(end 166.301501 111.711501)
		(width 0.114)
		(layer "In5.Cu")
		(net 446)
	)
	(arc
		(start 165.095122 112.943001)
		(mid 164.728487 113.094866)
		(end 164.576622 113.461501)
		(width 0.114)
		(layer "In5.Cu")
		(net 446)
	)
	(arc
		(start 164.458001 110.961501)
		(mid 164.609866 111.328136)
		(end 164.976501 111.480001)
		(width 0.114)
		(layer "In5.Cu")
		(net 446)
	)
	(arc
		(start 166.070001 108.957001)
		(mid 166.233696 109.024806)
		(end 166.301501 109.188501)
		(width 0.114)
		(layer "In5.Cu")
		(net 446)
	)
	(arc
		(start 166.301501 107.688501)
		(mid 166.233696 107.852196)
		(end 166.070001 107.920001)
		(width 0.114)
		(layer "In5.Cu")
		(net 446)
	)
	(segment
		(start 158.825001 104.276198)
		(end 159.146804 104.598001)
		(width 0.16)
		(layer "F.Cu")
		(net 449)
	)
	(segment
		(start 196.5 125.5)
		(end 196 125)
		(width 0.256)
		(layer "F.Cu")
		(net 449)
	)
	(segment
		(start 159.315002 104.598)
		(end 159.146804 104.598001)
		(width 0.16)
		(layer "F.Cu")
		(net 449)
	)
	(segment
		(start 158.825001 104.095001)
		(end 158.825001 104.276198)
		(width 0.16)
		(layer "F.Cu")
		(net 449)
	)
	(segment
		(start 159.315002 104.598)
		(end 159.460001 104.453001)
		(width 0.16)
		(layer "F.Cu")
		(net 449)
	)
	(via
		(at 159.460001 104.453001)
		(size 0.45)
		(drill 0.2)
		(layers "F.Cu" "B.Cu")
		(net 449)
	)
	(via
		(at 196 125)
		(size 0.45)
		(drill 0.2)
		(layers "F.Cu" "B.Cu")
		(net 449)
	)
	(segment
		(start 196.400001 125.400001)
		(end 196.400001 126.183579)
		(width 0.1)
		(layer "In5.Cu")
		(net 449)
	)
	(segment
		(start 166.588501 106.575561)
		(end 166.588501 107.688501)
		(width 0.114)
		(layer "In5.Cu")
		(net 449)
	)
	(segment
		(start 166.946441 125.856501)
		(end 183.405001 125.856501)
		(width 0.114)
		(layer "In5.Cu")
		(net 449)
	)
	(segment
		(start 165.095122 113.693001)
		(end 166.070001 113.693001)
		(width 0.114)
		(layer "In5.Cu")
		(net 449)
	)
	(segment
		(start 159.939441 104.586501)
		(end 160.559441 105.206501)
		(width 0.114)
		(layer "In5.Cu")
		(net 449)
	)
	(segment
		(start 166.588501 114.211501)
		(end 166.588501 125.498561)
		(width 0.114)
		(layer "In5.Cu")
		(net 449)
	)
	(segment
		(start 161.271501 105.081501)
		(end 161.271501 105.081013)
		(width 0.114)
		(layer "In5.Cu")
		(net 449)
	)
	(segment
		(start 166.588501 111.711501)
		(end 166.588501 112.711501)
		(width 0.114)
		(layer "In5.Cu")
		(net 449)
	)
	(segment
		(start 166.588501 109.188501)
		(end 166.588501 110.211501)
		(width 0.114)
		(layer "In5.Cu")
		(net 449)
	)
	(segment
		(start 160.559441 105.206501)
		(end 161.146501 105.206501)
		(width 0.114)
		(layer "In5.Cu")
		(net 449)
	)
	(segment
		(start 183.448501 125.900001)
		(end 183.405001 125.856501)
		(width 0.1)
		(layer "In5.Cu")
		(net 449)
	)
	(segment
		(start 196.400001 126.183579)
		(end 196.183579 126.400001)
		(width 0.1)
		(layer "In5.Cu")
		(net 449)
	)
	(segment
		(start 164.976501 108.670001)
		(end 166.070001 108.670001)
		(width 0.114)
		(layer "In5.Cu")
		(net 449)
	)
	(segment
		(start 159.460001 104.453001)
		(end 159.593501 104.586501)
		(width 0.114)
		(layer "In5.Cu")
		(net 449)
	)
	(segment
		(start 166.588501 125.498561)
		(end 166.946441 125.856501)
		(width 0.114)
		(layer "In5.Cu")
		(net 449)
	)
	(segment
		(start 192.891423 125.900001)
		(end 183.448501 125.900001)
		(width 0.1)
		(layer "In5.Cu")
		(net 449)
	)
	(segment
		(start 193.391423 126.400001)
		(end 192.891423 125.900001)
		(width 0.1)
		(layer "In5.Cu")
		(net 449)
	)
	(segment
		(start 166.070001 108.207001)
		(end 164.976501 108.207001)
		(width 0.114)
		(layer "In5.Cu")
		(net 449)
	)
	(segment
		(start 166.070001 110.730001)
		(end 164.976501 110.730001)
		(width 0.114)
		(layer "In5.Cu")
		(net 449)
	)
	(segment
		(start 166.070001 113.230001)
		(end 165.095122 113.230001)
		(width 0.114)
		(layer "In5.Cu")
		(net 449)
	)
	(segment
		(start 161.646501 105.206501)
		(end 165.219441 105.206501)
		(width 0.114)
		(layer "In5.Cu")
		(net 449)
	)
	(segment
		(start 164.976501 111.193001)
		(end 166.070001 111.193001)
		(width 0.114)
		(layer "In5.Cu")
		(net 449)
	)
	(segment
		(start 165.219441 105.206501)
		(end 166.588501 106.575561)
		(width 0.114)
		(layer "In5.Cu")
		(net 449)
	)
	(segment
		(start 159.593501 104.586501)
		(end 159.939441 104.586501)
		(width 0.114)
		(layer "In5.Cu")
		(net 449)
	)
	(segment
		(start 161.521501 105.081013)
		(end 161.521501 105.081501)
		(width 0.114)
		(layer "In5.Cu")
		(net 449)
	)
	(segment
		(start 196.000001 125.000001)
		(end 196.400001 125.400001)
		(width 0.1)
		(layer "In5.Cu")
		(net 449)
	)
	(segment
		(start 196.183579 126.400001)
		(end 193.391423 126.400001)
		(width 0.1)
		(layer "In5.Cu")
		(net 449)
	)
	(arc
		(start 164.745001 110.961501)
		(mid 164.812806 111.125196)
		(end 164.976501 111.193001)
		(width 0.114)
		(layer "In5.Cu")
		(net 449)
	)
	(arc
		(start 161.521501 105.081501)
		(mid 161.558113 105.169889)
		(end 161.646501 105.206501)
		(width 0.114)
		(layer "In5.Cu")
		(net 449)
	)
	(arc
		(start 164.863622 113.461501)
		(mid 164.931427 113.625196)
		(end 165.095122 113.693001)
		(width 0.114)
		(layer "In5.Cu")
		(net 449)
	)
	(arc
		(start 164.976501 108.207001)
		(mid 164.812806 108.274806)
		(end 164.745001 108.438501)
		(width 0.114)
		(layer "In5.Cu")
		(net 449)
	)
	(arc
		(start 161.396501 104.956013)
		(mid 161.484889 104.992625)
		(end 161.521501 105.081013)
		(width 0.114)
		(layer "In5.Cu")
		(net 449)
	)
	(arc
		(start 164.976501 110.730001)
		(mid 164.812806 110.797806)
		(end 164.745001 110.961501)
		(width 0.114)
		(layer "In5.Cu")
		(net 449)
	)
	(arc
		(start 164.745001 108.438501)
		(mid 164.812806 108.602196)
		(end 164.976501 108.670001)
		(width 0.114)
		(layer "In5.Cu")
		(net 449)
	)
	(arc
		(start 161.271501 105.081013)
		(mid 161.308113 104.992625)
		(end 161.396501 104.956013)
		(width 0.114)
		(layer "In5.Cu")
		(net 449)
	)
	(arc
		(start 166.070001 111.193001)
		(mid 166.436636 111.344866)
		(end 166.588501 111.711501)
		(width 0.114)
		(layer "In5.Cu")
		(net 449)
	)
	(arc
		(start 166.588501 110.211501)
		(mid 166.436636 110.578136)
		(end 166.070001 110.730001)
		(width 0.114)
		(layer "In5.Cu")
		(net 449)
	)
	(arc
		(start 166.070001 113.693001)
		(mid 166.436636 113.844866)
		(end 166.588501 114.211501)
		(width 0.114)
		(layer "In5.Cu")
		(net 449)
	)
	(arc
		(start 165.095122 113.230001)
		(mid 164.931427 113.297806)
		(end 164.863622 113.461501)
		(width 0.114)
		(layer "In5.Cu")
		(net 449)
	)
	(arc
		(start 166.588501 107.688501)
		(mid 166.436636 108.055136)
		(end 166.070001 108.207001)
		(width 0.114)
		(layer "In5.Cu")
		(net 449)
	)
	(arc
		(start 166.070001 108.670001)
		(mid 166.436636 108.821866)
		(end 166.588501 109.188501)
		(width 0.114)
		(layer "In5.Cu")
		(net 449)
	)
	(arc
		(start 161.146501 105.206501)
		(mid 161.234889 105.169889)
		(end 161.271501 105.081501)
		(width 0.114)
		(layer "In5.Cu")
		(net 449)
	)
	(arc
		(start 166.588501 112.711501)
		(mid 166.436636 113.078136)
		(end 166.070001 113.230001)
		(width 0.114)
		(layer "In5.Cu")
		(net 449)
	)
	(segment
		(start 160.095001 103.913804)
		(end 160.095001 104.095001)
		(width 0.16)
		(layer "F.Cu")
		(net 450)
	)
	(segment
		(start 160.585002 103.592002)
		(end 160.730001 103.737001)
		(width 0.16)
		(layer "F.Cu")
		(net 450)
	)
	(segment
		(start 160.585002 103.592002)
		(end 160.416804 103.592001)
		(width 0.16)
		(layer "F.Cu")
		(net 450)
	)
	(segment
		(start 199.5 124.5)
		(end 199 124)
		(width 0.256)
		(layer "F.Cu")
		(net 450)
	)
	(segment
		(start 160.416804 103.592001)
		(end 160.095001 103.913804)
		(width 0.16)
		(layer "F.Cu")
		(net 450)
	)
	(via
		(at 160.730001 103.737001)
		(size 0.45)
		(drill 0.2)
		(layers "F.Cu" "B.Cu")
		(net 450)
	)
	(via
		(at 199 124)
		(size 0.45)
		(drill 0.2)
		(layers "F.Cu" "B.Cu")
		(net 450)
	)
	(segment
		(start 167.858501 124.005561)
		(end 168.159441 124.306501)
		(width 0.114)
		(layer "In5.Cu")
		(net 450)
	)
	(segment
		(start 160.730001 103.737001)
		(end 160.596501 103.603501)
		(width 0.114)
		(layer "In5.Cu")
		(net 450)
	)
	(segment
		(start 159.925987 103.298927)
		(end 159.925987 101.971075)
		(width 0.114)
		(layer "In5.Cu")
		(net 450)
	)
	(segment
		(start 160.490561 101.406501)
		(end 167.309441 101.406501)
		(width 0.114)
		(layer "In5.Cu")
		(net 450)
	)
	(segment
		(start 171.150001 124.650001)
		(end 171.150001 124.065274)
		(width 0.114)
		(layer "In5.Cu")
		(net 450)
	)
	(segment
		(start 199.000001 124.000001)
		(end 198.600001 124.400001)
		(width 0.1)
		(layer "In5.Cu")
		(net 450)
	)
	(segment
		(start 170.709441 124.856501)
		(end 170.943501 124.856501)
		(width 0.114)
		(layer "In5.Cu")
		(net 450)
	)
	(segment
		(start 167.858501 101.955561)
		(end 167.858501 124.005561)
		(width 0.114)
		(layer "In5.Cu")
		(net 450)
	)
	(segment
		(start 172.550001 124.650001)
		(end 172.550001 124.065274)
		(width 0.114)
		(layer "In5.Cu")
		(net 450)
	)
	(segment
		(start 160.230561 103.603501)
		(end 159.925987 103.298927)
		(width 0.114)
		(layer "In5.Cu")
		(net 450)
	)
	(segment
		(start 193.441423 125.400001)
		(end 192.941423 124.900001)
		(width 0.1)
		(layer "In5.Cu")
		(net 450)
	)
	(segment
		(start 195.400001 124.758579)
		(end 195.400001 125.183579)
		(width 0.1)
		(layer "In5.Cu")
		(net 450)
	)
	(segment
		(start 168.159441 124.306501)
		(end 170.159441 124.306501)
		(width 0.114)
		(layer "In5.Cu")
		(net 450)
	)
	(segment
		(start 183.448501 124.900001)
		(end 183.405001 124.856501)
		(width 0.1)
		(layer "In5.Cu")
		(net 450)
	)
	(segment
		(start 160.596501 103.603501)
		(end 160.230561 103.603501)
		(width 0.114)
		(layer "In5.Cu")
		(net 450)
	)
	(segment
		(start 167.309441 101.406501)
		(end 167.858501 101.955561)
		(width 0.114)
		(layer "In5.Cu")
		(net 450)
	)
	(segment
		(start 192.941423 124.900001)
		(end 183.448501 124.900001)
		(width 0.1)
		(layer "In5.Cu")
		(net 450)
	)
	(segment
		(start 195.183579 125.400001)
		(end 193.441423 125.400001)
		(width 0.1)
		(layer "In5.Cu")
		(net 450)
	)
	(segment
		(start 159.925987 101.971075)
		(end 160.490561 101.406501)
		(width 0.114)
		(layer "In5.Cu")
		(net 450)
	)
	(segment
		(start 173.743501 124.856501)
		(end 183.405001 124.856501)
		(width 0.114)
		(layer "In5.Cu")
		(net 450)
	)
	(segment
		(start 195.400001 125.183579)
		(end 195.183579 125.400001)
		(width 0.1)
		(layer "In5.Cu")
		(net 450)
	)
	(segment
		(start 173.537001 124.065274)
		(end 173.537001 124.650001)
		(width 0.114)
		(layer "In5.Cu")
		(net 450)
	)
	(segment
		(start 198.600001 124.400001)
		(end 195.758579 124.400001)
		(width 0.1)
		(layer "In5.Cu")
		(net 450)
	)
	(segment
		(start 195.758579 124.400001)
		(end 195.400001 124.758579)
		(width 0.1)
		(layer "In5.Cu")
		(net 450)
	)
	(segment
		(start 172.137001 124.065274)
		(end 172.137001 124.650001)
		(width 0.114)
		(layer "In5.Cu")
		(net 450)
	)
	(segment
		(start 170.159441 124.306501)
		(end 170.709441 124.856501)
		(width 0.114)
		(layer "In5.Cu")
		(net 450)
	)
	(arc
		(start 171.643501 123.571774)
		(mid 171.992458 123.716317)
		(end 172.137001 124.065274)
		(width 0.114)
		(layer "In5.Cu")
		(net 450)
	)
	(arc
		(start 172.550001 124.065274)
		(mid 172.694544 123.716317)
		(end 173.043501 123.571774)
		(width 0.114)
		(layer "In5.Cu")
		(net 450)
	)
	(arc
		(start 173.043501 123.571774)
		(mid 173.392458 123.716317)
		(end 173.537001 124.065274)
		(width 0.114)
		(layer "In5.Cu")
		(net 450)
	)
	(arc
		(start 171.150001 124.065274)
		(mid 171.294544 123.716317)
		(end 171.643501 123.571774)
		(width 0.114)
		(layer "In5.Cu")
		(net 450)
	)
	(arc
		(start 170.943501 124.856501)
		(mid 171.089519 124.796019)
		(end 171.150001 124.650001)
		(width 0.114)
		(layer "In5.Cu")
		(net 450)
	)
	(arc
		(start 172.343501 124.856501)
		(mid 172.489519 124.796019)
		(end 172.550001 124.650001)
		(width 0.114)
		(layer "In5.Cu")
		(net 450)
	)
	(arc
		(start 172.137001 124.650001)
		(mid 172.197483 124.796019)
		(end 172.343501 124.856501)
		(width 0.114)
		(layer "In5.Cu")
		(net 450)
	)
	(arc
		(start 173.537001 124.650001)
		(mid 173.597483 124.796019)
		(end 173.743501 124.856501)
		(width 0.114)
		(layer "In5.Cu")
		(net 450)
	)
	(segment
		(start 212.025879 135.985026)
		(end 211.985026 135.985026)
		(width 0.256)
		(layer "F.Cu")
		(net 451)
	)
	(segment
		(start 211.985026 135.985026)
		(end 211.5 135.5)
		(width 0.256)
		(layer "F.Cu")
		(net 451)
	)
	(via
		(at 254.1 86.7)
		(size 0.45)
		(drill 0.2)
		(layers "F.Cu" "B.Cu")
		(net 451)
	)
	(via
		(at 212.025879 135.985026)
		(size 0.45)
		(drill 0.2)
		(layers "F.Cu" "B.Cu")
		(net 451)
	)
	(segment
		(start 254.1 86.7)
		(end 253.1 86.7)
		(width 0.1)
		(layer "B.Cu")
		(net 451)
	)
	(segment
		(start 242.315 87.3)
		(end 240.199999 85.184999)
		(width 0.1)
		(layer "B.Cu")
		(net 451)
	)
	(segment
		(start 252.5 87.3)
		(end 242.315 87.3)
		(width 0.1)
		(layer "B.Cu")
		(net 451)
	)
	(segment
		(start 253.1 86.7)
		(end 252.5 87.3)
		(width 0.1)
		(layer "B.Cu")
		(net 451)
	)
	(segment
		(start 230.4 107.499998)
		(end 233.399998 104.5)
		(width 0.1)
		(layer "In3.Cu")
		(net 451)
	)
	(segment
		(start 215.982842 136.4)
		(end 216.382842 136.8)
		(width 0.1)
		(layer "In3.Cu")
		(net 451)
	)
	(segment
		(start 226.631368 136.6)
		(end 230.4 132.831368)
		(width 0.1)
		(layer "In3.Cu")
		(net 451)
	)
	(segment
		(start 253.499998 95.5)
		(end 254.7 94.299998)
		(width 0.1)
		(layer "In3.Cu")
		(net 451)
	)
	(segment
		(start 212.025879 135.985026)
		(end 212.640853 136.6)
		(width 0.1)
		(layer "In3.Cu")
		(net 451)
	)
	(segment
		(start 214.017158 136.6)
		(end 214.217158 136.4)
		(width 0.1)
		(layer "In3.Cu")
		(net 451)
	)
	(segment
		(start 244.1 104.5)
		(end 253.1 95.5)
		(width 0.1)
		(layer "In3.Cu")
		(net 451)
	)
	(segment
		(start 233.399998 104.5)
		(end 244.1 104.5)
		(width 0.1)
		(layer "In3.Cu")
		(net 451)
	)
	(segment
		(start 254.7 89.291421)
		(end 253.9 88.491421)
		(width 0.1)
		(layer "In3.Cu")
		(net 451)
	)
	(segment
		(start 221.75589 136.6)
		(end 226.631368 136.6)
		(width 0.1)
		(layer "In3.Cu")
		(net 451)
	)
	(segment
		(start 253.9 88.491421)
		(end 253.9 86.9)
		(width 0.1)
		(layer "In3.Cu")
		(net 451)
	)
	(segment
		(start 214.217158 136.4)
		(end 215.982842 136.4)
		(width 0.1)
		(layer "In3.Cu")
		(net 451)
	)
	(segment
		(start 216.382842 136.8)
		(end 221.55589 136.8)
		(width 0.1)
		(layer "In3.Cu")
		(net 451)
	)
	(segment
		(start 221.55589 136.8)
		(end 221.75589 136.6)
		(width 0.1)
		(layer "In3.Cu")
		(net 451)
	)
	(segment
		(start 230.4 132.831368)
		(end 230.4 107.499998)
		(width 0.1)
		(layer "In3.Cu")
		(net 451)
	)
	(segment
		(start 254.7 94.299998)
		(end 254.7 89.291421)
		(width 0.1)
		(layer "In3.Cu")
		(net 451)
	)
	(segment
		(start 212.640853 136.6)
		(end 214.017158 136.6)
		(width 0.1)
		(layer "In3.Cu")
		(net 451)
	)
	(segment
		(start 253.1 95.5)
		(end 253.499998 95.5)
		(width 0.1)
		(layer "In3.Cu")
		(net 451)
	)
	(segment
		(start 253.9 86.9)
		(end 254.1 86.7)
		(width 0.1)
		(layer "In3.Cu")
		(net 451)
	)
	(segment
		(start 214.5 137.5)
		(end 215 138)
		(width 0.256)
		(layer "F.Cu")
		(net 452)
	)
	(via
		(at 215 138)
		(size 0.45)
		(drill 0.2)
		(layers "F.Cu" "B.Cu")
		(net 452)
	)
	(via
		(at 255.9 85.1)
		(size 0.45)
		(drill 0.2)
		(layers "F.Cu" "B.Cu")
		(net 452)
	)
	(segment
		(start 253.5 85.1)
		(end 251.9 86.7)
		(width 0.1)
		(layer "B.Cu")
		(net 452)
	)
	(segment
		(start 244.215 86.7)
		(end 242.699999 85.184999)
		(width 0.1)
		(layer "B.Cu")
		(net 452)
	)
	(segment
		(start 251.9 86.7)
		(end 244.215 86.7)
		(width 0.1)
		(layer "B.Cu")
		(net 452)
	)
	(segment
		(start 255.9 85.1)
		(end 253.5 85.1)
		(width 0.1)
		(layer "B.Cu")
		(net 452)
	)
	(segment
		(start 254 97)
		(end 255.7 95.3)
		(width 0.1)
		(layer "In3.Cu")
		(net 452)
	)
	(segment
		(start 233.899998 106)
		(end 244.7 106)
		(width 0.1)
		(layer "In3.Cu")
		(net 452)
	)
	(segment
		(start 215 138)
		(end 216.1 138)
		(width 0.1)
		(layer "In3.Cu")
		(net 452)
	)
	(segment
		(start 244.7 106)
		(end 253.7 97)
		(width 0.1)
		(layer "In3.Cu")
		(net 452)
	)
	(segment
		(start 255.7 95.3)
		(end 255.7 87.7)
		(width 0.1)
		(layer "In3.Cu")
		(net 452)
	)
	(segment
		(start 253.7 97)
		(end 254 97)
		(width 0.1)
		(layer "In3.Cu")
		(net 452)
	)
	(segment
		(start 227.1 137.6)
		(end 231.9 132.8)
		(width 0.1)
		(layer "In3.Cu")
		(net 452)
	)
	(segment
		(start 231.9 107.999998)
		(end 233.899998 106)
		(width 0.1)
		(layer "In3.Cu")
		(net 452)
	)
	(segment
		(start 216.3 137.8)
		(end 221.970103 137.8)
		(width 0.1)
		(layer "In3.Cu")
		(net 452)
	)
	(segment
		(start 255.7 87.7)
		(end 255.3 87.3)
		(width 0.1)
		(layer "In3.Cu")
		(net 452)
	)
	(segment
		(start 216.1 138)
		(end 216.3 137.8)
		(width 0.1)
		(layer "In3.Cu")
		(net 452)
	)
	(segment
		(start 231.9 132.8)
		(end 231.9 107.999998)
		(width 0.1)
		(layer "In3.Cu")
		(net 452)
	)
	(segment
		(start 221.970103 137.8)
		(end 222.170103 137.6)
		(width 0.1)
		(layer "In3.Cu")
		(net 452)
	)
	(segment
		(start 255.3 85.7)
		(end 255.9 85.1)
		(width 0.1)
		(layer "In3.Cu")
		(net 452)
	)
	(segment
		(start 222.170103 137.6)
		(end 227.1 137.6)
		(width 0.1)
		(layer "In3.Cu")
		(net 452)
	)
	(segment
		(start 255.3 87.3)
		(end 255.3 85.7)
		(width 0.1)
		(layer "In3.Cu")
		(net 452)
	)
	(segment
		(start 209.5 136.5)
		(end 210 137)
		(width 0.256)
		(layer "F.Cu")
		(net 453)
	)
	(via
		(at 210 135)
		(size 0.45)
		(drill 0.2)
		(layers "F.Cu" "B.Cu")
		(net 453)
	)
	(via
		(at 210 137)
		(size 0.45)
		(drill 0.2)
		(layers "F.Cu" "B.Cu")
		(net 453)
	)
	(via
		(at 251.2 83.44)
		(size 0.45)
		(drill 0.2)
		(layers "F.Cu" "B.Cu")
		(net 453)
	)
	(segment
		(start 210 137)
		(end 210.4 136.6)
		(width 0.1)
		(layer "B.Cu")
		(net 453)
	)
	(segment
		(start 251.2 83.48)
		(end 248.78 85.9)
		(width 0.1)
		(layer "B.Cu")
		(net 453)
	)
	(segment
		(start 210.4 136.6)
		(end 210.4 135.4)
		(width 0.1)
		(layer "B.Cu")
		(net 453)
	)
	(segment
		(start 251.2 83.44)
		(end 251.2 83.48)
		(width 0.1)
		(layer "B.Cu")
		(net 453)
	)
	(segment
		(start 210.4 135.4)
		(end 210 135)
		(width 0.1)
		(layer "B.Cu")
		(net 453)
	)
	(segment
		(start 248.78 85.9)
		(end 246.115 85.9)
		(width 0.1)
		(layer "B.Cu")
		(net 453)
	)
	(segment
		(start 246.115 85.9)
		(end 245.299999 85.084999)
		(width 0.1)
		(layer "B.Cu")
		(net 453)
	)
	(segment
		(start 225.95 134.05)
		(end 223.55 134.05)
		(width 0.1)
		(layer "In3.Cu")
		(net 453)
	)
	(segment
		(start 227.1 132.9)
		(end 225.95 134.05)
		(width 0.1)
		(layer "In3.Cu")
		(net 453)
	)
	(segment
		(start 227.1 106.4)
		(end 227.1 132.9)
		(width 0.1)
		(layer "In3.Cu")
		(net 453)
	)
	(segment
		(start 223.55 134.05)
		(end 222.025 132.525)
		(width 0.1)
		(layer "In3.Cu")
		(net 453)
	)
	(segment
		(start 210.4 132.734314)
		(end 210.4 134.7)
		(width 0.1)
		(layer "In3.Cu")
		(net 453)
	)
	(segment
		(start 210.1 135)
		(end 210 135)
		(width 0.1)
		(layer "In3.Cu")
		(net 453)
	)
	(segment
		(start 222.025 132.525)
		(end 215.799263 132.525)
		(width 0.1)
		(layer "In3.Cu")
		(net 453)
	)
	(segment
		(start 210.4 134.7)
		(end 210.1 135)
		(width 0.1)
		(layer "In3.Cu")
		(net 453)
	)
	(segment
		(start 213.275 132.425)
		(end 210.709315 132.425)
		(width 0.1)
		(layer "In3.Cu")
		(net 453)
	)
	(segment
		(start 251.2 83.44)
		(end 251.2 92.575)
		(width 0.1)
		(layer "In3.Cu")
		(net 453)
	)
	(segment
		(start 242.575 101.2)
		(end 232.3 101.2)
		(width 0.1)
		(layer "In3.Cu")
		(net 453)
	)
	(segment
		(start 215.799263 132.525)
		(end 215.474263 132.2)
		(width 0.1)
		(layer "In3.Cu")
		(net 453)
	)
	(segment
		(start 251.2 92.575)
		(end 242.575 101.2)
		(width 0.1)
		(layer "In3.Cu")
		(net 453)
	)
	(segment
		(start 232.3 101.2)
		(end 227.1 106.4)
		(width 0.1)
		(layer "In3.Cu")
		(net 453)
	)
	(segment
		(start 210.709315 132.425)
		(end 210.4 132.734314)
		(width 0.1)
		(layer "In3.Cu")
		(net 453)
	)
	(segment
		(start 213.5 132.2)
		(end 213.275 132.425)
		(width 0.1)
		(layer "In3.Cu")
		(net 453)
	)
	(segment
		(start 215.474263 132.2)
		(end 213.5 132.2)
		(width 0.1)
		(layer "In3.Cu")
		(net 453)
	)
	(segment
		(start 174.675191 132.734811)
		(end 174.851261 132.734811)
		(width 0.201)
		(layer "F.Cu")
		(net 454)
	)
	(segment
		(start 187.83 133.500001)
		(end 187.899398 133.430602)
		(width 0.1)
		(layer "F.Cu")
		(net 454)
	)
	(segment
		(start 170.504001 103.592001)
		(end 168.218 103.592002)
		(width 0.16)
		(layer "F.Cu")
		(net 454)
	)
	(segment
		(start 174.851261 132.734811)
		(end 175.316451 133.200001)
		(width 0.201)
		(layer "F.Cu")
		(net 454)
	)
	(segment
		(start 187.778578 133.1)
		(end 187.236 133.1)
		(width 0.1)
		(layer "F.Cu")
		(net 454)
	)
	(segment
		(start 186.686 133.1)
		(end 183.446375 133.1)
		(width 0.1)
		(layer "F.Cu")
		(net 454)
	)
	(segment
		(start 171.770191 104.003741)
		(end 171.426951 103.660501)
		(width 0.201)
		(layer "F.Cu")
		(net 454)
	)
	(segment
		(start 187.5 133.5)
		(end 187.83 133.500001)
		(width 0.1)
		(layer "F.Cu")
		(net 454)
	)
	(segment
		(start 187.899398 133.22082)
		(end 187.778578 133.1)
		(width 0.1)
		(layer "F.Cu")
		(net 454)
	)
	(segment
		(start 186.861 133.272149)
		(end 186.861 133.225)
		(width 0.1)
		(layer "F.Cu")
		(net 454)
	)
	(segment
		(start 183.446375 133.1)
		(end 183.346375 133.2)
		(width 0.1)
		(layer "F.Cu")
		(net 454)
	)
	(segment
		(start 170.504001 103.592001)
		(end 170.572501 103.660501)
		(width 0.16)
		(layer "F.Cu")
		(net 454)
	)
	(segment
		(start 171.770191 104.179811)
		(end 171.770191 104.003741)
		(width 0.201)
		(layer "F.Cu")
		(net 454)
	)
	(segment
		(start 175.316451 133.200001)
		(end 183.346376 133.200001)
		(width 0.201)
		(layer "F.Cu")
		(net 454)
	)
	(segment
		(start 167.715001 104.095001)
		(end 168.218 103.592002)
		(width 0.16)
		(layer "F.Cu")
		(net 454)
	)
	(segment
		(start 171.426951 103.660501)
		(end 170.572501 103.660501)
		(width 0.201)
		(layer "F.Cu")
		(net 454)
	)
	(segment
		(start 187.111 133.225)
		(end 187.111 133.272149)
		(width 0.1)
		(layer "F.Cu")
		(net 454)
	)
	(segment
		(start 187.899398 133.430602)
		(end 187.899398 133.22082)
		(width 0.1)
		(layer "F.Cu")
		(net 454)
	)
	(segment
		(start 186.736 133.1)
		(end 186.686 133.1)
		(width 0.1)
		(layer "F.Cu")
		(net 454)
	)
	(via
		(at 174.675191 132.734811)
		(size 0.45)
		(drill 0.2)
		(layers "F.Cu" "B.Cu")
		(net 454)
	)
	(via
		(at 171.770191 104.179811)
		(size 0.45)
		(drill 0.2)
		(layers "F.Cu" "B.Cu")
		(net 454)
	)
	(arc
		(start 187.111 133.272149)
		(mid 187.074388 133.360537)
		(end 186.986 133.397149)
		(width 0.1)
		(layer "F.Cu")
		(net 454)
	)
	(arc
		(start 186.986 133.397149)
		(mid 186.897612 133.360537)
		(end 186.861 133.272149)
		(width 0.1)
		(layer "F.Cu")
		(net 454)
	)
	(arc
		(start 186.861 133.225)
		(mid 186.824388 133.136612)
		(end 186.736 133.1)
		(width 0.1)
		(layer "F.Cu")
		(net 454)
	)
	(arc
		(start 187.236 133.1)
		(mid 187.147612 133.136612)
		(end 187.111 133.225)
		(width 0.1)
		(layer "F.Cu")
		(net 454)
	)
	(segment
		(start 172.660922 104.894472)
		(end 171.946261 104.179811)
		(width 0.201)
		(layer "B.Cu")
		(net 454)
	)
	(segment
		(start 172.719501 130.603051)
		(end 172.719501 105.035894)
		(width 0.201)
		(layer "B.Cu")
		(net 454)
	)
	(segment
		(start 171.946261 104.179811)
		(end 171.770191 104.179811)
		(width 0.201)
		(layer "B.Cu")
		(net 454)
	)
	(segment
		(start 174.675191 132.734811)
		(end 174.675191 132.558741)
		(width 0.201)
		(layer "B.Cu")
		(net 454)
	)
	(segment
		(start 174.675191 132.558741)
		(end 172.719501 130.603051)
		(width 0.201)
		(layer "B.Cu")
		(net 454)
	)
	(arc
		(start 172.660922 104.894472)
		(mid 172.704277 104.959357)
		(end 172.719501 105.035894)
		(width 0.201)
		(layer "B.Cu")
		(net 454)
	)
	(segment
		(start 160.095001 102.825001)
		(end 160.095001 103.006198)
		(width 0.16)
		(layer "F.Cu")
		(net 455)
	)
	(segment
		(start 160.585002 103.328)
		(end 160.730001 103.183001)
		(width 0.16)
		(layer "F.Cu")
		(net 455)
	)
	(segment
		(start 160.585002 103.328)
		(end 160.416804 103.328001)
		(width 0.16)
		(layer "F.Cu")
		(net 455)
	)
	(segment
		(start 199.5 125.5)
		(end 199 125)
		(width 0.256)
		(layer "F.Cu")
		(net 455)
	)
	(segment
		(start 160.095001 103.006198)
		(end 160.416804 103.328001)
		(width 0.16)
		(layer "F.Cu")
		(net 455)
	)
	(via
		(at 160.730001 103.183001)
		(size 0.45)
		(drill 0.2)
		(layers "F.Cu" "B.Cu")
		(net 455)
	)
	(via
		(at 199 125)
		(size 0.45)
		(drill 0.2)
		(layers "F.Cu" "B.Cu")
		(net 455)
	)
	(segment
		(start 183.448501 125.100001)
		(end 183.405001 125.143501)
		(width 0.1)
		(layer "In5.Cu")
		(net 455)
	)
	(segment
		(start 173.743501 125.143501)
		(end 183.405001 125.143501)
		(width 0.114)
		(layer "In5.Cu")
		(net 455)
	)
	(segment
		(start 168.040561 124.593501)
		(end 170.040561 124.593501)
		(width 0.114)
		(layer "In5.Cu")
		(net 455)
	)
	(segment
		(start 160.609441 101.693501)
		(end 160.929501 101.693501)
		(width 0.114)
		(layer "In5.Cu")
		(net 455)
	)
	(segment
		(start 161.730712 101.693501)
		(end 167.190561 101.693501)
		(width 0.114)
		(layer "In5.Cu")
		(net 455)
	)
	(segment
		(start 160.596501 103.316501)
		(end 160.349441 103.316501)
		(width 0.114)
		(layer "In5.Cu")
		(net 455)
	)
	(segment
		(start 167.571501 124.124441)
		(end 168.040561 124.593501)
		(width 0.114)
		(layer "In5.Cu")
		(net 455)
	)
	(segment
		(start 160.730001 103.183001)
		(end 160.596501 103.316501)
		(width 0.114)
		(layer "In5.Cu")
		(net 455)
	)
	(segment
		(start 170.590561 125.143501)
		(end 170.943501 125.143501)
		(width 0.114)
		(layer "In5.Cu")
		(net 455)
	)
	(segment
		(start 195.841423 124.600001)
		(end 195.600001 124.841423)
		(width 0.1)
		(layer "In5.Cu")
		(net 455)
	)
	(segment
		(start 161.129501 101.893501)
		(end 161.129501 102.1312)
		(width 0.114)
		(layer "In5.Cu")
		(net 455)
	)
	(segment
		(start 195.600001 124.841423)
		(end 195.600001 125.266423)
		(width 0.1)
		(layer "In5.Cu")
		(net 455)
	)
	(segment
		(start 167.190561 101.693501)
		(end 167.571501 102.074441)
		(width 0.114)
		(layer "In5.Cu")
		(net 455)
	)
	(segment
		(start 199.000001 125.000001)
		(end 198.600001 124.600001)
		(width 0.1)
		(layer "In5.Cu")
		(net 455)
	)
	(segment
		(start 172.837001 124.650001)
		(end 172.837001 124.065274)
		(width 0.114)
		(layer "In5.Cu")
		(net 455)
	)
	(segment
		(start 193.358579 125.600001)
		(end 192.858579 125.100001)
		(width 0.1)
		(layer "In5.Cu")
		(net 455)
	)
	(segment
		(start 195.600001 125.266423)
		(end 195.266423 125.600001)
		(width 0.1)
		(layer "In5.Cu")
		(net 455)
	)
	(segment
		(start 198.600001 124.600001)
		(end 195.841423 124.600001)
		(width 0.1)
		(layer "In5.Cu")
		(net 455)
	)
	(segment
		(start 192.858579 125.100001)
		(end 183.448501 125.100001)
		(width 0.1)
		(layer "In5.Cu")
		(net 455)
	)
	(segment
		(start 161.529501 102.1312)
		(end 161.529501 101.893501)
		(width 0.114)
		(layer "In5.Cu")
		(net 455)
	)
	(segment
		(start 171.437001 124.650001)
		(end 171.437001 124.065274)
		(width 0.114)
		(layer "In5.Cu")
		(net 455)
	)
	(segment
		(start 173.250001 124.065274)
		(end 173.250001 124.650001)
		(width 0.114)
		(layer "In5.Cu")
		(net 455)
	)
	(segment
		(start 195.266423 125.600001)
		(end 193.358579 125.600001)
		(width 0.1)
		(layer "In5.Cu")
		(net 455)
	)
	(segment
		(start 161.729501 101.693501)
		(end 161.730712 101.693501)
		(width 0.114)
		(layer "In5.Cu")
		(net 455)
	)
	(segment
		(start 170.040561 124.593501)
		(end 170.590561 125.143501)
		(width 0.114)
		(layer "In5.Cu")
		(net 455)
	)
	(segment
		(start 160.349441 103.316501)
		(end 160.212987 103.180047)
		(width 0.114)
		(layer "In5.Cu")
		(net 455)
	)
	(segment
		(start 171.850001 124.065274)
		(end 171.850001 124.650001)
		(width 0.114)
		(layer "In5.Cu")
		(net 455)
	)
	(segment
		(start 160.212987 102.089955)
		(end 160.609441 101.693501)
		(width 0.114)
		(layer "In5.Cu")
		(net 455)
	)
	(segment
		(start 167.571501 102.074441)
		(end 167.571501 124.124441)
		(width 0.114)
		(layer "In5.Cu")
		(net 455)
	)
	(segment
		(start 160.212987 103.180047)
		(end 160.212987 102.089955)
		(width 0.114)
		(layer "In5.Cu")
		(net 455)
	)
	(arc
		(start 173.250001 124.650001)
		(mid 173.394544 124.998958)
		(end 173.743501 125.143501)
		(width 0.114)
		(layer "In5.Cu")
		(net 455)
	)
	(arc
		(start 171.437001 124.065274)
		(mid 171.497483 123.919256)
		(end 171.643501 123.858774)
		(width 0.114)
		(layer "In5.Cu")
		(net 455)
	)
	(arc
		(start 161.329501 102.3312)
		(mid 161.470922 102.272621)
		(end 161.529501 102.1312)
		(width 0.114)
		(layer "In5.Cu")
		(net 455)
	)
	(arc
		(start 161.129501 102.1312)
		(mid 161.18808 102.272621)
		(end 161.329501 102.3312)
		(width 0.114)
		(layer "In5.Cu")
		(net 455)
	)
	(arc
		(start 171.643501 123.858774)
		(mid 171.789519 123.919256)
		(end 171.850001 124.065274)
		(width 0.114)
		(layer "In5.Cu")
		(net 455)
	)
	(arc
		(start 172.837001 124.065274)
		(mid 172.897483 123.919256)
		(end 173.043501 123.858774)
		(width 0.114)
		(layer "In5.Cu")
		(net 455)
	)
	(arc
		(start 160.929501 101.693501)
		(mid 161.070922 101.75208)
		(end 161.129501 101.893501)
		(width 0.114)
		(layer "In5.Cu")
		(net 455)
	)
	(arc
		(start 171.850001 124.650001)
		(mid 171.994544 124.998958)
		(end 172.343501 125.143501)
		(width 0.114)
		(layer "In5.Cu")
		(net 455)
	)
	(arc
		(start 172.343501 125.143501)
		(mid 172.692458 124.998958)
		(end 172.837001 124.650001)
		(width 0.114)
		(layer "In5.Cu")
		(net 455)
	)
	(arc
		(start 173.043501 123.858774)
		(mid 173.189519 123.919256)
		(end 173.250001 124.065274)
		(width 0.114)
		(layer "In5.Cu")
		(net 455)
	)
	(arc
		(start 170.943501 125.143501)
		(mid 171.292458 124.998958)
		(end 171.437001 124.650001)
		(width 0.114)
		(layer "In5.Cu")
		(net 455)
	)
	(arc
		(start 161.529501 101.893501)
		(mid 161.58808 101.75208)
		(end 161.729501 101.693501)
		(width 0.114)
		(layer "In5.Cu")
		(net 455)
	)
	(segment
		(start 212.5 144.5)
		(end 213 145)
		(width 0.256)
		(layer "F.Cu")
		(net 456)
	)
	(via
		(at 213 145)
		(size 0.45)
		(drill 0.2)
		(layers "F.Cu" "B.Cu")
		(net 456)
	)
	(via
		(at 220.2 139.22)
		(size 0.45)
		(drill 0.2)
		(layers "F.Cu" "B.Cu")
		(net 456)
	)
	(via
		(at 214.2 75.6)
		(size 0.45)
		(drill 0.2)
		(layers "F.Cu" "B.Cu")
		(net 456)
	)
	(segment
		(start 220.2 142.1)
		(end 216.8 145.5)
		(width 0.1)
		(layer "B.Cu")
		(net 456)
	)
	(segment
		(start 214.199999 77.414999)
		(end 214.2 75.6)
		(width 0.1)
		(layer "B.Cu")
		(net 456)
	)
	(segment
		(start 220.2 139.22)
		(end 220.2 142.1)
		(width 0.1)
		(layer "B.Cu")
		(net 456)
	)
	(segment
		(start 216.8 145.5)
		(end 213.5 145.5)
		(width 0.1)
		(layer "B.Cu")
		(net 456)
	)
	(segment
		(start 213.5 145.5)
		(end 213 145)
		(width 0.1)
		(layer "B.Cu")
		(net 456)
	)
	(segment
		(start 221.05 76.1)
		(end 220.4 76.1)
		(width 0.1)
		(layer "In3.Cu")
		(net 456)
	)
	(segment
		(start 233.5 125.275)
		(end 233.5 108.799998)
		(width 0.1)
		(layer "In3.Cu")
		(net 456)
	)
	(segment
		(start 233.95 125.725)
		(end 233.5 125.275)
		(width 0.1)
		(layer "In3.Cu")
		(net 456)
	)
	(segment
		(start 251.9 75.6)
		(end 221.55 75.6)
		(width 0.1)
		(layer "In3.Cu")
		(net 456)
	)
	(segment
		(start 219.725 75.425)
		(end 214.375 75.425)
		(width 0.1)
		(layer "In3.Cu")
		(net 456)
	)
	(segment
		(start 233.7 126.95)
		(end 233.95 126.7)
		(width 0.1)
		(layer "In3.Cu")
		(net 456)
	)
	(segment
		(start 247.5 107.8)
		(end 256.9 98.4)
		(width 0.1)
		(layer "In3.Cu")
		(net 456)
	)
	(segment
		(start 222.467159 139)
		(end 222.667158 138.8)
		(width 0.1)
		(layer "In3.Cu")
		(net 456)
	)
	(segment
		(start 233.5 108.799998)
		(end 234.499998 107.8)
		(width 0.1)
		(layer "In3.Cu")
		(net 456)
	)
	(segment
		(start 214.375 75.425)
		(end 214.2 75.6)
		(width 0.1)
		(layer "In3.Cu")
		(net 456)
	)
	(segment
		(start 221.55 75.6)
		(end 221.05 76.1)
		(width 0.1)
		(layer "In3.Cu")
		(net 456)
	)
	(segment
		(start 220.42 139)
		(end 222.467159 139)
		(width 0.1)
		(layer "In3.Cu")
		(net 456)
	)
	(segment
		(start 256.9 80.6)
		(end 251.9 75.6)
		(width 0.1)
		(layer "In3.Cu")
		(net 456)
	)
	(segment
		(start 233.95 126.7)
		(end 233.95 125.725)
		(width 0.1)
		(layer "In3.Cu")
		(net 456)
	)
	(segment
		(start 222.667158 138.8)
		(end 227.682842 138.8)
		(width 0.1)
		(layer "In3.Cu")
		(net 456)
	)
	(segment
		(start 220.4 76.1)
		(end 219.725 75.425)
		(width 0.1)
		(layer "In3.Cu")
		(net 456)
	)
	(segment
		(start 220.2 139.22)
		(end 220.42 139)
		(width 0.1)
		(layer "In3.Cu")
		(net 456)
	)
	(segment
		(start 234.499998 107.8)
		(end 247.5 107.8)
		(width 0.1)
		(layer "In3.Cu")
		(net 456)
	)
	(segment
		(start 227.682842 138.8)
		(end 233.7 132.782842)
		(width 0.1)
		(layer "In3.Cu")
		(net 456)
	)
	(segment
		(start 233.7 132.782842)
		(end 233.7 126.95)
		(width 0.1)
		(layer "In3.Cu")
		(net 456)
	)
	(segment
		(start 256.9 98.4)
		(end 256.9 80.6)
		(width 0.1)
		(layer "In3.Cu")
		(net 456)
	)
	(segment
		(start 211.5 133.5)
		(end 212 134)
		(width 0.256)
		(layer "F.Cu")
		(net 457)
	)
	(via
		(at 212 134)
		(size 0.45)
		(drill 0.2)
		(layers "F.Cu" "B.Cu")
		(net 457)
	)
	(via
		(at 216.8 76.2)
		(size 0.45)
		(drill 0.2)
		(layers "F.Cu" "B.Cu")
		(net 457)
	)
	(segment
		(start 216.799999 77.414999)
		(end 216.8 76.2)
		(width 0.1)
		(layer "B.Cu")
		(net 457)
	)
	(segment
		(start 215.5 133.2)
		(end 216.5 134.2)
		(width 0.1)
		(layer "In3.Cu")
		(net 457)
	)
	(segment
		(start 215.5 132.8)
		(end 215.5 133.2)
		(width 0.1)
		(layer "In3.Cu")
		(net 457)
	)
	(segment
		(start 217.6 77)
		(end 216.8 76.2)
		(width 0.1)
		(layer "In3.Cu")
		(net 457)
	)
	(segment
		(start 213.5 132.765685)
		(end 213.665684 132.6)
		(width 0.1)
		(layer "In3.Cu")
		(net 457)
	)
	(segment
		(start 251.6 85.534835)
		(end 252.32 84.814835)
		(width 0.1)
		(layer "In3.Cu")
		(net 457)
	)
	(segment
		(start 227.7 132.882842)
		(end 227.7 106.6)
		(width 0.1)
		(layer "In3.Cu")
		(net 457)
	)
	(segment
		(start 212.6 133.4)
		(end 213.2 133.4)
		(width 0.1)
		(layer "In3.Cu")
		(net 457)
	)
	(segment
		(start 213.5 133.1)
		(end 213.5 132.765685)
		(width 0.1)
		(layer "In3.Cu")
		(net 457)
	)
	(segment
		(start 251.6 93)
		(end 251.6 85.534835)
		(width 0.1)
		(layer "In3.Cu")
		(net 457)
	)
	(segment
		(start 227.7 106.6)
		(end 232.5 101.8)
		(width 0.1)
		(layer "In3.Cu")
		(net 457)
	)
	(segment
		(start 215.3 132.6)
		(end 215.5 132.8)
		(width 0.1)
		(layer "In3.Cu")
		(net 457)
	)
	(segment
		(start 226.132843 134.45)
		(end 227.7 132.882842)
		(width 0.1)
		(layer "In3.Cu")
		(net 457)
	)
	(segment
		(start 242.8 101.8)
		(end 251.6 93)
		(width 0.1)
		(layer "In3.Cu")
		(net 457)
	)
	(segment
		(start 222.658579 77)
		(end 217.6 77)
		(width 0.1)
		(layer "In3.Cu")
		(net 457)
	)
	(segment
		(start 223.058578 76.6)
		(end 222.658579 77)
		(width 0.1)
		(layer "In3.Cu")
		(net 457)
	)
	(segment
		(start 212 134)
		(end 212.6 133.4)
		(width 0.1)
		(layer "In3.Cu")
		(net 457)
	)
	(segment
		(start 251.4 76.6)
		(end 223.058578 76.6)
		(width 0.1)
		(layer "In3.Cu")
		(net 457)
	)
	(segment
		(start 216.5 134.2)
		(end 220.667158 134.2)
		(width 0.1)
		(layer "In3.Cu")
		(net 457)
	)
	(segment
		(start 220.917158 134.45)
		(end 226.132843 134.45)
		(width 0.1)
		(layer "In3.Cu")
		(net 457)
	)
	(segment
		(start 213.665684 132.6)
		(end 215.3 132.6)
		(width 0.1)
		(layer "In3.Cu")
		(net 457)
	)
	(segment
		(start 232.5 101.8)
		(end 242.8 101.8)
		(width 0.1)
		(layer "In3.Cu")
		(net 457)
	)
	(segment
		(start 252.32 84.814835)
		(end 252.32 77.52)
		(width 0.1)
		(layer "In3.Cu")
		(net 457)
	)
	(segment
		(start 220.667158 134.2)
		(end 220.917158 134.45)
		(width 0.1)
		(layer "In3.Cu")
		(net 457)
	)
	(segment
		(start 252.32 77.52)
		(end 251.4 76.6)
		(width 0.1)
		(layer "In3.Cu")
		(net 457)
	)
	(segment
		(start 213.2 133.4)
		(end 213.5 133.1)
		(width 0.1)
		(layer "In3.Cu")
		(net 457)
	)
	(segment
		(start 212.984649 140.984649)
		(end 212.984649 141.025)
		(width 0.256)
		(layer "F.Cu")
		(net 458)
	)
	(segment
		(start 212.5 140.5)
		(end 212.984649 140.984649)
		(width 0.256)
		(layer "F.Cu")
		(net 458)
	)
	(via
		(at 212.984649 141.025)
		(size 0.45)
		(drill 0.2)
		(layers "F.Cu" "B.Cu")
		(net 458)
	)
	(via
		(at 219.4 76.2)
		(size 0.45)
		(drill 0.2)
		(layers "F.Cu" "B.Cu")
		(net 458)
	)
	(via
		(at 216 139)
		(size 0.45)
		(drill 0.2)
		(layers "F.Cu" "B.Cu")
		(net 458)
	)
	(segment
		(start 216 140.9)
		(end 216 139)
		(width 0.1)
		(layer "B.Cu")
		(net 458)
	)
	(segment
		(start 213.459649 141.5)
		(end 215.4 141.5)
		(width 0.1)
		(layer "B.Cu")
		(net 458)
	)
	(segment
		(start 212.984649 141.025)
		(end 213.459649 141.5)
		(width 0.1)
		(layer "B.Cu")
		(net 458)
	)
	(segment
		(start 219.399999 77.414999)
		(end 219.4 76.2)
		(width 0.1)
		(layer "B.Cu")
		(net 458)
	)
	(segment
		(start 215.4 141.5)
		(end 216 140.9)
		(width 0.1)
		(layer "B.Cu")
		(net 458)
	)
	(segment
		(start 251.7 76)
		(end 222.7 76)
		(width 0.1)
		(layer "In3.Cu")
		(net 458)
	)
	(segment
		(start 256.3 86.8)
		(end 255.9 86.4)
		(width 0.1)
		(layer "In3.Cu")
		(net 458)
	)
	(segment
		(start 222.218632 138.4)
		(end 222.418632 138.2)
		(width 0.1)
		(layer "In3.Cu")
		(net 458)
	)
	(segment
		(start 222.3 76.4)
		(end 219.6 76.4)
		(width 0.1)
		(layer "In3.Cu")
		(net 458)
	)
	(segment
		(start 255.9 86.4)
		(end 255.9 86)
		(width 0.1)
		(layer "In3.Cu")
		(net 458)
	)
	(segment
		(start 232.8 126.35)
		(end 232.7 126.25)
		(width 0.1)
		(layer "In3.Cu")
		(net 458)
	)
	(segment
		(start 222.418632 138.2)
		(end 227.4 138.2)
		(width 0.1)
		(layer "In3.Cu")
		(net 458)
	)
	(segment
		(start 227.4 138.2)
		(end 232.8 132.8)
		(width 0.1)
		(layer "In3.Cu")
		(net 458)
	)
	(segment
		(start 234.199998 106.9)
		(end 246.3 106.9)
		(width 0.1)
		(layer "In3.Cu")
		(net 458)
	)
	(segment
		(start 232.8 108.299998)
		(end 234.199998 106.9)
		(width 0.1)
		(layer "In3.Cu")
		(net 458)
	)
	(segment
		(start 256.3 96.9)
		(end 256.3 86.8)
		(width 0.1)
		(layer "In3.Cu")
		(net 458)
	)
	(segment
		(start 232.7 126.25)
		(end 232.7 125.2)
		(width 0.1)
		(layer "In3.Cu")
		(net 458)
	)
	(segment
		(start 246.3 106.9)
		(end 256.3 96.9)
		(width 0.1)
		(layer "In3.Cu")
		(net 458)
	)
	(segment
		(start 219.6 76.4)
		(end 219.4 76.2)
		(width 0.1)
		(layer "In3.Cu")
		(net 458)
	)
	(segment
		(start 222.7 76)
		(end 222.3 76.4)
		(width 0.1)
		(layer "In3.Cu")
		(net 458)
	)
	(segment
		(start 216.6 138.4)
		(end 222.218632 138.4)
		(width 0.1)
		(layer "In3.Cu")
		(net 458)
	)
	(segment
		(start 216 139)
		(end 216.6 138.4)
		(width 0.1)
		(layer "In3.Cu")
		(net 458)
	)
	(segment
		(start 232.8 132.8)
		(end 232.8 126.35)
		(width 0.1)
		(layer "In3.Cu")
		(net 458)
	)
	(segment
		(start 232.8 125.1)
		(end 232.8 108.299998)
		(width 0.1)
		(layer "In3.Cu")
		(net 458)
	)
	(segment
		(start 256.5 80.8)
		(end 251.7 76)
		(width 0.1)
		(layer "In3.Cu")
		(net 458)
	)
	(segment
		(start 255.9 86)
		(end 256.5 85.4)
		(width 0.1)
		(layer "In3.Cu")
		(net 458)
	)
	(segment
		(start 232.7 125.2)
		(end 232.8 125.1)
		(width 0.1)
		(layer "In3.Cu")
		(net 458)
	)
	(segment
		(start 256.5 85.4)
		(end 256.5 80.8)
		(width 0.1)
		(layer "In3.Cu")
		(net 458)
	)
	(segment
		(start 183.446375 132.9)
		(end 183.345375 132.799)
		(width 0.1)
		(layer "F.Cu")
		(net 459)
	)
	(segment
		(start 188.21 133.5)
		(end 188.099398 133.389398)
		(width 0.1)
		(layer "F.Cu")
		(net 459)
	)
	(segment
		(start 188.099398 133.137976)
		(end 187.861422 132.9)
		(width 0.1)
		(layer "F.Cu")
		(net 459)
	)
	(segment
		(start 167.715001 102.825001)
		(end 168.218 103.328)
		(width 0.16)
		(layer "F.Cu")
		(net 459)
	)
	(segment
		(start 172.053741 103.720191)
		(end 171.593051 103.259501)
		(width 0.201)
		(layer "F.Cu")
		(net 459)
	)
	(segment
		(start 172.229811 103.720191)
		(end 172.053741 103.720191)
		(width 0.201)
		(layer "F.Cu")
		(net 459)
	)
	(segment
		(start 187.861422 132.9)
		(end 183.446375 132.9)
		(width 0.1)
		(layer "F.Cu")
		(net 459)
	)
	(segment
		(start 188.099398 133.389398)
		(end 188.099398 133.137976)
		(width 0.1)
		(layer "F.Cu")
		(net 459)
	)
	(segment
		(start 170.504001 103.328001)
		(end 170.572501 103.259501)
		(width 0.16)
		(layer "F.Cu")
		(net 459)
	)
	(segment
		(start 188.5 133.5)
		(end 188.21 133.5)
		(width 0.1)
		(layer "F.Cu")
		(net 459)
	)
	(segment
		(start 175.134811 132.275191)
		(end 175.134811 132.451261)
		(width 0.201)
		(layer "F.Cu")
		(net 459)
	)
	(segment
		(start 171.593051 103.259501)
		(end 170.572501 103.259501)
		(width 0.201)
		(layer "F.Cu")
		(net 459)
	)
	(segment
		(start 175.482551 132.799001)
		(end 183.345376 132.799001)
		(width 0.201)
		(layer "F.Cu")
		(net 459)
	)
	(segment
		(start 170.504001 103.328001)
		(end 168.218 103.328)
		(width 0.16)
		(layer "F.Cu")
		(net 459)
	)
	(segment
		(start 175.134811 132.451261)
		(end 175.482551 132.799001)
		(width 0.201)
		(layer "F.Cu")
		(net 459)
	)
	(via
		(at 172.229811 103.720191)
		(size 0.45)
		(drill 0.2)
		(layers "F.Cu" "B.Cu")
		(net 459)
	)
	(via
		(at 175.134811 132.275191)
		(size 0.45)
		(drill 0.2)
		(layers "F.Cu" "B.Cu")
		(net 459)
	)
	(segment
		(start 175.134811 132.275191)
		(end 174.958741 132.275191)
		(width 0.201)
		(layer "B.Cu")
		(net 459)
	)
	(segment
		(start 172.229811 103.896261)
		(end 172.229811 103.720191)
		(width 0.201)
		(layer "B.Cu")
		(net 459)
	)
	(segment
		(start 173.120501 130.436951)
		(end 173.120501 104.953465)
		(width 0.201)
		(layer "B.Cu")
		(net 459)
	)
	(segment
		(start 173.002758 104.669208)
		(end 172.229811 103.896261)
		(width 0.201)
		(layer "B.Cu")
		(net 459)
	)
	(segment
		(start 174.958741 132.275191)
		(end 173.120501 130.436951)
		(width 0.201)
		(layer "B.Cu")
		(net 459)
	)
	(arc
		(start 173.002758 104.669208)
		(mid 173.089901 104.799626)
		(end 173.120501 104.953465)
		(width 0.201)
		(layer "B.Cu")
		(net 459)
	)
	(segment
		(start 159.315002 101.052002)
		(end 159.460001 101.197001)
		(width 0.16)
		(layer "F.Cu")
		(net 460)
	)
	(segment
		(start 159.315002 101.052002)
		(end 159.146804 101.052001)
		(width 0.16)
		(layer "F.Cu")
		(net 460)
	)
	(segment
		(start 159.146804 101.052001)
		(end 158.825001 101.373804)
		(width 0.16)
		(layer "F.Cu")
		(net 460)
	)
	(segment
		(start 197.5 123.5)
		(end 197 123)
		(width 0.256)
		(layer "F.Cu")
		(net 460)
	)
	(segment
		(start 158.825001 101.373804)
		(end 158.825001 101.555001)
		(width 0.16)
		(layer "F.Cu")
		(net 460)
	)
	(via
		(at 197 123)
		(size 0.45)
		(drill 0.2)
		(layers "F.Cu" "B.Cu")
		(net 460)
	)
	(via
		(at 159.460001 101.197001)
		(size 0.45)
		(drill 0.2)
		(layers "F.Cu" "B.Cu")
		(net 460)
	)
	(segment
		(start 197.000001 123.000001)
		(end 197.42 123.42)
		(width 0.1)
		(layer "In5.Cu")
		(net 460)
	)
	(segment
		(start 174.280001 96.102809)
		(end 174.280001 96.420001)
		(width 0.114)
		(layer "In5.Cu")
		(net 460)
	)
	(segment
		(start 172.467001 96.420001)
		(end 172.467001 96.102809)
		(width 0.114)
		(layer "In5.Cu")
		(net 460)
	)
	(segment
		(start 178.067001 96.420001)
		(end 178.067001 96.102809)
		(width 0.114)
		(layer "In5.Cu")
		(net 460)
	)
	(segment
		(start 172.880001 96.102809)
		(end 172.880001 96.420001)
		(width 0.114)
		(layer "In5.Cu")
		(net 460)
	)
	(segment
		(start 178.480001 96.102809)
		(end 178.480001 96.420001)
		(width 0.114)
		(layer "In5.Cu")
		(net 460)
	)
	(segment
		(start 197.356501 111.584441)
		(end 197.356501 113.405001)
		(width 0.114)
		(layer "In5.Cu")
		(net 460)
	)
	(segment
		(start 179.880001 96.102809)
		(end 179.880001 96.420001)
		(width 0.114)
		(layer "In5.Cu")
		(net 460)
	)
	(segment
		(start 161.505458 100.674971)
		(end 161.520043 100.689556)
		(width 0.114)
		(layer "In5.Cu")
		(net 460)
	)
	(segment
		(start 173.867001 96.420001)
		(end 173.867001 96.102809)
		(width 0.114)
		(layer "In5.Cu")
		(net 460)
	)
	(segment
		(start 180.373501 96.913501)
		(end 182.685561 96.913501)
		(width 0.114)
		(layer "In5.Cu")
		(net 460)
	)
	(segment
		(start 161.752944 100.179994)
		(end 161.752944 100.179995)
		(width 0.114)
		(layer "In5.Cu")
		(net 460)
	)
	(segment
		(start 160.869441 101.063501)
		(end 161.257971 100.674971)
		(width 0.114)
		(layer "In5.Cu")
		(net 460)
	)
	(segment
		(start 161.752944 100.179995)
		(end 162.789441 99.143501)
		(width 0.114)
		(layer "In5.Cu")
		(net 460)
	)
	(segment
		(start 197.400001 118.241423)
		(end 197.400001 113.448501)
		(width 0.1)
		(layer "In5.Cu")
		(net 460)
	)
	(segment
		(start 198.400001 123.239999)
		(end 198.400001 118.841423)
		(width 0.1)
		(layer "In5.Cu")
		(net 460)
	)
	(segment
		(start 175.267001 96.420001)
		(end 175.267001 96.102809)
		(width 0.114)
		(layer "In5.Cu")
		(net 460)
	)
	(segment
		(start 198.22 123.42)
		(end 198.400001 123.239999)
		(width 0.1)
		(layer "In5.Cu")
		(net 460)
	)
	(segment
		(start 168.859441 99.143501)
		(end 171.089441 96.913501)
		(width 0.114)
		(layer "In5.Cu")
		(net 460)
	)
	(segment
		(start 197.400001 113.448501)
		(end 197.356501 113.405001)
		(width 0.1)
		(layer "In5.Cu")
		(net 460)
	)
	(segment
		(start 198.158579 118.600001)
		(end 197.758579 118.600001)
		(width 0.1)
		(layer "In5.Cu")
		(net 460)
	)
	(segment
		(start 179.467001 96.420001)
		(end 179.467001 96.102809)
		(width 0.114)
		(layer "In5.Cu")
		(net 460)
	)
	(segment
		(start 177.080001 96.102809)
		(end 177.080001 96.420001)
		(width 0.114)
		(layer "In5.Cu")
		(net 460)
	)
	(segment
		(start 175.680001 96.102809)
		(end 175.680001 96.420001)
		(width 0.114)
		(layer "In5.Cu")
		(net 460)
	)
	(segment
		(start 159.593501 101.063501)
		(end 160.869441 101.063501)
		(width 0.114)
		(layer "In5.Cu")
		(net 460)
	)
	(segment
		(start 197.758579 118.600001)
		(end 197.400001 118.241423)
		(width 0.1)
		(layer "In5.Cu")
		(net 460)
	)
	(segment
		(start 197.42 123.42)
		(end 198.22 123.42)
		(width 0.1)
		(layer "In5.Cu")
		(net 460)
	)
	(segment
		(start 182.685561 96.913501)
		(end 197.356501 111.584441)
		(width 0.114)
		(layer "In5.Cu")
		(net 460)
	)
	(segment
		(start 176.667001 96.420001)
		(end 176.667001 96.102809)
		(width 0.114)
		(layer "In5.Cu")
		(net 460)
	)
	(segment
		(start 162.789441 99.143501)
		(end 168.859441 99.143501)
		(width 0.114)
		(layer "In5.Cu")
		(net 460)
	)
	(segment
		(start 161.767531 100.689556)
		(end 161.76753 100.689556)
		(width 0.114)
		(layer "In5.Cu")
		(net 460)
	)
	(segment
		(start 171.089441 96.913501)
		(end 171.973501 96.913501)
		(width 0.114)
		(layer "In5.Cu")
		(net 460)
	)
	(segment
		(start 198.400001 118.841423)
		(end 198.158579 118.600001)
		(width 0.1)
		(layer "In5.Cu")
		(net 460)
	)
	(segment
		(start 161.76753 100.442068)
		(end 161.752944 100.427482)
		(width 0.114)
		(layer "In5.Cu")
		(net 460)
	)
	(segment
		(start 161.505457 100.674971)
		(end 161.505458 100.674971)
		(width 0.114)
		(layer "In5.Cu")
		(net 460)
	)
	(segment
		(start 159.460001 101.197001)
		(end 159.593501 101.063501)
		(width 0.114)
		(layer "In5.Cu")
		(net 460)
	)
	(arc
		(start 161.76753 100.689556)
		(mid 161.818786 100.565812)
		(end 161.76753 100.442068)
		(width 0.114)
		(layer "In5.Cu")
		(net 460)
	)
	(arc
		(start 179.880001 96.420001)
		(mid 180.024544 96.768958)
		(end 180.373501 96.913501)
		(width 0.114)
		(layer "In5.Cu")
		(net 460)
	)
	(arc
		(start 173.867001 96.102809)
		(mid 173.927483 95.956791)
		(end 174.073501 95.896309)
		(width 0.114)
		(layer "In5.Cu")
		(net 460)
	)
	(arc
		(start 172.467001 96.102809)
		(mid 172.527483 95.956791)
		(end 172.673501 95.896309)
		(width 0.114)
		(layer "In5.Cu")
		(net 460)
	)
	(arc
		(start 176.173501 96.913501)
		(mid 176.522458 96.768958)
		(end 176.667001 96.420001)
		(width 0.114)
		(layer "In5.Cu")
		(net 460)
	)
	(arc
		(start 172.880001 96.420001)
		(mid 173.024544 96.768958)
		(end 173.373501 96.913501)
		(width 0.114)
		(layer "In5.Cu")
		(net 460)
	)
	(arc
		(start 177.080001 96.420001)
		(mid 177.224544 96.768958)
		(end 177.573501 96.913501)
		(width 0.114)
		(layer "In5.Cu")
		(net 460)
	)
	(arc
		(start 176.873501 95.896309)
		(mid 177.019519 95.956791)
		(end 177.080001 96.102809)
		(width 0.114)
		(layer "In5.Cu")
		(net 460)
	)
	(arc
		(start 174.073501 95.896309)
		(mid 174.219519 95.956791)
		(end 174.280001 96.102809)
		(width 0.114)
		(layer "In5.Cu")
		(net 460)
	)
	(arc
		(start 179.673501 95.896309)
		(mid 179.819519 95.956791)
		(end 179.880001 96.102809)
		(width 0.114)
		(layer "In5.Cu")
		(net 460)
	)
	(arc
		(start 175.267001 96.102809)
		(mid 175.327483 95.956791)
		(end 175.473501 95.896309)
		(width 0.114)
		(layer "In5.Cu")
		(net 460)
	)
	(arc
		(start 178.480001 96.420001)
		(mid 178.624544 96.768958)
		(end 178.973501 96.913501)
		(width 0.114)
		(layer "In5.Cu")
		(net 460)
	)
	(arc
		(start 178.973501 96.913501)
		(mid 179.322458 96.768958)
		(end 179.467001 96.420001)
		(width 0.114)
		(layer "In5.Cu")
		(net 460)
	)
	(arc
		(start 172.673501 95.896309)
		(mid 172.819519 95.956791)
		(end 172.880001 96.102809)
		(width 0.114)
		(layer "In5.Cu")
		(net 460)
	)
	(arc
		(start 179.467001 96.102809)
		(mid 179.527483 95.956791)
		(end 179.673501 95.896309)
		(width 0.114)
		(layer "In5.Cu")
		(net 460)
	)
	(arc
		(start 171.973501 96.913501)
		(mid 172.322458 96.768958)
		(end 172.467001 96.420001)
		(width 0.114)
		(layer "In5.Cu")
		(net 460)
	)
	(arc
		(start 175.680001 96.420001)
		(mid 175.824544 96.768958)
		(end 176.173501 96.913501)
		(width 0.114)
		(layer "In5.Cu")
		(net 460)
	)
	(arc
		(start 173.373501 96.913501)
		(mid 173.722458 96.768958)
		(end 173.867001 96.420001)
		(width 0.114)
		(layer "In5.Cu")
		(net 460)
	)
	(arc
		(start 177.573501 96.913501)
		(mid 177.922458 96.768958)
		(end 178.067001 96.420001)
		(width 0.114)
		(layer "In5.Cu")
		(net 460)
	)
	(arc
		(start 176.667001 96.102809)
		(mid 176.727483 95.956791)
		(end 176.873501 95.896309)
		(width 0.114)
		(layer "In5.Cu")
		(net 460)
	)
	(arc
		(start 174.773501 96.913501)
		(mid 175.122458 96.768958)
		(end 175.267001 96.420001)
		(width 0.114)
		(layer "In5.Cu")
		(net 460)
	)
	(arc
		(start 178.273501 95.896309)
		(mid 178.419519 95.956791)
		(end 178.480001 96.102809)
		(width 0.114)
		(layer "In5.Cu")
		(net 460)
	)
	(arc
		(start 161.752944 100.427482)
		(mid 161.701688 100.303738)
		(end 161.752944 100.179994)
		(width 0.114)
		(layer "In5.Cu")
		(net 460)
	)
	(arc
		(start 174.280001 96.420001)
		(mid 174.424544 96.768958)
		(end 174.773501 96.913501)
		(width 0.114)
		(layer "In5.Cu")
		(net 460)
	)
	(arc
		(start 175.473501 95.896309)
		(mid 175.619519 95.956791)
		(end 175.680001 96.102809)
		(width 0.114)
		(layer "In5.Cu")
		(net 460)
	)
	(arc
		(start 178.067001 96.102809)
		(mid 178.127483 95.956791)
		(end 178.273501 95.896309)
		(width 0.114)
		(layer "In5.Cu")
		(net 460)
	)
	(arc
		(start 161.520043 100.689556)
		(mid 161.643787 100.740812)
		(end 161.767531 100.689556)
		(width 0.114)
		(layer "In5.Cu")
		(net 460)
	)
	(arc
		(start 161.257971 100.674971)
		(mid 161.381714 100.623715)
		(end 161.505457 100.674971)
		(width 0.114)
		(layer "In5.Cu")
		(net 460)
	)
	(segment
		(start 212.5 143.5)
		(end 213 144)
		(width 0.182)
		(layer "F.Cu")
		(net 461)
	)
	(via
		(at 213 144)
		(size 0.45)
		(drill 0.2)
		(layers "F.Cu" "B.Cu")
		(net 461)
	)
	(via
		(at 222 76)
		(size 0.45)
		(drill 0.2)
		(layers "F.Cu" "B.Cu")
		(net 461)
	)
	(via
		(at 218.12 139.25)
		(size 0.45)
		(drill 0.2)
		(layers "F.Cu" "B.Cu")
		(net 461)
	)
	(segment
		(start 213.5 144.5)
		(end 213 144)
		(width 0.1)
		(layer "B.Cu")
		(net 461)
	)
	(segment
		(start 217.7 139.67)
		(end 217.7 142.9)
		(width 0.1)
		(layer "B.Cu")
		(net 461)
	)
	(segment
		(start 217.7 142.9)
		(end 216.1 144.5)
		(width 0.1)
		(layer "B.Cu")
		(net 461)
	)
	(segment
		(start 216.1 144.5)
		(end 213.5 144.5)
		(width 0.1)
		(layer "B.Cu")
		(net 461)
	)
	(segment
		(start 218.12 139.25)
		(end 217.7 139.67)
		(width 0.1)
		(layer "B.Cu")
		(net 461)
	)
	(segment
		(start 221.999999 77.414999)
		(end 222 76)
		(width 0.1)
		(layer "B.Cu")
		(net 461)
	)
	(segment
		(start 234.399998 107.5)
		(end 247.4 107.5)
		(width 0.1)
		(layer "In3.Cu")
		(net 461)
	)
	(segment
		(start 233.725 126.575)
		(end 233.725 125.8)
		(width 0.1)
		(layer "In3.Cu")
		(net 461)
	)
	(segment
		(start 222.384316 138.8)
		(end 222.584316 138.6)
		(width 0.1)
		(layer "In3.Cu")
		(net 461)
	)
	(segment
		(start 222.584316 138.6)
		(end 227.582842 138.6)
		(width 0.1)
		(layer "In3.Cu")
		(net 461)
	)
	(segment
		(start 233.725 125.8)
		(end 233.275 125.35)
		(width 0.1)
		(layer "In3.Cu")
		(net 461)
	)
	(segment
		(start 222.2 75.8)
		(end 222 76)
		(width 0.1)
		(layer "In3.Cu")
		(net 461)
	)
	(segment
		(start 256.7 98.2)
		(end 256.7 80.7)
		(width 0.1)
		(layer "In3.Cu")
		(net 461)
	)
	(segment
		(start 218.12 139.25)
		(end 218.57 138.8)
		(width 0.1)
		(layer "In3.Cu")
		(net 461)
	)
	(segment
		(start 233.275 125.35)
		(end 233.275 108.624998)
		(width 0.1)
		(layer "In3.Cu")
		(net 461)
	)
	(segment
		(start 233.4 132.782842)
		(end 233.4 126.9)
		(width 0.1)
		(layer "In3.Cu")
		(net 461)
	)
	(segment
		(start 251.8 75.8)
		(end 222.2 75.8)
		(width 0.1)
		(layer "In3.Cu")
		(net 461)
	)
	(segment
		(start 233.4 126.9)
		(end 233.725 126.575)
		(width 0.1)
		(layer "In3.Cu")
		(net 461)
	)
	(segment
		(start 218.57 138.8)
		(end 222.384316 138.8)
		(width 0.1)
		(layer "In3.Cu")
		(net 461)
	)
	(segment
		(start 227.582842 138.6)
		(end 233.4 132.782842)
		(width 0.1)
		(layer "In3.Cu")
		(net 461)
	)
	(segment
		(start 256.7 80.7)
		(end 251.8 75.8)
		(width 0.1)
		(layer "In3.Cu")
		(net 461)
	)
	(segment
		(start 247.4 107.5)
		(end 256.7 98.2)
		(width 0.1)
		(layer "In3.Cu")
		(net 461)
	)
	(segment
		(start 233.275 108.624998)
		(end 234.399998 107.5)
		(width 0.1)
		(layer "In3.Cu")
		(net 461)
	)
	(segment
		(start 214.5 136.5)
		(end 215 137)
		(width 0.256)
		(layer "F.Cu")
		(net 462)
	)
	(via
		(at 215 137)
		(size 0.45)
		(drill 0.2)
		(layers "F.Cu" "B.Cu")
		(net 462)
	)
	(via
		(at 254.9255 88.6)
		(size 0.45)
		(drill 0.2)
		(layers "F.Cu" "B.Cu")
		(net 462)
	)
	(segment
		(start 253.7 88.2)
		(end 239.314999 88.2)
		(width 0.1)
		(layer "B.Cu")
		(net 462)
	)
	(segment
		(start 239.314999 88.2)
		(end 236.299999 85.185)
		(width 0.1)
		(layer "B.Cu")
		(net 462)
	)
	(segment
		(start 254.1 88.6)
		(end 253.7 88.2)
		(width 0.1)
		(layer "B.Cu")
		(net 462)
	)
	(segment
		(start 254.9255 88.6)
		(end 254.1 88.6)
		(width 0.1)
		(layer "B.Cu")
		(net 462)
	)
	(segment
		(start 226.8 137)
		(end 221.921576 137)
		(width 0.1)
		(layer "In3.Cu")
		(net 462)
	)
	(segment
		(start 253.699997 96.1)
		(end 253.4 96.1)
		(width 0.1)
		(layer "In3.Cu")
		(net 462)
	)
	(segment
		(start 231 107.699998)
		(end 231 132.8)
		(width 0.1)
		(layer "In3.Cu")
		(net 462)
	)
	(segment
		(start 221.721577 137.2)
		(end 215.2 137.2)
		(width 0.1)
		(layer "In3.Cu")
		(net 462)
	)
	(segment
		(start 231 132.8)
		(end 226.8 137)
		(width 0.1)
		(layer "In3.Cu")
		(net 462)
	)
	(segment
		(start 255.1 88.7745)
		(end 255.1 94.699997)
		(width 0.1)
		(layer "In3.Cu")
		(net 462)
	)
	(segment
		(start 244.4 105.1)
		(end 233.599998 105.1)
		(width 0.1)
		(layer "In3.Cu")
		(net 462)
	)
	(segment
		(start 253.4 96.1)
		(end 244.4 105.1)
		(width 0.1)
		(layer "In3.Cu")
		(net 462)
	)
	(segment
		(start 233.599998 105.1)
		(end 231 107.699998)
		(width 0.1)
		(layer "In3.Cu")
		(net 462)
	)
	(segment
		(start 254.9255 88.6)
		(end 255.1 88.7745)
		(width 0.1)
		(layer "In3.Cu")
		(net 462)
	)
	(segment
		(start 215.2 137.2)
		(end 215 137)
		(width 0.1)
		(layer "In3.Cu")
		(net 462)
	)
	(segment
		(start 221.921576 137)
		(end 221.721577 137.2)
		(width 0.1)
		(layer "In3.Cu")
		(net 462)
	)
	(segment
		(start 255.1 94.699997)
		(end 253.699997 96.1)
		(width 0.1)
		(layer "In3.Cu")
		(net 462)
	)
	(segment
		(start 166.445001 101.555001)
		(end 166.948 101.052002)
		(width 0.16)
		(layer "F.Cu")
		(net 463)
	)
	(segment
		(start 170.641001 101.120501)
		(end 171.475001 101.120501)
		(width 0.201)
		(layer "F.Cu")
		(net 463)
	)
	(segment
		(start 166.948 101.052002)
		(end 170.572501 101.052001)
		(width 0.16)
		(layer "F.Cu")
		(net 463)
	)
	(segment
		(start 171.599501 101.245001)
		(end 171.475001 101.120501)
		(width 0.16)
		(layer "F.Cu")
		(net 463)
	)
	(segment
		(start 170.572501 101.052001)
		(end 170.641001 101.120501)
		(width 0.16)
		(layer "F.Cu")
		(net 463)
	)
	(via
		(at 189.5 134.5)
		(size 0.45)
		(drill 0.2)
		(layers "F.Cu" "B.Cu")
		(net 463)
	)
	(via
		(at 171.599501 101.245001)
		(size 0.45)
		(drill 0.2)
		(layers "F.Cu" "B.Cu")
		(net 463)
	)
	(segment
		(start 188.713 134.100002)
		(end 183.446376 134.100001)
		(width 0.1)
		(layer "B.Cu")
		(net 463)
	)
	(segment
		(start 171.599501 101.245001)
		(end 171.724002 101.120501)
		(width 0.201)
		(layer "B.Cu")
		(net 463)
	)
	(segment
		(start 189.830002 134.500001)
		(end 189.8994 134.430604)
		(width 0.1)
		(layer "B.Cu")
		(net 463)
	)
	(segment
		(start 172.251951 101.120501)
		(end 174.024501 102.893051)
		(width 0.201)
		(layer "B.Cu")
		(net 463)
	)
	(segment
		(start 178.246451 134.200001)
		(end 183.346376 134.200001)
		(width 0.201)
		(layer "B.Cu")
		(net 463)
	)
	(segment
		(start 188.763 134.100002)
		(end 188.713 134.100002)
		(width 0.1)
		(layer "B.Cu")
		(net 463)
	)
	(segment
		(start 171.724002 101.120501)
		(end 172.251951 101.120501)
		(width 0.201)
		(layer "B.Cu")
		(net 463)
	)
	(segment
		(start 174.024501 102.893051)
		(end 174.024501 129.978051)
		(width 0.201)
		(layer "B.Cu")
		(net 463)
	)
	(segment
		(start 189.77858 134.100002)
		(end 189.263 134.100002)
		(width 0.1)
		(layer "B.Cu")
		(net 463)
	)
	(segment
		(start 183.446376 134.100001)
		(end 183.346376 134.200001)
		(width 0.1)
		(layer "B.Cu")
		(net 463)
	)
	(segment
		(start 189.138 134.225002)
		(end 189.138 134.229234)
		(width 0.1)
		(layer "B.Cu")
		(net 463)
	)
	(segment
		(start 189.8994 134.220821)
		(end 189.77858 134.100002)
		(width 0.1)
		(layer "B.Cu")
		(net 463)
	)
	(segment
		(start 174.024501 129.978051)
		(end 178.246451 134.200001)
		(width 0.201)
		(layer "B.Cu")
		(net 463)
	)
	(segment
		(start 189.500001 134.500001)
		(end 189.830002 134.500001)
		(width 0.1)
		(layer "B.Cu")
		(net 463)
	)
	(segment
		(start 189.8994 134.430604)
		(end 189.8994 134.220821)
		(width 0.1)
		(layer "B.Cu")
		(net 463)
	)
	(segment
		(start 188.888 134.229234)
		(end 188.888 134.225002)
		(width 0.1)
		(layer "B.Cu")
		(net 463)
	)
	(arc
		(start 189.138 134.229234)
		(mid 189.101388 134.317622)
		(end 189.013 134.354234)
		(width 0.1)
		(layer "B.Cu")
		(net 463)
	)
	(arc
		(start 189.263 134.100002)
		(mid 189.174612 134.136614)
		(end 189.138 134.225002)
		(width 0.1)
		(layer "B.Cu")
		(net 463)
	)
	(arc
		(start 189.013 134.354234)
		(mid 188.924612 134.317622)
		(end 188.888 134.229234)
		(width 0.1)
		(layer "B.Cu")
		(net 463)
	)
	(arc
		(start 188.888 134.225002)
		(mid 188.851388 134.136614)
		(end 188.763 134.100002)
		(width 0.1)
		(layer "B.Cu")
		(net 463)
	)
	(segment
		(start 197.015445 124.015445)
		(end 197.015445 123.975001)
		(width 0.256)
		(layer "F.Cu")
		(net 464)
	)
	(segment
		(start 159.315002 100.788)
		(end 159.146804 100.788001)
		(width 0.16)
		(layer "F.Cu")
		(net 464)
	)
	(segment
		(start 159.315002 100.788)
		(end 159.460001 100.643001)
		(width 0.16)
		(layer "F.Cu")
		(net 464)
	)
	(segment
		(start 197.5 124.5)
		(end 197.015445 124.015445)
		(width 0.256)
		(layer "F.Cu")
		(net 464)
	)
	(segment
		(start 158.825001 100.285001)
		(end 158.825001 100.466198)
		(width 0.16)
		(layer "F.Cu")
		(net 464)
	)
	(segment
		(start 158.825001 100.466198)
		(end 159.146804 100.788001)
		(width 0.16)
		(layer "F.Cu")
		(net 464)
	)
	(via
		(at 197.015445 123.975001)
		(size 0.45)
		(drill 0.2)
		(layers "F.Cu" "B.Cu")
		(net 464)
	)
	(via
		(at 159.460001 100.643001)
		(size 0.45)
		(drill 0.2)
		(layers "F.Cu" "B.Cu")
		(net 464)
	)
	(segment
		(start 176.380001 96.420001)
		(end 176.380001 96.102809)
		(width 0.114)
		(layer "In5.Cu")
		(net 464)
	)
	(segment
		(start 174.980001 96.420001)
		(end 174.980001 96.102809)
		(width 0.114)
		(layer "In5.Cu")
		(net 464)
	)
	(segment
		(start 162.670561 98.856501)
		(end 168.740561 98.856501)
		(width 0.114)
		(layer "In5.Cu")
		(net 464)
	)
	(segment
		(start 172.180001 96.420001)
		(end 172.180001 96.102809)
		(width 0.114)
		(layer "In5.Cu")
		(net 464)
	)
	(segment
		(start 179.180001 96.420001)
		(end 179.180001 96.102809)
		(width 0.114)
		(layer "In5.Cu")
		(net 464)
	)
	(segment
		(start 197.000001 124.000001)
		(end 197.380002 123.62)
		(width 0.1)
		(layer "In5.Cu")
		(net 464)
	)
	(segment
		(start 180.373501 96.626501)
		(end 182.804441 96.626501)
		(width 0.114)
		(layer "In5.Cu")
		(net 464)
	)
	(segment
		(start 180.167001 96.102809)
		(end 180.167001 96.420001)
		(width 0.114)
		(layer "In5.Cu")
		(net 464)
	)
	(segment
		(start 198.302842 123.62)
		(end 198.600001 123.322841)
		(width 0.1)
		(layer "In5.Cu")
		(net 464)
	)
	(segment
		(start 175.967001 96.102809)
		(end 175.967001 96.420001)
		(width 0.114)
		(layer "In5.Cu")
		(net 464)
	)
	(segment
		(start 182.804441 96.626501)
		(end 197.643501 111.465561)
		(width 0.114)
		(layer "In5.Cu")
		(net 464)
	)
	(segment
		(start 174.567001 96.102809)
		(end 174.567001 96.420001)
		(width 0.114)
		(layer "In5.Cu")
		(net 464)
	)
	(segment
		(start 197.643501 111.465561)
		(end 197.643501 113.405001)
		(width 0.114)
		(layer "In5.Cu")
		(net 464)
	)
	(segment
		(start 197.600001 113.448501)
		(end 197.643501 113.405001)
		(width 0.1)
		(layer "In5.Cu")
		(net 464)
	)
	(segment
		(start 197.600001 118.158579)
		(end 197.600001 113.448501)
		(width 0.1)
		(layer "In5.Cu")
		(net 464)
	)
	(segment
		(start 197.841423 118.400001)
		(end 197.600001 118.158579)
		(width 0.1)
		(layer "In5.Cu")
		(net 464)
	)
	(segment
		(start 197.380002 123.62)
		(end 198.302842 123.62)
		(width 0.1)
		(layer "In5.Cu")
		(net 464)
	)
	(segment
		(start 159.593501 100.776501)
		(end 160.750561 100.776501)
		(width 0.114)
		(layer "In5.Cu")
		(net 464)
	)
	(segment
		(start 160.750561 100.776501)
		(end 162.670561 98.856501)
		(width 0.114)
		(layer "In5.Cu")
		(net 464)
	)
	(segment
		(start 173.580001 96.420001)
		(end 173.580001 96.102809)
		(width 0.114)
		(layer "In5.Cu")
		(net 464)
	)
	(segment
		(start 159.460001 100.643001)
		(end 159.593501 100.776501)
		(width 0.114)
		(layer "In5.Cu")
		(net 464)
	)
	(segment
		(start 177.367001 96.102809)
		(end 177.367001 96.420001)
		(width 0.114)
		(layer "In5.Cu")
		(net 464)
	)
	(segment
		(start 198.600001 123.322841)
		(end 198.600001 118.758579)
		(width 0.1)
		(layer "In5.Cu")
		(net 464)
	)
	(segment
		(start 168.740561 98.856501)
		(end 170.970561 96.626501)
		(width 0.114)
		(layer "In5.Cu")
		(net 464)
	)
	(segment
		(start 173.167001 96.102809)
		(end 173.167001 96.420001)
		(width 0.114)
		(layer "In5.Cu")
		(net 464)
	)
	(segment
		(start 177.780001 96.420001)
		(end 177.780001 96.102809)
		(width 0.114)
		(layer "In5.Cu")
		(net 464)
	)
	(segment
		(start 178.767001 96.102809)
		(end 178.767001 96.420001)
		(width 0.114)
		(layer "In5.Cu")
		(net 464)
	)
	(segment
		(start 198.600001 118.758579)
		(end 198.241421 118.400001)
		(width 0.1)
		(layer "In5.Cu")
		(net 464)
	)
	(segment
		(start 170.970561 96.626501)
		(end 171.973501 96.626501)
		(width 0.114)
		(layer "In5.Cu")
		(net 464)
	)
	(segment
		(start 198.241421 118.400001)
		(end 197.841423 118.400001)
		(width 0.1)
		(layer "In5.Cu")
		(net 464)
	)
	(arc
		(start 180.167001 96.420001)
		(mid 180.227483 96.566019)
		(end 180.373501 96.626501)
		(width 0.114)
		(layer "In5.Cu")
		(net 464)
	)
	(arc
		(start 178.273501 95.609309)
		(mid 178.622458 95.753852)
		(end 178.767001 96.102809)
		(width 0.114)
		(layer "In5.Cu")
		(net 464)
	)
	(arc
		(start 175.967001 96.420001)
		(mid 176.027483 96.566019)
		(end 176.173501 96.626501)
		(width 0.114)
		(layer "In5.Cu")
		(net 464)
	)
	(arc
		(start 178.973501 96.626501)
		(mid 179.119519 96.566019)
		(end 179.180001 96.420001)
		(width 0.114)
		(layer "In5.Cu")
		(net 464)
	)
	(arc
		(start 174.567001 96.420001)
		(mid 174.627483 96.566019)
		(end 174.773501 96.626501)
		(width 0.114)
		(layer "In5.Cu")
		(net 464)
	)
	(arc
		(start 173.167001 96.420001)
		(mid 173.227483 96.566019)
		(end 173.373501 96.626501)
		(width 0.114)
		(layer "In5.Cu")
		(net 464)
	)
	(arc
		(start 176.873501 95.609309)
		(mid 177.222458 95.753852)
		(end 177.367001 96.102809)
		(width 0.114)
		(layer "In5.Cu")
		(net 464)
	)
	(arc
		(start 172.673501 95.609309)
		(mid 173.022458 95.753852)
		(end 173.167001 96.102809)
		(width 0.114)
		(layer "In5.Cu")
		(net 464)
	)
	(arc
		(start 174.980001 96.102809)
		(mid 175.124544 95.753852)
		(end 175.473501 95.609309)
		(width 0.114)
		(layer "In5.Cu")
		(net 464)
	)
	(arc
		(start 173.373501 96.626501)
		(mid 173.519519 96.566019)
		(end 173.580001 96.420001)
		(width 0.114)
		(layer "In5.Cu")
		(net 464)
	)
	(arc
		(start 172.180001 96.102809)
		(mid 172.324544 95.753852)
		(end 172.673501 95.609309)
		(width 0.114)
		(layer "In5.Cu")
		(net 464)
	)
	(arc
		(start 175.473501 95.609309)
		(mid 175.822458 95.753852)
		(end 175.967001 96.102809)
		(width 0.114)
		(layer "In5.Cu")
		(net 464)
	)
	(arc
		(start 171.973501 96.626501)
		(mid 172.119519 96.566019)
		(end 172.180001 96.420001)
		(width 0.114)
		(layer "In5.Cu")
		(net 464)
	)
	(arc
		(start 179.673501 95.609309)
		(mid 180.022458 95.753852)
		(end 180.167001 96.102809)
		(width 0.114)
		(layer "In5.Cu")
		(net 464)
	)
	(arc
		(start 179.180001 96.102809)
		(mid 179.324544 95.753852)
		(end 179.673501 95.609309)
		(width 0.114)
		(layer "In5.Cu")
		(net 464)
	)
	(arc
		(start 177.367001 96.420001)
		(mid 177.427483 96.566019)
		(end 177.573501 96.626501)
		(width 0.114)
		(layer "In5.Cu")
		(net 464)
	)
	(arc
		(start 178.767001 96.420001)
		(mid 178.827483 96.566019)
		(end 178.973501 96.626501)
		(width 0.114)
		(layer "In5.Cu")
		(net 464)
	)
	(arc
		(start 177.573501 96.626501)
		(mid 177.719519 96.566019)
		(end 177.780001 96.420001)
		(width 0.114)
		(layer "In5.Cu")
		(net 464)
	)
	(arc
		(start 176.380001 96.102809)
		(mid 176.524544 95.753852)
		(end 176.873501 95.609309)
		(width 0.114)
		(layer "In5.Cu")
		(net 464)
	)
	(arc
		(start 177.780001 96.102809)
		(mid 177.924544 95.753852)
		(end 178.273501 95.609309)
		(width 0.114)
		(layer "In5.Cu")
		(net 464)
	)
	(arc
		(start 176.173501 96.626501)
		(mid 176.319519 96.566019)
		(end 176.380001 96.420001)
		(width 0.114)
		(layer "In5.Cu")
		(net 464)
	)
	(arc
		(start 174.073501 95.609309)
		(mid 174.422458 95.753852)
		(end 174.567001 96.102809)
		(width 0.114)
		(layer "In5.Cu")
		(net 464)
	)
	(arc
		(start 173.580001 96.102809)
		(mid 173.724544 95.753852)
		(end 174.073501 95.609309)
		(width 0.114)
		(layer "In5.Cu")
		(net 464)
	)
	(arc
		(start 174.773501 96.626501)
		(mid 174.919519 96.566019)
		(end 174.980001 96.420001)
		(width 0.114)
		(layer "In5.Cu")
		(net 464)
	)
	(segment
		(start 166.445001 100.285001)
		(end 166.948 100.788)
		(width 0.16)
		(layer "F.Cu")
		(net 468)
	)
	(segment
		(start 170.641001 100.719501)
		(end 171.475001 100.719501)
		(width 0.201)
		(layer "F.Cu")
		(net 468)
	)
	(segment
		(start 166.948 100.788)
		(end 170.572501 100.788001)
		(width 0.16)
		(layer "F.Cu")
		(net 468)
	)
	(segment
		(start 171.475001 100.719501)
		(end 171.599501 100.595)
		(width 0.201)
		(layer "F.Cu")
		(net 468)
	)
	(segment
		(start 170.572501 100.788001)
		(end 170.641001 100.719501)
		(width 0.16)
		(layer "F.Cu")
		(net 468)
	)
	(via
		(at 190.5 134.5)
		(size 0.45)
		(drill 0.2)
		(layers "F.Cu" "B.Cu")
		(net 468)
	)
	(via
		(at 171.599501 100.595)
		(size 0.45)
		(drill 0.2)
		(layers "F.Cu" "B.Cu")
		(net 468)
	)
	(segment
		(start 190.0994 134.137977)
		(end 189.861424 133.900001)
		(width 0.1)
		(layer "B.Cu")
		(net 468)
	)
	(segment
		(start 174.425501 102.726951)
		(end 174.425501 129.811951)
		(width 0.201)
		(layer "B.Cu")
		(net 468)
	)
	(segment
		(start 172.418051 100.719501)
		(end 174.425501 102.726951)
		(width 0.201)
		(layer "B.Cu")
		(net 468)
	)
	(segment
		(start 190.210001 134.500001)
		(end 190.099399 134.389399)
		(width 0.1)
		(layer "B.Cu")
		(net 468)
	)
	(segment
		(start 190.500001 134.500001)
		(end 190.210001 134.500001)
		(width 0.1)
		(layer "B.Cu")
		(net 468)
	)
	(segment
		(start 183.447376 133.900001)
		(end 183.346376 133.799001)
		(width 0.1)
		(layer "B.Cu")
		(net 468)
	)
	(segment
		(start 174.425501 129.811951)
		(end 178.412551 133.799001)
		(width 0.201)
		(layer "B.Cu")
		(net 468)
	)
	(segment
		(start 171.599501 100.595)
		(end 171.724002 100.719501)
		(width 0.201)
		(layer "B.Cu")
		(net 468)
	)
	(segment
		(start 190.099399 134.389399)
		(end 190.0994 134.137977)
		(width 0.1)
		(layer "B.Cu")
		(net 468)
	)
	(segment
		(start 171.724002 100.719501)
		(end 172.418051 100.719501)
		(width 0.201)
		(layer "B.Cu")
		(net 468)
	)
	(segment
		(start 178.412551 133.799001)
		(end 183.346376 133.799001)
		(width 0.201)
		(layer "B.Cu")
		(net 468)
	)
	(segment
		(start 189.861424 133.900001)
		(end 183.447376 133.900001)
		(width 0.1)
		(layer "B.Cu")
		(net 468)
	)
	(segment
		(start 213.5 136.5)
		(end 214 137)
		(width 0.256)
		(layer "F.Cu")
		(net 470)
	)
	(via
		(at 254.3 87.6)
		(size 0.45)
		(drill 0.2)
		(layers "F.Cu" "B.Cu")
		(net 470)
	)
	(via
		(at 214 137)
		(size 0.45)
		(drill 0.2)
		(layers "F.Cu" "B.Cu")
		(net 470)
	)
	(segment
		(start 254.3 87.6)
		(end 241.315 87.6)
		(width 0.1)
		(layer "B.Cu")
		(net 470)
	)
	(segment
		(start 241.315 87.6)
		(end 238.899999 85.184999)
		(width 0.1)
		(layer "B.Cu")
		(net 470)
	)
	(segment
		(start 233.499998 104.8)
		(end 230.7 107.599998)
		(width 0.1)
		(layer "In3.Cu")
		(net 470)
	)
	(segment
		(start 214.3 136.6)
		(end 214 136.9)
		(width 0.1)
		(layer "In3.Cu")
		(net 470)
	)
	(segment
		(start 221.638734 137)
		(end 216.3 137)
		(width 0.1)
		(layer "In3.Cu")
		(net 470)
	)
	(segment
		(start 254.9 89.2)
		(end 254.9 94.499998)
		(width 0.1)
		(layer "In3.Cu")
		(net 470)
	)
	(segment
		(start 216.3 137)
		(end 215.9 136.6)
		(width 0.1)
		(layer "In3.Cu")
		(net 470)
	)
	(segment
		(start 254.9 94.499998)
		(end 253.599998 95.8)
		(width 0.1)
		(layer "In3.Cu")
		(net 470)
	)
	(segment
		(start 254.3 87.6)
		(end 254.3 88.6)
		(width 0.1)
		(layer "In3.Cu")
		(net 470)
	)
	(segment
		(start 214 136.9)
		(end 214 137)
		(width 0.1)
		(layer "In3.Cu")
		(net 470)
	)
	(segment
		(start 253.3 95.8)
		(end 244.3 104.8)
		(width 0.1)
		(layer "In3.Cu")
		(net 470)
	)
	(segment
		(start 226.71421 136.8)
		(end 221.838733 136.8)
		(width 0.1)
		(layer "In3.Cu")
		(net 470)
	)
	(segment
		(start 230.7 107.599998)
		(end 230.7 132.81421)
		(width 0.1)
		(layer "In3.Cu")
		(net 470)
	)
	(segment
		(start 221.838733 136.8)
		(end 221.638734 137)
		(width 0.1)
		(layer "In3.Cu")
		(net 470)
	)
	(segment
		(start 253.599998 95.8)
		(end 253.3 95.8)
		(width 0.1)
		(layer "In3.Cu")
		(net 470)
	)
	(segment
		(start 254.3 88.6)
		(end 254.9 89.2)
		(width 0.1)
		(layer "In3.Cu")
		(net 470)
	)
	(segment
		(start 215.9 136.6)
		(end 214.3 136.6)
		(width 0.1)
		(layer "In3.Cu")
		(net 470)
	)
	(segment
		(start 244.3 104.8)
		(end 233.499998 104.8)
		(width 0.1)
		(layer "In3.Cu")
		(net 470)
	)
	(segment
		(start 230.7 132.81421)
		(end 226.71421 136.8)
		(width 0.1)
		(layer "In3.Cu")
		(net 470)
	)
	(segment
		(start 214.015281 137.975)
		(end 213.975 137.975)
		(width 0.256)
		(layer "F.Cu")
		(net 471)
	)
	(segment
		(start 213.975 137.975)
		(end 213.5 137.5)
		(width 0.256)
		(layer "F.Cu")
		(net 471)
	)
	(via
		(at 214.015281 137.975)
		(size 0.45)
		(drill 0.2)
		(layers "F.Cu" "B.Cu")
		(net 471)
	)
	(via
		(at 254.9 85.9)
		(size 0.45)
		(drill 0.2)
		(layers "F.Cu" "B.Cu")
		(net 471)
	)
	(segment
		(start 243.315 87)
		(end 241.499999 85.184999)
		(width 0.1)
		(layer "B.Cu")
		(net 471)
	)
	(segment
		(start 254.9 85.9)
		(end 253.3 85.9)
		(width 0.1)
		(layer "B.Cu")
		(net 471)
	)
	(segment
		(start 253.3 85.9)
		(end 252.2 87)
		(width 0.1)
		(layer "B.Cu")
		(net 471)
	)
	(segment
		(start 252.2 87)
		(end 243.315 87)
		(width 0.1)
		(layer "B.Cu")
		(net 471)
	)
	(segment
		(start 214.3 137.6)
		(end 221.887261 137.6)
		(width 0.1)
		(layer "In3.Cu")
		(net 471)
	)
	(segment
		(start 254.9 87.2)
		(end 254.9 85.9)
		(width 0.1)
		(layer "In3.Cu")
		(net 471)
	)
	(segment
		(start 214.015281 137.975)
		(end 214.015281 137.884719)
		(width 0.1)
		(layer "In3.Cu")
		(net 471)
	)
	(segment
		(start 255.5 95.099998)
		(end 255.5 87.8)
		(width 0.1)
		(layer "In3.Cu")
		(net 471)
	)
	(segment
		(start 226.965684 137.4)
		(end 231.6 132.765684)
		(width 0.1)
		(layer "In3.Cu")
		(net 471)
	)
	(segment
		(start 233.799998 105.7)
		(end 244.6 105.7)
		(width 0.1)
		(layer "In3.Cu")
		(net 471)
	)
	(segment
		(start 253.899998 96.7)
		(end 255.5 95.099998)
		(width 0.1)
		(layer "In3.Cu")
		(net 471)
	)
	(segment
		(start 231.6 107.899998)
		(end 233.799998 105.7)
		(width 0.1)
		(layer "In3.Cu")
		(net 471)
	)
	(segment
		(start 253.6 96.7)
		(end 253.899998 96.7)
		(width 0.1)
		(layer "In3.Cu")
		(net 471)
	)
	(segment
		(start 222.087261 137.4)
		(end 226.965684 137.4)
		(width 0.1)
		(layer "In3.Cu")
		(net 471)
	)
	(segment
		(start 244.6 105.7)
		(end 253.6 96.7)
		(width 0.1)
		(layer "In3.Cu")
		(net 471)
	)
	(segment
		(start 214.015281 137.884719)
		(end 214.3 137.6)
		(width 0.1)
		(layer "In3.Cu")
		(net 471)
	)
	(segment
		(start 231.6 132.765684)
		(end 231.6 107.899998)
		(width 0.1)
		(layer "In3.Cu")
		(net 471)
	)
	(segment
		(start 255.5 87.8)
		(end 254.9 87.2)
		(width 0.1)
		(layer "In3.Cu")
		(net 471)
	)
	(segment
		(start 221.887261 137.6)
		(end 222.087261 137.4)
		(width 0.1)
		(layer "In3.Cu")
		(net 471)
	)
	(segment
		(start 212.5 133.5)
		(end 213 134)
		(width 0.256)
		(layer "F.Cu")
		(net 472)
	)
	(via
		(at 213 134)
		(size 0.45)
		(drill 0.2)
		(layers "F.Cu" "B.Cu")
		(net 472)
	)
	(via
		(at 252.8 83.44)
		(size 0.45)
		(drill 0.2)
		(layers "F.Cu" "B.Cu")
		(net 472)
	)
	(segment
		(start 252.8 83.44)
		(end 249.84 86.4)
		(width 0.1)
		(layer "B.Cu")
		(net 472)
	)
	(segment
		(start 245.315 86.4)
		(end 244.099999 85.184999)
		(width 0.1)
		(layer "B.Cu")
		(net 472)
	)
	(segment
		(start 249.84 86.4)
		(end 245.315 86.4)
		(width 0.1)
		(layer "B.Cu")
		(net 472)
	)
	(segment
		(start 232.6 102.1)
		(end 228 106.7)
		(width 0.1)
		(layer "In3.Cu")
		(net 472)
	)
	(segment
		(start 251.8 85.617677)
		(end 251.8 93.25)
		(width 0.1)
		(layer "In3.Cu")
		(net 472)
	)
	(segment
		(start 242.95 102.1)
		(end 232.6 102.1)
		(width 0.1)
		(layer "In3.Cu")
		(net 472)
	)
	(segment
		(start 213.575 133.425)
		(end 213 134)
		(width 0.1)
		(layer "In3.Cu")
		(net 472)
	)
	(segment
		(start 220.834316 134.65)
		(end 220.584316 134.4)
		(width 0.1)
		(layer "In3.Cu")
		(net 472)
	)
	(segment
		(start 252.8 83.44)
		(end 252.8 84.617677)
		(width 0.1)
		(layer "In3.Cu")
		(net 472)
	)
	(segment
		(start 220.584316 134.4)
		(end 216.4 134.4)
		(width 0.1)
		(layer "In3.Cu")
		(net 472)
	)
	(segment
		(start 252.8 84.617677)
		(end 251.8 85.617677)
		(width 0.1)
		(layer "In3.Cu")
		(net 472)
	)
	(segment
		(start 251.8 93.25)
		(end 242.95 102.1)
		(width 0.1)
		(layer "In3.Cu")
		(net 472)
	)
	(segment
		(start 215.425 133.425)
		(end 213.575 133.425)
		(width 0.1)
		(layer "In3.Cu")
		(net 472)
	)
	(segment
		(start 228 106.7)
		(end 228 132.9)
		(width 0.1)
		(layer "In3.Cu")
		(net 472)
	)
	(segment
		(start 226.25 134.65)
		(end 220.834316 134.65)
		(width 0.1)
		(layer "In3.Cu")
		(net 472)
	)
	(segment
		(start 216.4 134.4)
		(end 215.425 133.425)
		(width 0.1)
		(layer "In3.Cu")
		(net 472)
	)
	(segment
		(start 228 132.9)
		(end 226.25 134.65)
		(width 0.1)
		(layer "In3.Cu")
		(net 472)
	)
	(segment
		(start 171.475001 98.580501)
		(end 170.572501 98.580501)
		(width 0.201)
		(layer "F.Cu")
		(net 473)
	)
	(segment
		(start 171.599501 98.705001)
		(end 171.475001 98.580501)
		(width 0.201)
		(layer "F.Cu")
		(net 473)
	)
	(segment
		(start 167.715001 99.015001)
		(end 168.218 98.512002)
		(width 0.16)
		(layer "F.Cu")
		(net 473)
	)
	(segment
		(start 170.504001 98.512001)
		(end 170.572501 98.580501)
		(width 0.16)
		(layer "F.Cu")
		(net 473)
	)
	(segment
		(start 170.504001 98.512001)
		(end 168.218 98.512002)
		(width 0.16)
		(layer "F.Cu")
		(net 473)
	)
	(via
		(at 189.5 132.5)
		(size 0.45)
		(drill 0.2)
		(layers "F.Cu" "B.Cu")
		(net 473)
	)
	(via
		(at 171.599501 98.705001)
		(size 0.45)
		(drill 0.2)
		(layers "F.Cu" "B.Cu")
		(net 473)
	)
	(segment
		(start 183.446376 132.100001)
		(end 183.346376 132.200001)
		(width 0.1)
		(layer "B.Cu")
		(net 473)
	)
	(segment
		(start 178.156451 132.200001)
		(end 183.346376 132.200001)
		(width 0.201)
		(layer "B.Cu")
		(net 473)
	)
	(segment
		(start 189.8994 132.430604)
		(end 189.8994 132.220821)
		(width 0.1)
		(layer "B.Cu")
		(net 473)
	)
	(segment
		(start 171.599501 98.705001)
		(end 171.724002 98.580501)
		(width 0.201)
		(layer "B.Cu")
		(net 473)
	)
	(segment
		(start 189.830002 132.500001)
		(end 189.8994 132.430604)
		(width 0.1)
		(layer "B.Cu")
		(net 473)
	)
	(segment
		(start 188.852 132.322233)
		(end 188.852 132.225002)
		(width 0.1)
		(layer "B.Cu")
		(net 473)
	)
	(segment
		(start 175.319501 99.733051)
		(end 175.319501 129.363051)
		(width 0.201)
		(layer "B.Cu")
		(net 473)
	)
	(segment
		(start 188.677 132.100002)
		(end 183.446376 132.100001)
		(width 0.1)
		(layer "B.Cu")
		(net 473)
	)
	(segment
		(start 174.166951 98.580501)
		(end 175.319501 99.733051)
		(width 0.201)
		(layer "B.Cu")
		(net 473)
	)
	(segment
		(start 189.500001 132.500001)
		(end 189.830002 132.500001)
		(width 0.1)
		(layer "B.Cu")
		(net 473)
	)
	(segment
		(start 171.724002 98.580501)
		(end 174.166951 98.580501)
		(width 0.201)
		(layer "B.Cu")
		(net 473)
	)
	(segment
		(start 188.727 132.100002)
		(end 188.677 132.100002)
		(width 0.1)
		(layer "B.Cu")
		(net 473)
	)
	(segment
		(start 189.102 132.225002)
		(end 189.102 132.322233)
		(width 0.1)
		(layer "B.Cu")
		(net 473)
	)
	(segment
		(start 175.319501 129.363051)
		(end 178.156451 132.200001)
		(width 0.201)
		(layer "B.Cu")
		(net 473)
	)
	(segment
		(start 189.77858 132.100002)
		(end 189.227 132.100002)
		(width 0.1)
		(layer "B.Cu")
		(net 473)
	)
	(segment
		(start 189.8994 132.220821)
		(end 189.77858 132.100002)
		(width 0.1)
		(layer "B.Cu")
		(net 473)
	)
	(arc
		(start 188.977 132.447233)
		(mid 188.888612 132.410621)
		(end 188.852 132.322233)
		(width 0.1)
		(layer "B.Cu")
		(net 473)
	)
	(arc
		(start 189.102 132.322233)
		(mid 189.065388 132.410621)
		(end 188.977 132.447233)
		(width 0.1)
		(layer "B.Cu")
		(net 473)
	)
	(arc
		(start 188.852 132.225002)
		(mid 188.815388 132.136614)
		(end 188.727 132.100002)
		(width 0.1)
		(layer "B.Cu")
		(net 473)
	)
	(arc
		(start 189.227 132.100002)
		(mid 189.138612 132.136614)
		(end 189.102 132.225002)
		(width 0.1)
		(layer "B.Cu")
		(net 473)
	)
	(segment
		(start 204.5 139.5)
		(end 205 140)
		(width 0.256)
		(layer "F.Cu")
		(net 474)
	)
	(via
		(at 205 140)
		(size 0.45)
		(drill 0.2)
		(layers "F.Cu" "B.Cu")
		(net 474)
	)
	(via
		(at 182.625501 84.300001)
		(size 0.45)
		(drill 0.2)
		(layers "F.Cu" "B.Cu")
		(net 474)
	)
	(segment
		(start 182.625501 84.300001)
		(end 186.785001 84.300001)
		(width 0.1)
		(layer "B.Cu")
		(net 474)
	)
	(segment
		(start 186.785001 84.300001)
		(end 186.800001 84.315001)
		(width 0.1)
		(layer "B.Cu")
		(net 474)
	)
	(segment
		(start 183.400001 139.600001)
		(end 182.000001 138.200001)
		(width 0.1)
		(layer "In3.Cu")
		(net 474)
	)
	(segment
		(start 182.625501 84.300001)
		(end 182.000001 84.925501)
		(width 0.1)
		(layer "In3.Cu")
		(net 474)
	)
	(segment
		(start 204.600001 139.600001)
		(end 183.400001 139.600001)
		(width 0.1)
		(layer "In3.Cu")
		(net 474)
	)
	(segment
		(start 205.000001 140.000001)
		(end 204.600001 139.600001)
		(width 0.1)
		(layer "In3.Cu")
		(net 474)
	)
	(segment
		(start 182.000001 84.925501)
		(end 182.000001 138.200001)
		(width 0.1)
		(layer "In3.Cu")
		(net 474)
	)
	(segment
		(start 205.5 140.5)
		(end 206 141)
		(width 0.256)
		(layer "F.Cu")
		(net 475)
	)
	(via
		(at 206 141)
		(size 0.45)
		(drill 0.2)
		(layers "F.Cu" "B.Cu")
		(net 475)
	)
	(via
		(at 182.600001 83.700001)
		(size 0.45)
		(drill 0.2)
		(layers "F.Cu" "B.Cu")
		(net 475)
	)
	(segment
		(start 187.900001 83.700001)
		(end 188.100001 83.900001)
		(width 0.1)
		(layer "B.Cu")
		(net 475)
	)
	(segment
		(start 188.100001 83.900001)
		(end 188.100001 84.315001)
		(width 0.1)
		(layer "B.Cu")
		(net 475)
	)
	(segment
		(start 182.600001 83.700001)
		(end 187.900001 83.700001)
		(width 0.1)
		(layer "B.Cu")
		(net 475)
	)
	(segment
		(start 205.000001 140.400001)
		(end 205.600001 141.000001)
		(width 0.1)
		(layer "In3.Cu")
		(net 475)
	)
	(segment
		(start 181.800001 84.500001)
		(end 181.800001 138.300001)
		(width 0.1)
		(layer "In3.Cu")
		(net 475)
	)
	(segment
		(start 182.600001 83.700001)
		(end 181.800001 84.500001)
		(width 0.1)
		(layer "In3.Cu")
		(net 475)
	)
	(segment
		(start 181.800001 138.300001)
		(end 183.900001 140.400001)
		(width 0.1)
		(layer "In3.Cu")
		(net 475)
	)
	(segment
		(start 183.900001 140.400001)
		(end 205.000001 140.400001)
		(width 0.1)
		(layer "In3.Cu")
		(net 475)
	)
	(segment
		(start 205.600001 141.000001)
		(end 206.000001 141.000001)
		(width 0.1)
		(layer "In3.Cu")
		(net 475)
	)
	(segment
		(start 205.5 144.5)
		(end 205.999967 144.999967)
		(width 0.256)
		(layer "F.Cu")
		(net 476)
	)
	(segment
		(start 205.999967 144.999967)
		(end 205.999967 145.012279)
		(width 0.256)
		(layer "F.Cu")
		(net 476)
	)
	(via
		(at 180.414813 83.314813)
		(size 0.45)
		(drill 0.2)
		(layers "F.Cu" "B.Cu")
		(net 476)
	)
	(via
		(at 205.999967 145.012279)
		(size 0.45)
		(drill 0.2)
		(layers "F.Cu" "B.Cu")
		(net 476)
	)
	(segment
		(start 180.414813 83.314813)
		(end 188.814813 83.314813)
		(width 0.1)
		(layer "B.Cu")
		(net 476)
	)
	(segment
		(start 189.36 83.86)
		(end 188.814813 83.314813)
		(width 0.1)
		(layer "B.Cu")
		(net 476)
	)
	(segment
		(start 189.36 84.315)
		(end 189.36 83.86)
		(width 0.1)
		(layer "B.Cu")
		(net 476)
	)
	(segment
		(start 182.800001 141.682843)
		(end 182.800001 144.000001)
		(width 0.1)
		(layer "In3.Cu")
		(net 476)
	)
	(segment
		(start 205.400001 144.400001)
		(end 206.000001 145.000001)
		(width 0.1)
		(layer "In3.Cu")
		(net 476)
	)
	(segment
		(start 180.414813 83.314813)
		(end 180.200001 83.529625)
		(width 0.1)
		(layer "In3.Cu")
		(net 476)
	)
	(segment
		(start 182.800001 144.000001)
		(end 183.200001 144.400001)
		(width 0.1)
		(layer "In3.Cu")
		(net 476)
	)
	(segment
		(start 180.200001 139.082843)
		(end 182.800001 141.682843)
		(width 0.1)
		(layer "In3.Cu")
		(net 476)
	)
	(segment
		(start 180.200001 83.529625)
		(end 180.200001 139.082843)
		(width 0.1)
		(layer "In3.Cu")
		(net 476)
	)
	(segment
		(start 183.200001 144.400001)
		(end 205.400001 144.400001)
		(width 0.1)
		(layer "In3.Cu")
		(net 476)
	)
	(segment
		(start 204.5 144.5)
		(end 205 145)
		(width 0.256)
		(layer "F.Cu")
		(net 477)
	)
	(via
		(at 205 145)
		(size 0.45)
		(drill 0.2)
		(layers "F.Cu" "B.Cu")
		(net 477)
	)
	(via
		(at 180.400001 82.700001)
		(size 0.45)
		(drill 0.2)
		(layers "F.Cu" "B.Cu")
		(net 477)
	)
	(segment
		(start 190.600001 84.315001)
		(end 190.600001 83.900001)
		(width 0.1)
		(layer "B.Cu")
		(net 477)
	)
	(segment
		(start 180.700001 83.000001)
		(end 180.400001 82.700001)
		(width 0.1)
		(layer "B.Cu")
		(net 477)
	)
	(segment
		(start 189.700001 83.000001)
		(end 180.700001 83.000001)
		(width 0.1)
		(layer "B.Cu")
		(net 477)
	)
	(segment
		(start 190.600001 83.900001)
		(end 189.700001 83.000001)
		(width 0.1)
		(layer "B.Cu")
		(net 477)
	)
	(segment
		(start 204.600001 144.600001)
		(end 205.000001 145.000001)
		(width 0.1)
		(layer "In3.Cu")
		(net 477)
	)
	(segment
		(start 180.400001 82.700001)
		(end 180.000001 83.100001)
		(width 0.1)
		(layer "In3.Cu")
		(net 477)
	)
	(segment
		(start 182.600001 141.800001)
		(end 182.600001 144.200001)
		(width 0.1)
		(layer "In3.Cu")
		(net 477)
	)
	(segment
		(start 182.600001 144.200001)
		(end 183.000001 144.600001)
		(width 0.1)
		(layer "In3.Cu")
		(net 477)
	)
	(segment
		(start 180.000001 83.100001)
		(end 180.000001 139.200001)
		(width 0.1)
		(layer "In3.Cu")
		(net 477)
	)
	(segment
		(start 183.000001 144.600001)
		(end 204.600001 144.600001)
		(width 0.1)
		(layer "In3.Cu")
		(net 477)
	)
	(segment
		(start 180.000001 139.200001)
		(end 182.600001 141.800001)
		(width 0.1)
		(layer "In3.Cu")
		(net 477)
	)
	(segment
		(start 170.572501 106.132001)
		(end 170.641001 106.200501)
		(width 0.16)
		(layer "F.Cu")
		(net 478)
	)
	(segment
		(start 166.445001 106.635001)
		(end 166.948 106.132002)
		(width 0.16)
		(layer "F.Cu")
		(net 478)
	)
	(segment
		(start 173.085001 106.476251)
		(end 172.809251 106.200501)
		(width 0.201)
		(layer "F.Cu")
		(net 478)
	)
	(segment
		(start 166.948 106.132002)
		(end 170.572501 106.132001)
		(width 0.16)
		(layer "F.Cu")
		(net 478)
	)
	(segment
		(start 172.809251 106.200501)
		(end 170.641001 106.200501)
		(width 0.201)
		(layer "F.Cu")
		(net 478)
	)
	(segment
		(start 171.599501 98.055)
		(end 171.475 98.179501)
		(width 0.201)
		(layer "F.Cu")
		(net 479)
	)
	(segment
		(start 171.475 98.179501)
		(end 170.572501 98.179501)
		(width 0.201)
		(layer "F.Cu")
		(net 479)
	)
	(segment
		(start 170.504001 98.248001)
		(end 170.572501 98.179501)
		(width 0.16)
		(layer "F.Cu")
		(net 479)
	)
	(segment
		(start 170.504001 98.248001)
		(end 168.218 98.248)
		(width 0.16)
		(layer "F.Cu")
		(net 479)
	)
	(segment
		(start 167.715001 97.745001)
		(end 168.218 98.248)
		(width 0.16)
		(layer "F.Cu")
		(net 479)
	)
	(via
		(at 190.5 132.5)
		(size 0.45)
		(drill 0.2)
		(layers "F.Cu" "B.Cu")
		(net 479)
	)
	(via
		(at 171.599501 98.055)
		(size 0.45)
		(drill 0.2)
		(layers "F.Cu" "B.Cu")
		(net 479)
	)
	(segment
		(start 171.724002 98.179501)
		(end 174.333051 98.179501)
		(width 0.201)
		(layer "B.Cu")
		(net 479)
	)
	(segment
		(start 190.0994 132.137977)
		(end 189.861424 131.900001)
		(width 0.1)
		(layer "B.Cu")
		(net 479)
	)
	(segment
		(start 175.720501 129.196951)
		(end 178.322551 131.799001)
		(width 0.201)
		(layer "B.Cu")
		(net 479)
	)
	(segment
		(start 190.099399 132.389399)
		(end 190.0994 132.137977)
		(width 0.1)
		(layer "B.Cu")
		(net 479)
	)
	(segment
		(start 183.447376 131.900001)
		(end 183.346376 131.799001)
		(width 0.1)
		(layer "B.Cu")
		(net 479)
	)
	(segment
		(start 190.210001 132.500001)
		(end 190.099399 132.389399)
		(width 0.1)
		(layer "B.Cu")
		(net 479)
	)
	(segment
		(start 174.333051 98.179501)
		(end 175.720501 99.566951)
		(width 0.201)
		(layer "B.Cu")
		(net 479)
	)
	(segment
		(start 171.599501 98.055)
		(end 171.724002 98.179501)
		(width 0.201)
		(layer "B.Cu")
		(net 479)
	)
	(segment
		(start 175.720501 99.566951)
		(end 175.720501 129.196951)
		(width 0.201)
		(layer "B.Cu")
		(net 479)
	)
	(segment
		(start 178.322551 131.799001)
		(end 183.346376 131.799001)
		(width 0.201)
		(layer "B.Cu")
		(net 479)
	)
	(segment
		(start 190.500001 132.500001)
		(end 190.210001 132.500001)
		(width 0.1)
		(layer "B.Cu")
		(net 479)
	)
	(segment
		(start 189.861424 131.900001)
		(end 183.447376 131.900001)
		(width 0.1)
		(layer "B.Cu")
		(net 479)
	)
	(segment
		(start 204.97 140.97)
		(end 205 140.97)
		(width 0.256)
		(layer "F.Cu")
		(net 480)
	)
	(segment
		(start 204.5 140.5)
		(end 204.97 140.97)
		(width 0.256)
		(layer "F.Cu")
		(net 480)
	)
	(via
		(at 205 140.97)
		(size 0.45)
		(drill 0.2)
		(layers "F.Cu" "B.Cu")
		(net 480)
	)
	(via
		(at 182.625501 82.625501)
		(size 0.45)
		(drill 0.2)
		(layers "F.Cu" "B.Cu")
		(net 480)
	)
	(segment
		(start 182.625501 82.625501)
		(end 190.625501 82.625501)
		(width 0.1)
		(layer "B.Cu")
		(net 480)
	)
	(segment
		(start 191.900001 83.900001)
		(end 191.900001 84.315001)
		(width 0.1)
		(layer "B.Cu")
		(net 480)
	)
	(segment
		(start 190.625501 82.625501)
		(end 191.900001 83.900001)
		(width 0.1)
		(layer "B.Cu")
		(net 480)
	)
	(segment
		(start 182.625501 82.625501)
		(end 181.989813 83.261189)
		(width 0.1)
		(layer "In3.Cu")
		(net 480)
	)
	(segment
		(start 181.600001 84.357008)
		(end 181.600001 138.400001)
		(width 0.1)
		(layer "In3.Cu")
		(net 480)
	)
	(segment
		(start 183.800001 140.600001)
		(end 204.600001 140.600001)
		(width 0.1)
		(layer "In3.Cu")
		(net 480)
	)
	(segment
		(start 181.989813 83.261189)
		(end 181.989813 83.967196)
		(width 0.1)
		(layer "In3.Cu")
		(net 480)
	)
	(segment
		(start 204.600001 140.600001)
		(end 205.000001 141.000001)
		(width 0.1)
		(layer "In3.Cu")
		(net 480)
	)
	(segment
		(start 181.989813 83.967196)
		(end 181.600001 84.357008)
		(width 0.1)
		(layer "In3.Cu")
		(net 480)
	)
	(segment
		(start 181.600001 138.400001)
		(end 183.800001 140.600001)
		(width 0.1)
		(layer "In3.Cu")
		(net 480)
	)
	(segment
		(start 166.935002 95.972003)
		(end 166.766804 95.972003)
		(width 0.16)
		(layer "F.Cu")
		(net 483)
	)
	(segment
		(start 187.83 135.500001)
		(end 187.899398 135.430602)
		(width 0.1)
		(layer "F.Cu")
		(net 483)
	)
	(segment
		(start 166.445001 96.293804)
		(end 166.445001 96.475002)
		(width 0.16)
		(layer "F.Cu")
		(net 483)
	)
	(segment
		(start 166.935002 95.972003)
		(end 167.080001 96.117002)
		(width 0.16)
		(layer "F.Cu")
		(net 483)
	)
	(segment
		(start 187.111 135.225)
		(end 187.111 135.272149)
		(width 0.1)
		(layer "F.Cu")
		(net 483)
	)
	(segment
		(start 187.899398 135.430602)
		(end 187.899398 135.22082)
		(width 0.1)
		(layer "F.Cu")
		(net 483)
	)
	(segment
		(start 171.399501 133.303051)
		(end 173.296451 135.200001)
		(width 0.201)
		(layer "F.Cu")
		(net 483)
	)
	(segment
		(start 187.5 135.5)
		(end 187.83 135.500001)
		(width 0.1)
		(layer "F.Cu")
		(net 483)
	)
	(segment
		(start 187.899398 135.22082)
		(end 187.778578 135.1)
		(width 0.1)
		(layer "F.Cu")
		(net 483)
	)
	(segment
		(start 186.861 135.272149)
		(end 186.861 135.225)
		(width 0.1)
		(layer "F.Cu")
		(net 483)
	)
	(segment
		(start 186.686 135.1)
		(end 183.446375 135.1)
		(width 0.1)
		(layer "F.Cu")
		(net 483)
	)
	(segment
		(start 187.778578 135.1)
		(end 187.236 135.1)
		(width 0.1)
		(layer "F.Cu")
		(net 483)
	)
	(segment
		(start 171.275001 132.123977)
		(end 171.399501 132.248477)
		(width 0.201)
		(layer "F.Cu")
		(net 483)
	)
	(segment
		(start 171.399501 132.248477)
		(end 171.399501 133.303051)
		(width 0.201)
		(layer "F.Cu")
		(net 483)
	)
	(segment
		(start 166.766804 95.972003)
		(end 166.445001 96.293804)
		(width 0.16)
		(layer "F.Cu")
		(net 483)
	)
	(segment
		(start 186.736 135.1)
		(end 186.686 135.1)
		(width 0.1)
		(layer "F.Cu")
		(net 483)
	)
	(segment
		(start 173.296451 135.200001)
		(end 183.375001 135.200001)
		(width 0.201)
		(layer "F.Cu")
		(net 483)
	)
	(segment
		(start 183.446375 135.1)
		(end 183.346375 135.2)
		(width 0.1)
		(layer "F.Cu")
		(net 483)
	)
	(via
		(at 167.080001 96.117002)
		(size 0.45)
		(drill 0.2)
		(layers "F.Cu" "B.Cu")
		(net 483)
	)
	(via
		(at 171.275001 132.123977)
		(size 0.45)
		(drill 0.2)
		(layers "F.Cu" "B.Cu")
		(net 483)
	)
	(arc
		(start 187.236 135.1)
		(mid 187.147612 135.136612)
		(end 187.111 135.225)
		(width 0.1)
		(layer "F.Cu")
		(net 483)
	)
	(arc
		(start 186.986 135.397149)
		(mid 186.897612 135.360537)
		(end 186.861 135.272149)
		(width 0.1)
		(layer "F.Cu")
		(net 483)
	)
	(arc
		(start 187.111 135.272149)
		(mid 187.074388 135.360537)
		(end 186.986 135.397149)
		(width 0.1)
		(layer "F.Cu")
		(net 483)
	)
	(arc
		(start 186.861 135.225)
		(mid 186.824388 135.136612)
		(end 186.736 135.1)
		(width 0.1)
		(layer "F.Cu")
		(net 483)
	)
	(segment
		(start 171.399501 131.999477)
		(end 171.399501 125.863051)
		(width 0.201)
		(layer "B.Cu")
		(net 483)
	)
	(segment
		(start 168.271445 96.040502)
		(end 167.156501 96.040502)
		(width 0.201)
		(layer "B.Cu")
		(net 483)
	)
	(segment
		(start 167.156501 96.040502)
		(end 167.080001 96.117002)
		(width 0.201)
		(layer "B.Cu")
		(net 483)
	)
	(segment
		(start 168.784501 123.248051)
		(end 168.784501 96.553558)
		(width 0.201)
		(layer "B.Cu")
		(net 483)
	)
	(segment
		(start 168.784501 96.553558)
		(end 168.271445 96.040502)
		(width 0.201)
		(layer "B.Cu")
		(net 483)
	)
	(segment
		(start 171.399501 125.863051)
		(end 168.784501 123.248051)
		(width 0.201)
		(layer "B.Cu")
		(net 483)
	)
	(segment
		(start 171.275001 132.123977)
		(end 171.399501 131.999477)
		(width 0.201)
		(layer "B.Cu")
		(net 483)
	)
	(segment
		(start 205.014987 142.014987)
		(end 204.5 141.5)
		(width 0.256)
		(layer "F.Cu")
		(net 485)
	)
	(segment
		(start 205.014987 142.025889)
		(end 205.014987 142.014987)
		(width 0.256)
		(layer "F.Cu")
		(net 485)
	)
	(via
		(at 205.014987 142.025889)
		(size 0.45)
		(drill 0.2)
		(layers "F.Cu" "B.Cu")
		(net 485)
	)
	(via
		(at 181.577847 82.577847)
		(size 0.45)
		(drill 0.2)
		(layers "F.Cu" "B.Cu")
		(net 485)
	)
	(segment
		(start 193.100001 83.900001)
		(end 193.100001 84.315001)
		(width 0.1)
		(layer "B.Cu")
		(net 485)
	)
	(segment
		(start 191.400001 82.200001)
		(end 193.100001 83.900001)
		(width 0.1)
		(layer "B.Cu")
		(net 485)
	)
	(segment
		(start 181.955693 82.200001)
		(end 191.400001 82.200001)
		(width 0.1)
		(layer "B.Cu")
		(net 485)
	)
	(segment
		(start 181.577847 82.577847)
		(end 181.955693 82.200001)
		(width 0.1)
		(layer "B.Cu")
		(net 485)
	)
	(segment
		(start 204.600001 142.400001)
		(end 205.000001 142.000001)
		(width 0.1)
		(layer "In3.Cu")
		(net 485)
	)
	(segment
		(start 184.700001 142.400001)
		(end 204.600001 142.400001)
		(width 0.1)
		(layer "In3.Cu")
		(net 485)
	)
	(segment
		(start 181.389813 82.765881)
		(end 181.389813 83.71867)
		(width 0.1)
		(layer "In3.Cu")
		(net 485)
	)
	(segment
		(start 181.000001 138.700001)
		(end 184.700001 142.400001)
		(width 0.1)
		(layer "In3.Cu")
		(net 485)
	)
	(segment
		(start 181.000001 84.108482)
		(end 181.000001 138.700001)
		(width 0.1)
		(layer "In3.Cu")
		(net 485)
	)
	(segment
		(start 181.389813 83.71867)
		(end 181.000001 84.108482)
		(width 0.1)
		(layer "In3.Cu")
		(net 485)
	)
	(segment
		(start 181.577847 82.577847)
		(end 181.389813 82.765881)
		(width 0.1)
		(layer "In3.Cu")
		(net 485)
	)
	(segment
		(start 183.446375 134.9)
		(end 183.345375 134.799)
		(width 0.1)
		(layer "F.Cu")
		(net 486)
	)
	(segment
		(start 188.21 135.5)
		(end 188.099398 135.389398)
		(width 0.1)
		(layer "F.Cu")
		(net 486)
	)
	(segment
		(start 171.800501 133.136951)
		(end 173.462551 134.799001)
		(width 0.201)
		(layer "F.Cu")
		(net 486)
	)
	(segment
		(start 188.099398 135.137976)
		(end 187.861422 134.9)
		(width 0.1)
		(layer "F.Cu")
		(net 486)
	)
	(segment
		(start 173.462551 134.799001)
		(end 183.374001 134.799001)
		(width 0.201)
		(layer "F.Cu")
		(net 486)
	)
	(segment
		(start 187.861422 134.9)
		(end 183.446375 134.9)
		(width 0.1)
		(layer "F.Cu")
		(net 486)
	)
	(segment
		(start 166.935002 95.708)
		(end 167.080001 95.563002)
		(width 0.16)
		(layer "F.Cu")
		(net 486)
	)
	(segment
		(start 171.800501 132.248477)
		(end 171.800501 133.136951)
		(width 0.201)
		(layer "F.Cu")
		(net 486)
	)
	(segment
		(start 188.5 135.5)
		(end 188.21 135.5)
		(width 0.1)
		(layer "F.Cu")
		(net 486)
	)
	(segment
		(start 166.445001 95.205001)
		(end 166.445001 95.386199)
		(width 0.16)
		(layer "F.Cu")
		(net 486)
	)
	(segment
		(start 166.935002 95.708)
		(end 166.766805 95.708002)
		(width 0.16)
		(layer "F.Cu")
		(net 486)
	)
	(segment
		(start 166.445001 95.386199)
		(end 166.766805 95.708002)
		(width 0.16)
		(layer "F.Cu")
		(net 486)
	)
	(segment
		(start 188.099398 135.389398)
		(end 188.099398 135.137976)
		(width 0.1)
		(layer "F.Cu")
		(net 486)
	)
	(segment
		(start 171.925001 132.123977)
		(end 171.800501 132.248477)
		(width 0.201)
		(layer "F.Cu")
		(net 486)
	)
	(via
		(at 171.925001 132.123977)
		(size 0.45)
		(drill 0.2)
		(layers "F.Cu" "B.Cu")
		(net 486)
	)
	(via
		(at 167.080001 95.563002)
		(size 0.45)
		(drill 0.2)
		(layers "F.Cu" "B.Cu")
		(net 486)
	)
	(segment
		(start 169.185501 96.387458)
		(end 168.437545 95.639502)
		(width 0.201)
		(layer "B.Cu")
		(net 486)
	)
	(segment
		(start 169.185501 123.081951)
		(end 169.185501 96.387458)
		(width 0.201)
		(layer "B.Cu")
		(net 486)
	)
	(segment
		(start 167.156501 95.639502)
		(end 167.080001 95.563002)
		(width 0.201)
		(layer "B.Cu")
		(net 486)
	)
	(segment
		(start 171.800501 125.696951)
		(end 169.185501 123.081951)
		(width 0.201)
		(layer "B.Cu")
		(net 486)
	)
	(segment
		(start 171.925001 132.123977)
		(end 171.800501 131.999477)
		(width 0.201)
		(layer "B.Cu")
		(net 486)
	)
	(segment
		(start 168.437545 95.639502)
		(end 167.156501 95.639502)
		(width 0.201)
		(layer "B.Cu")
		(net 486)
	)
	(segment
		(start 171.800501 131.999477)
		(end 171.800501 125.696951)
		(width 0.201)
		(layer "B.Cu")
		(net 486)
	)
	(segment
		(start 209.5 141.5)
		(end 210 142)
		(width 0.256)
		(layer "F.Cu")
		(net 487)
	)
	(via
		(at 182.800001 79.600001)
		(size 0.45)
		(drill 0.2)
		(layers "F.Cu" "B.Cu")
		(net 487)
	)
	(via
		(at 210 142)
		(size 0.45)
		(drill 0.2)
		(layers "F.Cu" "B.Cu")
		(net 487)
	)
	(via
		(at 204 145)
		(size 0.45)
		(drill 0.2)
		(layers "F.Cu" "B.Cu")
		(net 487)
	)
	(segment
		(start 209.5 142.5)
		(end 209.5 143.1)
		(width 0.1)
		(layer "B.Cu")
		(net 487)
	)
	(segment
		(start 204.5 144.5)
		(end 204 145)
		(width 0.1)
		(layer "B.Cu")
		(net 487)
	)
	(segment
		(start 209.5 143.1)
		(end 209.2 143.4)
		(width 0.1)
		(layer "B.Cu")
		(net 487)
	)
	(segment
		(start 184.815001 79.600001)
		(end 185.500001 80.285001)
		(width 0.1)
		(layer "B.Cu")
		(net 487)
	)
	(segment
		(start 182.800001 79.600001)
		(end 184.815001 79.600001)
		(width 0.1)
		(layer "B.Cu")
		(net 487)
	)
	(segment
		(start 204.8 143.4)
		(end 204.5 143.7)
		(width 0.1)
		(layer "B.Cu")
		(net 487)
	)
	(segment
		(start 210 142)
		(end 209.5 142.5)
		(width 0.1)
		(layer "B.Cu")
		(net 487)
	)
	(segment
		(start 204.5 143.7)
		(end 204.5 144.5)
		(width 0.1)
		(layer "B.Cu")
		(net 487)
	)
	(segment
		(start 209.2 143.4)
		(end 204.8 143.4)
		(width 0.1)
		(layer "B.Cu")
		(net 487)
	)
	(segment
		(start 194.87 146.38)
		(end 193.27 146.38)
		(width 0.1)
		(layer "In3.Cu")
		(net 487)
	)
	(segment
		(start 179.800001 80.300001)
		(end 180.500001 79.600001)
		(width 0.1)
		(layer "In3.Cu")
		(net 487)
	)
	(segment
		(start 179.800001 139.282844)
		(end 179.800001 80.300001)
		(width 0.1)
		(layer "In3.Cu")
		(net 487)
	)
	(segment
		(start 204.000001 145.000001)
		(end 203.414715 145.585287)
		(width 0.1)
		(layer "In3.Cu")
		(net 487)
	)
	(segment
		(start 182.400001 144.870573)
		(end 182.400001 141.882843)
		(width 0.1)
		(layer "In3.Cu")
		(net 487)
	)
	(segment
		(start 180.500001 79.600001)
		(end 182.800001 79.600001)
		(width 0.1)
		(layer "In3.Cu")
		(net 487)
	)
	(segment
		(start 182.400001 141.882843)
		(end 179.800001 139.282844)
		(width 0.1)
		(layer "In3.Cu")
		(net 487)
	)
	(segment
		(start 193.27 146.38)
		(end 192.475287 145.585287)
		(width 0.1)
		(layer "In3.Cu")
		(net 487)
	)
	(segment
		(start 195.664713 145.585287)
		(end 194.87 146.38)
		(width 0.1)
		(layer "In3.Cu")
		(net 487)
	)
	(segment
		(start 183.114715 145.585287)
		(end 182.400001 144.870573)
		(width 0.1)
		(layer "In3.Cu")
		(net 487)
	)
	(segment
		(start 192.475287 145.585287)
		(end 183.114715 145.585287)
		(width 0.1)
		(layer "In3.Cu")
		(net 487)
	)
	(segment
		(start 203.414715 145.585287)
		(end 195.664713 145.585287)
		(width 0.1)
		(layer "In3.Cu")
		(net 487)
	)
	(segment
		(start 206.5 140.5)
		(end 207 141)
		(width 0.256)
		(layer "F.Cu")
		(net 488)
	)
	(via
		(at 207 141)
		(size 0.45)
		(drill 0.2)
		(layers "F.Cu" "B.Cu")
		(net 488)
	)
	(via
		(at 182.800001 80.200001)
		(size 0.45)
		(drill 0.2)
		(layers "F.Cu" "B.Cu")
		(net 488)
	)
	(segment
		(start 183.400001 80.800001)
		(end 186.285001 80.800001)
		(width 0.1)
		(layer "B.Cu")
		(net 488)
	)
	(segment
		(start 182.800001 80.200001)
		(end 183.400001 80.800001)
		(width 0.1)
		(layer "B.Cu")
		(net 488)
	)
	(segment
		(start 186.285001 80.800001)
		(end 186.800001 80.285001)
		(width 0.1)
		(layer "B.Cu")
		(net 488)
	)
	(segment
		(start 207.000001 141.000001)
		(end 206.600001 141.400001)
		(width 0.1)
		(layer "In3.Cu")
		(net 488)
	)
	(segment
		(start 181.400001 84.274166)
		(end 181.789813 83.884354)
		(width 0.1)
		(layer "In3.Cu")
		(net 488)
	)
	(segment
		(start 184.282843 141.400001)
		(end 181.400001 138.517159)
		(width 0.1)
		(layer "In3.Cu")
		(net 488)
	)
	(segment
		(start 206.600001 141.400001)
		(end 184.282843 141.400001)
		(width 0.1)
		(layer "In3.Cu")
		(net 488)
	)
	(segment
		(start 182.250501 82.717659)
		(end 182.250501 80.749501)
		(width 0.1)
		(layer "In3.Cu")
		(net 488)
	)
	(segment
		(start 181.789813 83.178347)
		(end 182.250501 82.717659)
		(width 0.1)
		(layer "In3.Cu")
		(net 488)
	)
	(segment
		(start 181.789813 83.884354)
		(end 181.789813 83.178347)
		(width 0.1)
		(layer "In3.Cu")
		(net 488)
	)
	(segment
		(start 181.400001 138.517159)
		(end 181.400001 84.274166)
		(width 0.1)
		(layer "In3.Cu")
		(net 488)
	)
	(segment
		(start 182.250501 80.749501)
		(end 182.800001 80.200001)
		(width 0.1)
		(layer "In3.Cu")
		(net 488)
	)
	(segment
		(start 205.5 143.5)
		(end 205.975 143.975)
		(width 0.256)
		(layer "F.Cu")
		(net 489)
	)
	(segment
		(start 205.975 143.975)
		(end 205.984648 143.975)
		(width 0.256)
		(layer "F.Cu")
		(net 489)
	)
	(via
		(at 205.984648 143.975)
		(size 0.45)
		(drill 0.2)
		(layers "F.Cu" "B.Cu")
		(net 489)
	)
	(via
		(at 180.615313 80.500001)
		(size 0.45)
		(drill 0.2)
		(layers "F.Cu" "B.Cu")
		(net 489)
	)
	(segment
		(start 180.615313 80.500001)
		(end 180.915313 80.200001)
		(width 0.1)
		(layer "B.Cu")
		(net 489)
	)
	(segment
		(start 189.36 80.325002)
		(end 188.685001 81.000001)
		(width 0.1)
		(layer "B.Cu")
		(net 489)
	)
	(segment
		(start 180.915313 80.200001)
		(end 181.600001 80.200001)
		(width 0.1)
		(layer "B.Cu")
		(net 489)
	)
	(segment
		(start 182.400001 81.000001)
		(end 188.685001 81.000001)
		(width 0.1)
		(layer "B.Cu")
		(net 489)
	)
	(segment
		(start 181.600001 80.200001)
		(end 182.400001 81.000001)
		(width 0.1)
		(layer "B.Cu")
		(net 489)
	)
	(segment
		(start 189.36 80.285)
		(end 189.36 80.325002)
		(width 0.1)
		(layer "B.Cu")
		(net 489)
	)
	(segment
		(start 180.400001 83.859956)
		(end 180.400001 139.000001)
		(width 0.1)
		(layer "In3.Cu")
		(net 489)
	)
	(segment
		(start 184.100001 142.700001)
		(end 184.100001 143.000001)
		(width 0.1)
		(layer "In3.Cu")
		(net 489)
	)
	(segment
		(start 180.400001 139.000001)
		(end 184.100001 142.700001)
		(width 0.1)
		(layer "In3.Cu")
		(net 489)
	)
	(segment
		(start 180.789813 83.470144)
		(end 180.400001 83.859956)
		(width 0.1)
		(layer "In3.Cu")
		(net 489)
	)
	(segment
		(start 184.100001 143.000001)
		(end 184.700001 143.600001)
		(width 0.1)
		(layer "In3.Cu")
		(net 489)
	)
	(segment
		(start 205.600001 143.600001)
		(end 206.000001 144.000001)
		(width 0.1)
		(layer "In3.Cu")
		(net 489)
	)
	(segment
		(start 184.700001 143.600001)
		(end 205.600001 143.600001)
		(width 0.1)
		(layer "In3.Cu")
		(net 489)
	)
	(segment
		(start 180.615313 80.500001)
		(end 180.789813 80.674501)
		(width 0.1)
		(layer "In3.Cu")
		(net 489)
	)
	(segment
		(start 180.789813 80.674501)
		(end 180.789813 83.470144)
		(width 0.1)
		(layer "In3.Cu")
		(net 489)
	)
	(segment
		(start 170.504001 93.432001)
		(end 168.218 93.432002)
		(width 0.16)
		(layer "F.Cu")
		(net 490)
	)
	(segment
		(start 170.504001 93.432001)
		(end 170.572501 93.500501)
		(width 0.16)
		(layer "F.Cu")
		(net 490)
	)
	(segment
		(start 171.599501 93.625001)
		(end 171.475001 93.500501)
		(width 0.201)
		(layer "F.Cu")
		(net 490)
	)
	(segment
		(start 171.475001 93.500501)
		(end 170.572501 93.500501)
		(width 0.201)
		(layer "F.Cu")
		(net 490)
	)
	(segment
		(start 167.715001 93.935001)
		(end 168.218 93.432002)
		(width 0.16)
		(layer "F.Cu")
		(net 490)
	)
	(via
		(at 171.599501 93.625001)
		(size 0.45)
		(drill 0.2)
		(layers "F.Cu" "B.Cu")
		(net 490)
	)
	(via
		(at 189.5 130.5)
		(size 0.45)
		(drill 0.2)
		(layers "F.Cu" "B.Cu")
		(net 490)
	)
	(segment
		(start 179.976451 130.200001)
		(end 183.346376 130.200001)
		(width 0.201)
		(layer "B.Cu")
		(net 490)
	)
	(segment
		(start 175.876951 93.500501)
		(end 177.919501 95.543051)
		(width 0.201)
		(layer "B.Cu")
		(net 490)
	)
	(segment
		(start 188.786 130.100002)
		(end 188.736 130.100002)
		(width 0.1)
		(layer "B.Cu")
		(net 490)
	)
	(segment
		(start 189.830002 130.500001)
		(end 189.8994 130.430604)
		(width 0.1)
		(layer "B.Cu")
		(net 490)
	)
	(segment
		(start 189.161 130.225002)
		(end 189.161 130.327733)
		(width 0.1)
		(layer "B.Cu")
		(net 490)
	)
	(segment
		(start 189.8994 130.220821)
		(end 189.77858 130.100002)
		(width 0.1)
		(layer "B.Cu")
		(net 490)
	)
	(segment
		(start 177.919501 95.543051)
		(end 177.919501 128.143051)
		(width 0.201)
		(layer "B.Cu")
		(net 490)
	)
	(segment
		(start 189.500001 130.500001)
		(end 189.830002 130.500001)
		(width 0.1)
		(layer "B.Cu")
		(net 490)
	)
	(segment
		(start 177.919501 128.143051)
		(end 179.976451 130.200001)
		(width 0.201)
		(layer "B.Cu")
		(net 490)
	)
	(segment
		(start 171.724002 93.500501)
		(end 175.876951 93.500501)
		(width 0.201)
		(layer "B.Cu")
		(net 490)
	)
	(segment
		(start 188.911 130.327733)
		(end 188.911 130.225002)
		(width 0.1)
		(layer "B.Cu")
		(net 490)
	)
	(segment
		(start 183.446376 130.100001)
		(end 183.346376 130.200001)
		(width 0.1)
		(layer "B.Cu")
		(net 490)
	)
	(segment
		(start 189.8994 130.430604)
		(end 189.8994 130.220821)
		(width 0.1)
		(layer "B.Cu")
		(net 490)
	)
	(segment
		(start 188.736 130.100002)
		(end 183.446376 130.100001)
		(width 0.1)
		(layer "B.Cu")
		(net 490)
	)
	(segment
		(start 189.77858 130.100002)
		(end 189.286 130.100002)
		(width 0.1)
		(layer "B.Cu")
		(net 490)
	)
	(segment
		(start 171.599501 93.625001)
		(end 171.724002 93.500501)
		(width 0.201)
		(layer "B.Cu")
		(net 490)
	)
	(arc
		(start 189.036 130.452733)
		(mid 188.947612 130.416121)
		(end 188.911 130.327733)
		(width 0.1)
		(layer "B.Cu")
		(net 490)
	)
	(arc
		(start 189.161 130.327733)
		(mid 189.124388 130.416121)
		(end 189.036 130.452733)
		(width 0.1)
		(layer "B.Cu")
		(net 490)
	)
	(arc
		(start 189.286 130.100002)
		(mid 189.197612 130.136614)
		(end 189.161 130.225002)
		(width 0.1)
		(layer "B.Cu")
		(net 490)
	)
	(arc
		(start 188.911 130.225002)
		(mid 188.874388 130.136614)
		(end 188.786 130.100002)
		(width 0.1)
		(layer "B.Cu")
		(net 490)
	)
	(segment
		(start 206.5 142.5)
		(end 207 143)
		(width 0.256)
		(layer "F.Cu")
		(net 491)
	)
	(via
		(at 207 143)
		(size 0.45)
		(drill 0.2)
		(layers "F.Cu" "B.Cu")
		(net 491)
	)
	(via
		(at 181.676001 80.900001)
		(size 0.45)
		(drill 0.2)
		(layers "F.Cu" "B.Cu")
		(net 491)
	)
	(segment
		(start 189.585001 81.300001)
		(end 190.600001 80.285001)
		(width 0.1)
		(layer "B.Cu")
		(net 491)
	)
	(segment
		(start 181.676001 80.900001)
		(end 181.876001 81.100001)
		(width 0.1)
		(layer "B.Cu")
		(net 491)
	)
	(segment
		(start 181.882843 81.100001)
		(end 182.082843 81.300001)
		(width 0.1)
		(layer "B.Cu")
		(net 491)
	)
	(segment
		(start 182.082843 81.300001)
		(end 189.585001 81.300001)
		(width 0.1)
		(layer "B.Cu")
		(net 491)
	)
	(segment
		(start 181.876001 81.100001)
		(end 181.882843 81.100001)
		(width 0.1)
		(layer "B.Cu")
		(net 491)
	)
	(segment
		(start 181.189813 83.635828)
		(end 180.800001 84.02564)
		(width 0.1)
		(layer "In3.Cu")
		(net 491)
	)
	(segment
		(start 206.600001 142.600001)
		(end 207.000001 143.000001)
		(width 0.1)
		(layer "In3.Cu")
		(net 491)
	)
	(segment
		(start 180.800001 84.02564)
		(end 180.800001 138.800001)
		(width 0.1)
		(layer "In3.Cu")
		(net 491)
	)
	(segment
		(start 181.189813 81.386189)
		(end 181.189813 83.635828)
		(width 0.1)
		(layer "In3.Cu")
		(net 491)
	)
	(segment
		(start 181.676001 80.900001)
		(end 181.189813 81.386189)
		(width 0.1)
		(layer "In3.Cu")
		(net 491)
	)
	(segment
		(start 184.600001 142.600001)
		(end 206.600001 142.600001)
		(width 0.1)
		(layer "In3.Cu")
		(net 491)
	)
	(segment
		(start 180.800001 138.800001)
		(end 184.600001 142.600001)
		(width 0.1)
		(layer "In3.Cu")
		(net 491)
	)
	(segment
		(start 204.5 142.5)
		(end 205 143)
		(width 0.256)
		(layer "F.Cu")
		(net 492)
	)
	(via
		(at 205 143)
		(size 0.45)
		(drill 0.2)
		(layers "F.Cu" "B.Cu")
		(net 492)
	)
	(via
		(at 181.169399 80.687143)
		(size 0.45)
		(drill 0.2)
		(layers "F.Cu" "B.Cu")
		(net 492)
	)
	(segment
		(start 181.700001 81.300001)
		(end 181.500001 81.300001)
		(width 0.1)
		(layer "B.Cu")
		(net 492)
	)
	(segment
		(start 191.300001 81.600001)
		(end 182.000001 81.600001)
		(width 0.1)
		(layer "B.Cu")
		(net 492)
	)
	(segment
		(start 182.000001 81.600001)
		(end 181.700001 81.300001)
		(width 0.1)
		(layer "B.Cu")
		(net 492)
	)
	(segment
		(start 181.500001 81.300001)
		(end 181.169399 80.969399)
		(width 0.1)
		(layer "B.Cu")
		(net 492)
	)
	(segment
		(start 191.900001 80.285001)
		(end 191.900001 81.000001)
		(width 0.1)
		(layer "B.Cu")
		(net 492)
	)
	(segment
		(start 191.900001 81.000001)
		(end 191.300001 81.600001)
		(width 0.1)
		(layer "B.Cu")
		(net 492)
	)
	(segment
		(start 181.169399 80.969399)
		(end 181.169399 80.687143)
		(width 0.1)
		(layer "B.Cu")
		(net 492)
	)
	(segment
		(start 181.169399 80.687143)
		(end 180.989813 80.866729)
		(width 0.1)
		(layer "In3.Cu")
		(net 492)
	)
	(segment
		(start 184.86967 143.400001)
		(end 204.600001 143.400001)
		(width 0.1)
		(layer "In3.Cu")
		(net 492)
	)
	(segment
		(start 184.30858 142.591422)
		(end 184.30858 142.83891)
		(width 0.1)
		(layer "In3.Cu")
		(net 492)
	)
	(segment
		(start 180.600001 83.942798)
		(end 180.600001 138.882843)
		(width 0.1)
		(layer "In3.Cu")
		(net 492)
	)
	(segment
		(start 180.600001 138.882843)
		(end 184.30858 142.591422)
		(width 0.1)
		(layer "In3.Cu")
		(net 492)
	)
	(segment
		(start 184.30858 142.83891)
		(end 184.86967 143.400001)
		(width 0.1)
		(layer "In3.Cu")
		(net 492)
	)
	(segment
		(start 180.989813 83.552986)
		(end 180.600001 83.942798)
		(width 0.1)
		(layer "In3.Cu")
		(net 492)
	)
	(segment
		(start 180.989813 80.866729)
		(end 180.989813 83.552986)
		(width 0.1)
		(layer "In3.Cu")
		(net 492)
	)
	(segment
		(start 204.600001 143.400001)
		(end 205.000001 143.000001)
		(width 0.1)
		(layer "In3.Cu")
		(net 492)
	)
	(segment
		(start 206.5 141.5)
		(end 207 142)
		(width 0.256)
		(layer "F.Cu")
		(net 493)
	)
	(via
		(at 207 142)
		(size 0.45)
		(drill 0.2)
		(layers "F.Cu" "B.Cu")
		(net 493)
	)
	(via
		(at 181.600001 81.800001)
		(size 0.45)
		(drill 0.2)
		(layers "F.Cu" "B.Cu")
		(net 493)
	)
	(segment
		(start 181.700001 81.900001)
		(end 192.600001 81.900001)
		(width 0.1)
		(layer "B.Cu")
		(net 493)
	)
	(segment
		(start 193.100001 81.400001)
		(end 193.100001 80.285001)
		(width 0.1)
		(layer "B.Cu")
		(net 493)
	)
	(segment
		(start 192.600001 81.900001)
		(end 193.100001 81.400001)
		(width 0.1)
		(layer "B.Cu")
		(net 493)
	)
	(segment
		(start 181.600001 81.800001)
		(end 181.700001 81.900001)
		(width 0.1)
		(layer "B.Cu")
		(net 493)
	)
	(segment
		(start 206.600001 141.600001)
		(end 207.000001 142.000001)
		(width 0.1)
		(layer "In3.Cu")
		(net 493)
	)
	(segment
		(start 181.589813 83.801512)
		(end 181.200001 84.191324)
		(width 0.1)
		(layer "In3.Cu")
		(net 493)
	)
	(segment
		(start 181.589813 83.089813)
		(end 181.589813 83.801512)
		(width 0.1)
		(layer "In3.Cu")
		(net 493)
	)
	(segment
		(start 182.050501 82.634817)
		(end 181.595505 83.089813)
		(width 0.1)
		(layer "In3.Cu")
		(net 493)
	)
	(segment
		(start 184.200001 141.600001)
		(end 206.600001 141.600001)
		(width 0.1)
		(layer "In3.Cu")
		(net 493)
	)
	(segment
		(start 181.595505 83.089813)
		(end 181.589813 83.089813)
		(width 0.1)
		(layer "In3.Cu")
		(net 493)
	)
	(segment
		(start 181.200001 84.191324)
		(end 181.200001 138.600001)
		(width 0.1)
		(layer "In3.Cu")
		(net 493)
	)
	(segment
		(start 182.050501 82.250501)
		(end 182.050501 82.634817)
		(width 0.1)
		(layer "In3.Cu")
		(net 493)
	)
	(segment
		(start 181.200001 138.600001)
		(end 184.200001 141.600001)
		(width 0.1)
		(layer "In3.Cu")
		(net 493)
	)
	(segment
		(start 181.600001 81.800001)
		(end 182.050501 82.250501)
		(width 0.1)
		(layer "In3.Cu")
		(net 493)
	)
	(via
		(at 192.5 133.5)
		(size 0.45)
		(drill 0.2)
		(layers "F.Cu" "B.Cu")
		(net 494)
	)
	(segment
		(start 192.3 133.3)
		(end 192.285 133.3)
		(width 0.4)
		(layer "B.Cu")
		(net 494)
	)
	(segment
		(start 192.5 133.5)
		(end 192.3 133.3)
		(width 0.4)
		(layer "B.Cu")
		(net 494)
	)
	(segment
		(start 198.745 110)
		(end 198.545 110)
		(width 0.184)
		(layer "F.Cu")
		(net 495)
	)
	(segment
		(start 202.5 116.5)
		(end 203 116)
		(width 0.182)
		(layer "F.Cu")
		(net 495)
	)
	(segment
		(start 203 114.16)
		(end 203 113.35)
		(width 0.182)
		(layer "F.Cu")
		(net 495)
	)
	(segment
		(start 198.545 110.1)
		(end 198.545 110)
		(width 0.184)
		(layer "F.Cu")
		(net 495)
	)
	(segment
		(start 201.6 111.5)
		(end 203 112.9)
		(width 0.184)
		(layer "F.Cu")
		(net 495)
	)
	(segment
		(start 203 112.9)
		(end 203 113.35)
		(width 0.184)
		(layer "F.Cu")
		(net 495)
	)
	(segment
		(start 198.745 110)
		(end 199.445 110.7)
		(width 0.184)
		(layer "F.Cu")
		(net 495)
	)
	(segment
		(start 199.445 110.7)
		(end 199.445 110.82)
		(width 0.184)
		(layer "F.Cu")
		(net 495)
	)
	(segment
		(start 198.445 110)
		(end 198.745 110)
		(width 0.184)
		(layer "F.Cu")
		(net 495)
	)
	(segment
		(start 198.445 110)
		(end 198.545 110.1)
		(width 0.184)
		(layer "F.Cu")
		(net 495)
	)
	(segment
		(start 203 116)
		(end 203 115.27)
		(width 0.182)
		(layer "F.Cu")
		(net 495)
	)
	(segment
		(start 203 115.27)
		(end 202.8 115.07)
		(width 0.182)
		(layer "F.Cu")
		(net 495)
	)
	(segment
		(start 197.8 110)
		(end 198.445 110)
		(width 0.184)
		(layer "F.Cu")
		(net 495)
	)
	(segment
		(start 198.545 110.945)
		(end 199.1 111.5)
		(width 0.184)
		(layer "F.Cu")
		(net 495)
	)
	(segment
		(start 202.8 114.36)
		(end 203 114.16)
		(width 0.182)
		(layer "F.Cu")
		(net 495)
	)
	(segment
		(start 198.545 110.1)
		(end 198.545 110.945)
		(width 0.182)
		(layer "F.Cu")
		(net 495)
	)
	(segment
		(start 202.8 115.07)
		(end 202.8 114.36)
		(width 0.182)
		(layer "F.Cu")
		(net 495)
	)
	(segment
		(start 199.1 111.5)
		(end 201.6 111.5)
		(width 0.184)
		(layer "F.Cu")
		(net 495)
	)
	(segment
		(start 198.645 110)
		(end 198.545 110.1)
		(width 0.184)
		(layer "F.Cu")
		(net 495)
	)
	(segment
		(start 201 117)
		(end 201 116.3)
		(width 0.182)
		(layer "F.Cu")
		(net 496)
	)
	(segment
		(start 200 115.7)
		(end 200 114.7)
		(width 0.182)
		(layer "F.Cu")
		(net 496)
	)
	(segment
		(start 200.5 117.5)
		(end 201 117)
		(width 0.182)
		(layer "F.Cu")
		(net 496)
	)
	(segment
		(start 200.65 115.95)
		(end 200.25 115.95)
		(width 0.182)
		(layer "F.Cu")
		(net 496)
	)
	(segment
		(start 201 116.3)
		(end 200.65 115.95)
		(width 0.182)
		(layer "F.Cu")
		(net 496)
	)
	(segment
		(start 195.075 113.575)
		(end 195.2 113.7)
		(width 0.182)
		(layer "F.Cu")
		(net 496)
	)
	(segment
		(start 199.7 114.4)
		(end 200 114.7)
		(width 0.184)
		(layer "F.Cu")
		(net 496)
	)
	(segment
		(start 200.25 115.95)
		(end 200 115.7)
		(width 0.182)
		(layer "F.Cu")
		(net 496)
	)
	(segment
		(start 195.9 114.4)
		(end 199.7 114.4)
		(width 0.184)
		(layer "F.Cu")
		(net 496)
	)
	(segment
		(start 195.075 111.225)
		(end 195.075 113.575)
		(width 0.182)
		(layer "F.Cu")
		(net 496)
	)
	(segment
		(start 195.2 113.7)
		(end 195.9 114.4)
		(width 0.184)
		(layer "F.Cu")
		(net 496)
	)
	(segment
		(start 261.215 130.7)
		(end 261.215 131.485)
		(width 0.1)
		(layer "F.Cu")
		(net 497)
	)
	(segment
		(start 260.085 130.7)
		(end 261.215 130.7)
		(width 0.1)
		(layer "F.Cu")
		(net 497)
	)
	(segment
		(start 210.5 144.5)
		(end 211.015374 145.015374)
		(width 0.256)
		(layer "F.Cu")
		(net 497)
	)
	(segment
		(start 261.215 131.485)
		(end 260.8 131.9)
		(width 0.1)
		(layer "F.Cu")
		(net 497)
	)
	(segment
		(start 211.015374 145.015374)
		(end 211.015374 145.025)
		(width 0.256)
		(layer "F.Cu")
		(net 497)
	)
	(via
		(at 211.015374 145.025)
		(size 0.45)
		(drill 0.2)
		(layers "F.Cu" "B.Cu")
		(net 497)
	)
	(via
		(at 223.925 127.175)
		(size 0.45)
		(drill 0.2)
		(layers "F.Cu" "B.Cu")
		(net 497)
	)
	(via
		(at 260.8 131.9)
		(size 0.45)
		(drill 0.2)
		(layers "F.Cu" "B.Cu")
		(net 497)
	)
	(segment
		(start 211.015374 143.015374)
		(end 210.6 142.6)
		(width 0.1)
		(layer "B.Cu")
		(net 497)
	)
	(segment
		(start 210.6 137.6)
		(end 210.6 134.8)
		(width 0.1)
		(layer "B.Cu")
		(net 497)
	)
	(segment
		(start 216 133.4)
		(end 216.6 132.8)
		(width 0.1)
		(layer "B.Cu")
		(net 497)
	)
	(segment
		(start 211.015374 145.025)
		(end 211.015374 143.015374)
		(width 0.1)
		(layer "B.Cu")
		(net 497)
	)
	(segment
		(start 211.5 138.5)
		(end 210.6 137.6)
		(width 0.1)
		(layer "B.Cu")
		(net 497)
	)
	(segment
		(start 211.6 131.8)
		(end 211.6 133.2)
		(width 0.1)
		(layer "B.Cu")
		(net 497)
	)
	(segment
		(start 216.6 131.875)
		(end 218.175 130.3)
		(width 0.1)
		(layer "B.Cu")
		(net 497)
	)
	(segment
		(start 210.3 134.5)
		(end 209.8 134.5)
		(width 0.1)
		(layer "B.Cu")
		(net 497)
	)
	(segment
		(start 218.175 128.275)
		(end 219.275 127.175)
		(width 0.1)
		(layer "B.Cu")
		(net 497)
	)
	(segment
		(start 219.275 127.175)
		(end 223.925 127.175)
		(width 0.1)
		(layer "B.Cu")
		(net 497)
	)
	(segment
		(start 209.8 134.5)
		(end 209.59 134.29)
		(width 0.1)
		(layer "B.Cu")
		(net 497)
	)
	(segment
		(start 211.6 133.2)
		(end 211.8 133.4)
		(width 0.1)
		(layer "B.Cu")
		(net 497)
	)
	(segment
		(start 210.6 142.6)
		(end 210.6 141.8)
		(width 0.1)
		(layer "B.Cu")
		(net 497)
	)
	(segment
		(start 211.425 131.625)
		(end 211.6 131.8)
		(width 0.1)
		(layer "B.Cu")
		(net 497)
	)
	(segment
		(start 209.844669 131.625)
		(end 211.425 131.625)
		(width 0.1)
		(layer "B.Cu")
		(net 497)
	)
	(segment
		(start 218.175 130.3)
		(end 218.175 128.275)
		(width 0.1)
		(layer "B.Cu")
		(net 497)
	)
	(segment
		(start 209.59 131.879669)
		(end 209.844669 131.625)
		(width 0.1)
		(layer "B.Cu")
		(net 497)
	)
	(segment
		(start 209.59 134.29)
		(end 209.59 131.879669)
		(width 0.1)
		(layer "B.Cu")
		(net 497)
	)
	(segment
		(start 211.8 133.4)
		(end 216 133.4)
		(width 0.1)
		(layer "B.Cu")
		(net 497)
	)
	(segment
		(start 216.6 132.8)
		(end 216.6 131.875)
		(width 0.1)
		(layer "B.Cu")
		(net 497)
	)
	(segment
		(start 210.9 141.5)
		(end 211.1 141.5)
		(width 0.1)
		(layer "B.Cu")
		(net 497)
	)
	(segment
		(start 210.6 141.8)
		(end 210.9 141.5)
		(width 0.1)
		(layer "B.Cu")
		(net 497)
	)
	(segment
		(start 210.6 134.8)
		(end 210.3 134.5)
		(width 0.1)
		(layer "B.Cu")
		(net 497)
	)
	(segment
		(start 211.5 141.1)
		(end 211.5 138.5)
		(width 0.1)
		(layer "B.Cu")
		(net 497)
	)
	(segment
		(start 211.1 141.5)
		(end 211.5 141.1)
		(width 0.1)
		(layer "B.Cu")
		(net 497)
	)
	(segment
		(start 222.775 124.025)
		(end 223.325 123.475)
		(width 0.1)
		(layer "In5.Cu")
		(net 497)
	)
	(segment
		(start 242.65 117.95)
		(end 242.975 117.625)
		(width 0.1)
		(layer "In5.Cu")
		(net 497)
	)
	(segment
		(start 231.25 123.45)
		(end 234.65 120.05)
		(width 0.1)
		(layer "In5.Cu")
		(net 497)
	)
	(segment
		(start 219.025 124.025)
		(end 222.775 124.025)
		(width 0.1)
		(layer "In5.Cu")
		(net 497)
	)
	(segment
		(start 218.85 125.625)
		(end 222.75 125.625)
		(width 0.1)
		(layer "In5.Cu")
		(net 497)
	)
	(segment
		(start 255.325 118.9)
		(end 259.15 122.725)
		(width 0.1)
		(layer "In5.Cu")
		(net 497)
	)
	(segment
		(start 223.925 127.175)
		(end 223.925 126.8)
		(width 0.1)
		(layer "In5.Cu")
		(net 497)
	)
	(segment
		(start 223.325 123.475)
		(end 223.35 123.45)
		(width 0.1)
		(layer "In5.Cu")
		(net 497)
	)
	(segment
		(start 242.975 117.625)
		(end 249.975 117.625)
		(width 0.1)
		(layer "In5.Cu")
		(net 497)
	)
	(segment
		(start 259.15 122.725)
		(end 259.15 130.25)
		(width 0.1)
		(layer "In5.Cu")
		(net 497)
	)
	(segment
		(start 218.525 124.525)
		(end 219.025 124.025)
		(width 0.1)
		(layer "In5.Cu")
		(net 497)
	)
	(segment
		(start 223.35 123.45)
		(end 231.25 123.45)
		(width 0.1)
		(layer "In5.Cu")
		(net 497)
	)
	(segment
		(start 254 119.075)
		(end 254.175 118.9)
		(width 0.1)
		(layer "In5.Cu")
		(net 497)
	)
	(segment
		(start 218.85 125.625)
		(end 218.525 125.3)
		(width 0.1)
		(layer "In5.Cu")
		(net 497)
	)
	(segment
		(start 222.75 125.625)
		(end 223.925 126.8)
		(width 0.1)
		(layer "In5.Cu")
		(net 497)
	)
	(segment
		(start 259.15 130.25)
		(end 260.8 131.9)
		(width 0.1)
		(layer "In5.Cu")
		(net 497)
	)
	(segment
		(start 251.425 119.075)
		(end 254 119.075)
		(width 0.1)
		(layer "In5.Cu")
		(net 497)
	)
	(segment
		(start 249.975 117.625)
		(end 251.425 119.075)
		(width 0.1)
		(layer "In5.Cu")
		(net 497)
	)
	(segment
		(start 234.65 120.05)
		(end 241.375 120.05)
		(width 0.1)
		(layer "In5.Cu")
		(net 497)
	)
	(segment
		(start 218.525 125.3)
		(end 218.525 124.525)
		(width 0.1)
		(layer "In5.Cu")
		(net 497)
	)
	(segment
		(start 254.175 118.9)
		(end 255.325 118.9)
		(width 0.1)
		(layer "In5.Cu")
		(net 497)
	)
	(segment
		(start 241.375 120.05)
		(end 242.65 118.775)
		(width 0.1)
		(layer "In5.Cu")
		(net 497)
	)
	(segment
		(start 242.65 118.775)
		(end 242.65 117.95)
		(width 0.1)
		(layer "In5.Cu")
		(net 497)
	)
	(segment
		(start 232.95 147.8)
		(end 232.592719 147.8)
		(width 0.182)
		(layer "F.Cu")
		(net 498)
	)
	(segment
		(start 232.592719 147.8)
		(end 232.288029 147.49531)
		(width 0.182)
		(layer "F.Cu")
		(net 498)
	)
	(segment
		(start 198.5 141.5)
		(end 198 142)
		(width 0.256)
		(layer "F.Cu")
		(net 498)
	)
	(via
		(at 198 142)
		(size 0.45)
		(drill 0.2)
		(layers "F.Cu" "B.Cu")
		(net 498)
	)
	(via
		(at 232.288029 147.49531)
		(size 0.45)
		(drill 0.2)
		(layers "F.Cu" "B.Cu")
		(net 498)
	)
	(segment
		(start 232.692719 147.9)
		(end 232.288029 147.49531)
		(width 0.182)
		(layer "B.Cu")
		(net 498)
	)
	(segment
		(start 233.315 147.9)
		(end 232.692719 147.9)
		(width 0.182)
		(layer "B.Cu")
		(net 498)
	)
	(segment
		(start 230.192719 145.4)
		(end 232.288029 147.49531)
		(width 0.1)
		(layer "In7.Cu")
		(net 498)
	)
	(segment
		(start 198 143.6)
		(end 199.8 145.4)
		(width 0.1)
		(layer "In7.Cu")
		(net 498)
	)
	(segment
		(start 199.8 145.4)
		(end 230.192719 145.4)
		(width 0.1)
		(layer "In7.Cu")
		(net 498)
	)
	(segment
		(start 198 142)
		(end 198 143.6)
		(width 0.1)
		(layer "In7.Cu")
		(net 498)
	)
	(segment
		(start 172.809251 105.799501)
		(end 170.641001 105.799501)
		(width 0.201)
		(layer "F.Cu")
		(net 499)
	)
	(segment
		(start 170.572501 105.868001)
		(end 170.641001 105.799501)
		(width 0.16)
		(layer "F.Cu")
		(net 499)
	)
	(segment
		(start 166.445001 105.365001)
		(end 166.948 105.868)
		(width 0.16)
		(layer "F.Cu")
		(net 499)
	)
	(segment
		(start 166.948 105.868)
		(end 170.572501 105.868001)
		(width 0.16)
		(layer "F.Cu")
		(net 499)
	)
	(segment
		(start 173.085001 105.523751)
		(end 172.809251 105.799501)
		(width 0.201)
		(layer "F.Cu")
		(net 499)
	)
	(segment
		(start 233.1 149.8)
		(end 232.7 150.2)
		(width 0.182)
		(layer "F.Cu")
		(net 500)
	)
	(segment
		(start 199.5 142.5)
		(end 199 143)
		(width 0.256)
		(layer "F.Cu")
		(net 500)
	)
	(segment
		(start 233.1 149.6)
		(end 233.1 149.8)
		(width 0.182)
		(layer "F.Cu")
		(net 500)
	)
	(via
		(at 199 143)
		(size 0.45)
		(drill 0.2)
		(layers "F.Cu" "B.Cu")
		(net 500)
	)
	(via
		(at 232.7 150.2)
		(size 0.45)
		(drill 0.2)
		(layers "F.Cu" "B.Cu")
		(net 500)
	)
	(segment
		(start 233.315 148.9)
		(end 233.315 149.585)
		(width 0.182)
		(layer "B.Cu")
		(net 500)
	)
	(segment
		(start 233.315 149.585)
		(end 232.7 150.2)
		(width 0.182)
		(layer "B.Cu")
		(net 500)
	)
	(segment
		(start 199.5 144.4)
		(end 199.7 144.6)
		(width 0.1)
		(layer "In7.Cu")
		(net 500)
	)
	(segment
		(start 199.7 144.6)
		(end 230 144.6)
		(width 0.1)
		(layer "In7.Cu")
		(net 500)
	)
	(segment
		(start 232.217234 149.382766)
		(end 232.217234 149.982766)
		(width 0.1)
		(layer "In7.Cu")
		(net 500)
	)
	(segment
		(start 199 143)
		(end 199.5 143.5)
		(width 0.1)
		(layer "In7.Cu")
		(net 500)
	)
	(segment
		(start 232.7 150.2)
		(end 232.434468 150.2)
		(width 0.1)
		(layer "In7.Cu")
		(net 500)
	)
	(segment
		(start 230 144.6)
		(end 232.7 147.3)
		(width 0.1)
		(layer "In7.Cu")
		(net 500)
	)
	(segment
		(start 232.7 147.3)
		(end 232.7 148.9)
		(width 0.1)
		(layer "In7.Cu")
		(net 500)
	)
	(segment
		(start 232.7 148.9)
		(end 232.217234 149.382766)
		(width 0.1)
		(layer "In7.Cu")
		(net 500)
	)
	(segment
		(start 232.434468 150.2)
		(end 232.217234 149.982766)
		(width 0.1)
		(layer "In7.Cu")
		(net 500)
	)
	(segment
		(start 199.5 143.5)
		(end 199.5 144.4)
		(width 0.1)
		(layer "In7.Cu")
		(net 500)
	)
	(segment
		(start 202.5 138.5)
		(end 203 139)
		(width 0.256)
		(layer "F.Cu")
		(net 501)
	)
	(segment
		(start 219.85 150.05)
		(end 219.45 150.05)
		(width 0.184)
		(layer "F.Cu")
		(net 501)
	)
	(segment
		(start 219.45 150.05)
		(end 219.135 150.05)
		(width 0.198)
		(layer "F.Cu")
		(net 501)
	)
	(segment
		(start 220.4625 150.05)
		(end 219.85 150.05)
		(width 0.198)
		(layer "F.Cu")
		(net 501)
	)
	(segment
		(start 219.135 150.05)
		(end 218.885 149.8)
		(width 0.198)
		(layer "F.Cu")
		(net 501)
	)
	(via
		(at 203 139)
		(size 0.45)
		(drill 0.2)
		(layers "F.Cu" "B.Cu")
		(net 501)
	)
	(via
		(at 219.45 150.05)
		(size 0.45)
		(drill 0.2)
		(layers "F.Cu" "B.Cu")
		(net 501)
	)
	(segment
		(start 224.6 146.225)
		(end 224 145.625)
		(width 0.1)
		(layer "In5.Cu")
		(net 501)
	)
	(segment
		(start 221.425 145.625)
		(end 221.2 145.4)
		(width 0.1)
		(layer "In5.Cu")
		(net 501)
	)
	(segment
		(start 224.6 147.8)
		(end 224.6 146.225)
		(width 0.1)
		(layer "In5.Cu")
		(net 501)
	)
	(segment
		(start 219.45 150.05)
		(end 220.6 148.9)
		(width 0.1)
		(layer "In5.Cu")
		(net 501)
	)
	(segment
		(start 224 145.625)
		(end 221.425 145.625)
		(width 0.1)
		(layer "In5.Cu")
		(net 501)
	)
	(segment
		(start 204.5 146.182842)
		(end 204.2 145.882842)
		(width 0.1)
		(layer "In5.Cu")
		(net 501)
	)
	(segment
		(start 215.925 147.775)
		(end 215.925 149.475)
		(width 0.1)
		(layer "In5.Cu")
		(net 501)
	)
	(segment
		(start 204.5 153.825)
		(end 204.5 146.182842)
		(width 0.1)
		(layer "In5.Cu")
		(net 501)
	)
	(segment
		(start 203.25 144.925)
		(end 203.25 141.563173)
		(width 0.1)
		(layer "In5.Cu")
		(net 501)
	)
	(segment
		(start 204.2 145.875)
		(end 203.25 144.925)
		(width 0.1)
		(layer "In5.Cu")
		(net 501)
	)
	(segment
		(start 212.5 152.9)
		(end 210.854657 152.9)
		(width 0.1)
		(layer "In5.Cu")
		(net 501)
	)
	(segment
		(start 203.575 141.238173)
		(end 203.575 139.575)
		(width 0.1)
		(layer "In5.Cu")
		(net 501)
	)
	(segment
		(start 221.2 145.4)
		(end 218.3 145.4)
		(width 0.1)
		(layer "In5.Cu")
		(net 501)
	)
	(segment
		(start 218.3 145.4)
		(end 215.925 147.775)
		(width 0.1)
		(layer "In5.Cu")
		(net 501)
	)
	(segment
		(start 204.2 145.882842)
		(end 204.2 145.875)
		(width 0.1)
		(layer "In5.Cu")
		(net 501)
	)
	(segment
		(start 203.575 139.575)
		(end 203 139)
		(width 0.1)
		(layer "In5.Cu")
		(net 501)
	)
	(segment
		(start 205.4 154.725)
		(end 204.5 153.825)
		(width 0.1)
		(layer "In5.Cu")
		(net 501)
	)
	(segment
		(start 215.925 149.475)
		(end 212.5 152.9)
		(width 0.1)
		(layer "In5.Cu")
		(net 501)
	)
	(segment
		(start 203.25 141.563173)
		(end 203.575 141.238173)
		(width 0.1)
		(layer "In5.Cu")
		(net 501)
	)
	(segment
		(start 220.6 148.9)
		(end 223.5 148.9)
		(width 0.1)
		(layer "In5.Cu")
		(net 501)
	)
	(segment
		(start 209.029658 154.725)
		(end 205.4 154.725)
		(width 0.1)
		(layer "In5.Cu")
		(net 501)
	)
	(segment
		(start 223.5 148.9)
		(end 224.6 147.8)
		(width 0.1)
		(layer "In5.Cu")
		(net 501)
	)
	(segment
		(start 210.854657 152.9)
		(end 209.029658 154.725)
		(width 0.1)
		(layer "In5.Cu")
		(net 501)
	)
	(segment
		(start 219.1 147.15)
		(end 220.15 147.15)
		(width 0.184)
		(layer "F.Cu")
		(net 502)
	)
	(segment
		(start 220.6375 148.3625)
		(end 220.5 148.225)
		(width 0.184)
		(layer "F.Cu")
		(net 502)
	)
	(segment
		(start 203.025 136.051391)
		(end 203.025 136.025)
		(width 0.256)
		(layer "F.Cu")
		(net 502)
	)
	(segment
		(start 203.025 136.025)
		(end 202.5 135.5)
		(width 0.256)
		(layer "F.Cu")
		(net 502)
	)
	(segment
		(start 218.885 147.8)
		(end 218.885 147.365)
		(width 0.184)
		(layer "F.Cu")
		(net 502)
	)
	(segment
		(start 221.15 148.3625)
		(end 220.6375 148.3625)
		(width 0.184)
		(layer "F.Cu")
		(net 502)
	)
	(segment
		(start 220.5 148.225)
		(end 220.4 148.125)
		(width 0.184)
		(layer "F.Cu")
		(net 502)
	)
	(segment
		(start 220.15 147.15)
		(end 220.4 147.4)
		(width 0.184)
		(layer "F.Cu")
		(net 502)
	)
	(segment
		(start 218.885 147.365)
		(end 219.1 147.15)
		(width 0.184)
		(layer "F.Cu")
		(net 502)
	)
	(segment
		(start 220.4 148.125)
		(end 220.4 147.4)
		(width 0.184)
		(layer "F.Cu")
		(net 502)
	)
	(via
		(at 203.025 136.051391)
		(size 0.45)
		(drill 0.2)
		(layers "F.Cu" "B.Cu")
		(net 502)
	)
	(via
		(at 220.4 147.4)
		(size 0.45)
		(drill 0.2)
		(layers "F.Cu" "B.Cu")
		(net 502)
	)
	(segment
		(start 207.617158 157.3)
		(end 211.217158 153.7)
		(width 0.1)
		(layer "In5.Cu")
		(net 502)
	)
	(segment
		(start 220.4 147.775)
		(end 220.4 147.4)
		(width 0.1)
		(layer "In5.Cu")
		(net 502)
	)
	(segment
		(start 211.217158 153.7)
		(end 213.325 153.7)
		(width 0.1)
		(layer "In5.Cu")
		(net 502)
	)
	(segment
		(start 203.025 136.051391)
		(end 202.4 136.676391)
		(width 0.1)
		(layer "In5.Cu")
		(net 502)
	)
	(segment
		(start 202.4 151.640684)
		(end 203 152.240684)
		(width 0.1)
		(layer "In5.Cu")
		(net 502)
	)
	(segment
		(start 203 152.240684)
		(end 203 156.95)
		(width 0.1)
		(layer "In5.Cu")
		(net 502)
	)
	(segment
		(start 217.15 148.4)
		(end 219.775 148.4)
		(width 0.1)
		(layer "In5.Cu")
		(net 502)
	)
	(segment
		(start 219.775 148.4)
		(end 220.4 147.775)
		(width 0.1)
		(layer "In5.Cu")
		(net 502)
	)
	(segment
		(start 202.4 136.676391)
		(end 202.4 151.640684)
		(width 0.1)
		(layer "In5.Cu")
		(net 502)
	)
	(segment
		(start 213.325 153.7)
		(end 216.9 150.125)
		(width 0.1)
		(layer "In5.Cu")
		(net 502)
	)
	(segment
		(start 203 156.95)
		(end 203.35 157.3)
		(width 0.1)
		(layer "In5.Cu")
		(net 502)
	)
	(segment
		(start 216.9 148.65)
		(end 217.15 148.4)
		(width 0.1)
		(layer "In5.Cu")
		(net 502)
	)
	(segment
		(start 216.9 150.125)
		(end 216.9 148.65)
		(width 0.1)
		(layer "In5.Cu")
		(net 502)
	)
	(segment
		(start 203.35 157.3)
		(end 207.617158 157.3)
		(width 0.1)
		(layer "In5.Cu")
		(net 502)
	)
	(segment
		(start 204.5 119.5)
		(end 205 119)
		(width 0.256)
		(layer "F.Cu")
		(net 503)
	)
	(segment
		(start 197.041252 92.1)
		(end 196.991252 92.05)
		(width 0.182)
		(layer "F.Cu")
		(net 503)
	)
	(segment
		(start 198.022851 92.1)
		(end 197.041252 92.1)
		(width 0.182)
		(layer "F.Cu")
		(net 503)
	)
	(via
		(at 196.991252 92.05)
		(size 0.45)
		(drill 0.2)
		(layers "F.Cu" "B.Cu")
		(net 503)
	)
	(via
		(at 205 119)
		(size 0.45)
		(drill 0.2)
		(layers "F.Cu" "B.Cu")
		(net 503)
	)
	(segment
		(start 197.506252 92.05)
		(end 198.006252 91.55)
		(width 0.184)
		(layer "B.Cu")
		(net 503)
	)
	(segment
		(start 196.376252 92.05)
		(end 196.176252 91.85)
		(width 0.184)
		(layer "B.Cu")
		(net 503)
	)
	(segment
		(start 196.991252 92.05)
		(end 196.376252 92.05)
		(width 0.184)
		(layer "B.Cu")
		(net 503)
	)
	(segment
		(start 196.991252 92.05)
		(end 197.506252 92.05)
		(width 0.184)
		(layer "B.Cu")
		(net 503)
	)
	(segment
		(start 198.997612 103.02)
		(end 198.61 103.02)
		(width 0.1)
		(layer "In7.Cu")
		(net 503)
	)
	(segment
		(start 199.047612 103.82)
		(end 198.61 103.82)
		(width 0.1)
		(layer "In7.Cu")
		(net 503)
	)
	(segment
		(start 198.41 102.82)
		(end 198.41 102.77)
		(width 0.1)
		(layer "In7.Cu")
		(net 503)
	)
	(segment
		(start 200.52 101.31)
		(end 202.141252 99.688748)
		(width 0.1)
		(layer "In7.Cu")
		(net 503)
	)
	(segment
		(start 198.61 103.42)
		(end 198.997612 103.42)
		(width 0.1)
		(layer "In7.Cu")
		(net 503)
	)
	(segment
		(start 199.047612 104.62)
		(end 198.61 104.62)
		(width 0.1)
		(layer "In7.Cu")
		(net 503)
	)
	(segment
		(start 198.61 105.02)
		(end 199.047612 105.02)
		(width 0.1)
		(layer "In7.Cu")
		(net 503)
	)
	(segment
		(start 202.141252 97.181252)
		(end 201.31 96.35)
		(width 0.1)
		(layer "In7.Cu")
		(net 503)
	)
	(segment
		(start 201.31 96.35)
		(end 198.76 96.35)
		(width 0.1)
		(layer "In7.Cu")
		(net 503)
	)
	(segment
		(start 197.321583 92.05)
		(end 196.991252 92.05)
		(width 0.1)
		(layer "In7.Cu")
		(net 503)
	)
	(segment
		(start 198.41 102.53)
		(end 199.63 101.31)
		(width 0.1)
		(layer "In7.Cu")
		(net 503)
	)
	(segment
		(start 198.41 105.47)
		(end 198.41 105.22)
		(width 0.1)
		(layer "In7.Cu")
		(net 503)
	)
	(segment
		(start 201.91 108.97)
		(end 198.41 105.47)
		(width 0.1)
		(layer "In7.Cu")
		(net 503)
	)
	(segment
		(start 198.41 102.77)
		(end 198.41 102.53)
		(width 0.1)
		(layer "In7.Cu")
		(net 503)
	)
	(segment
		(start 199.63 101.31)
		(end 200.52 101.31)
		(width 0.1)
		(layer "In7.Cu")
		(net 503)
	)
	(segment
		(start 205 119)
		(end 204.6 118.6)
		(width 0.1)
		(layer "In7.Cu")
		(net 503)
	)
	(segment
		(start 198.61 104.22)
		(end 199.047612 104.22)
		(width 0.1)
		(layer "In7.Cu")
		(net 503)
	)
	(segment
		(start 198.36 95.95)
		(end 198.36 93.088417)
		(width 0.1)
		(layer "In7.Cu")
		(net 503)
	)
	(segment
		(start 201.91 110.41)
		(end 201.91 108.97)
		(width 0.1)
		(layer "In7.Cu")
		(net 503)
	)
	(segment
		(start 198.36 93.088417)
		(end 197.321583 92.05)
		(width 0.1)
		(layer "In7.Cu")
		(net 503)
	)
	(segment
		(start 202.141252 99.688748)
		(end 202.141252 97.181252)
		(width 0.1)
		(layer "In7.Cu")
		(net 503)
	)
	(segment
		(start 204.6 113.1)
		(end 201.91 110.41)
		(width 0.1)
		(layer "In7.Cu")
		(net 503)
	)
	(segment
		(start 204.6 118.6)
		(end 204.6 113.1)
		(width 0.1)
		(layer "In7.Cu")
		(net 503)
	)
	(segment
		(start 198.76 96.35)
		(end 198.36 95.95)
		(width 0.1)
		(layer "In7.Cu")
		(net 503)
	)
	(arc
		(start 199.247612 104.82)
		(mid 199.189033 104.678579)
		(end 199.047612 104.62)
		(width 0.1)
		(layer "In7.Cu")
		(net 503)
	)
	(arc
		(start 199.197612 103.22)
		(mid 199.139033 103.078579)
		(end 198.997612 103.02)
		(width 0.1)
		(layer "In7.Cu")
		(net 503)
	)
	(arc
		(start 199.047612 105.02)
		(mid 199.189033 104.961421)
		(end 199.247612 104.82)
		(width 0.1)
		(layer "In7.Cu")
		(net 503)
	)
	(arc
		(start 198.41 103.62)
		(mid 198.468579 103.478579)
		(end 198.61 103.42)
		(width 0.1)
		(layer "In7.Cu")
		(net 503)
	)
	(arc
		(start 198.61 103.02)
		(mid 198.468579 102.961421)
		(end 198.41 102.82)
		(width 0.1)
		(layer "In7.Cu")
		(net 503)
	)
	(arc
		(start 198.997612 103.42)
		(mid 199.139033 103.361421)
		(end 199.197612 103.22)
		(width 0.1)
		(layer "In7.Cu")
		(net 503)
	)
	(arc
		(start 199.247612 104.02)
		(mid 199.189033 103.878579)
		(end 199.047612 103.82)
		(width 0.1)
		(layer "In7.Cu")
		(net 503)
	)
	(arc
		(start 198.41 104.42)
		(mid 198.468579 104.278579)
		(end 198.61 104.22)
		(width 0.1)
		(layer "In7.Cu")
		(net 503)
	)
	(arc
		(start 198.61 103.82)
		(mid 198.468579 103.761421)
		(end 198.41 103.62)
		(width 0.1)
		(layer "In7.Cu")
		(net 503)
	)
	(arc
		(start 199.047612 104.22)
		(mid 199.189033 104.161421)
		(end 199.247612 104.02)
		(width 0.1)
		(layer "In7.Cu")
		(net 503)
	)
	(arc
		(start 198.61 104.62)
		(mid 198.468579 104.561421)
		(end 198.41 104.42)
		(width 0.1)
		(layer "In7.Cu")
		(net 503)
	)
	(arc
		(start 198.41 105.22)
		(mid 198.468579 105.078579)
		(end 198.61 105.02)
		(width 0.1)
		(layer "In7.Cu")
		(net 503)
	)
	(segment
		(start 198.022851 92.6)
		(end 197.341252 92.6)
		(width 0.182)
		(layer "F.Cu")
		(net 504)
	)
	(segment
		(start 197.341252 92.6)
		(end 197.291252 92.55)
		(width 0.182)
		(layer "F.Cu")
		(net 504)
	)
	(segment
		(start 204.5 120.5)
		(end 205 120)
		(width 0.256)
		(layer "F.Cu")
		(net 504)
	)
	(segment
		(start 205 120)
		(end 205 119.95)
		(width 0.256)
		(layer "F.Cu")
		(net 504)
	)
	(via
		(at 205 119.95)
		(size 0.45)
		(drill 0.2)
		(layers "F.Cu" "B.Cu")
		(net 504)
	)
	(via
		(at 197.291252 92.55)
		(size 0.45)
		(drill 0.2)
		(layers "F.Cu" "B.Cu")
		(net 504)
	)
	(segment
		(start 196.476252 92.55)
		(end 196.176252 92.85)
		(width 0.184)
		(layer "B.Cu")
		(net 504)
	)
	(segment
		(start 197.291252 92.55)
		(end 198.006252 92.55)
		(width 0.184)
		(layer "B.Cu")
		(net 504)
	)
	(segment
		(start 197.291252 92.55)
		(end 196.476252 92.55)
		(width 0.184)
		(layer "B.Cu")
		(net 504)
	)
	(segment
		(start 198.38 97.43)
		(end 197.866252 96.916252)
		(width 0.1)
		(layer "In7.Cu")
		(net 504)
	)
	(segment
		(start 199.195 97.205)
		(end 199.195 96.859592)
		(width 0.1)
		(layer "In7.Cu")
		(net 504)
	)
	(segment
		(start 198.52 97.43)
		(end 198.38 97.43)
		(width 0.1)
		(layer "In7.Cu")
		(net 504)
	)
	(segment
		(start 201.47 110.57)
		(end 201.47 108.96)
		(width 0.1)
		(layer "In7.Cu")
		(net 504)
	)
	(segment
		(start 204.375 113.475)
		(end 201.47 110.57)
		(width 0.1)
		(layer "In7.Cu")
		(net 504)
	)
	(segment
		(start 201.741252 99.648748)
		(end 201.741252 97.691252)
		(width 0.1)
		(layer "In7.Cu")
		(net 504)
	)
	(segment
		(start 199.51 101.01)
		(end 200.38 101.01)
		(width 0.1)
		(layer "In7.Cu")
		(net 504)
	)
	(segment
		(start 200.995 97.205)
		(end 200.995 96.859592)
		(width 0.1)
		(layer "In7.Cu")
		(net 504)
	)
	(segment
		(start 197.866252 93.125)
		(end 197.291252 92.55)
		(width 0.1)
		(layer "In7.Cu")
		(net 504)
	)
	(segment
		(start 200.38 101.01)
		(end 201.741252 99.648748)
		(width 0.1)
		(layer "In7.Cu")
		(net 504)
	)
	(segment
		(start 204.375 119.325)
		(end 204.375 113.475)
		(width 0.1)
		(layer "In7.Cu")
		(net 504)
	)
	(segment
		(start 200.095 97.205)
		(end 200.095 96.859592)
		(width 0.1)
		(layer "In7.Cu")
		(net 504)
	)
	(segment
		(start 201.48 97.43)
		(end 201.22 97.43)
		(width 0.1)
		(layer "In7.Cu")
		(net 504)
	)
	(segment
		(start 198 102.52)
		(end 199.51 101.01)
		(width 0.1)
		(layer "In7.Cu")
		(net 504)
	)
	(segment
		(start 199.645 96.859592)
		(end 199.645 97.205)
		(width 0.1)
		(layer "In7.Cu")
		(net 504)
	)
	(segment
		(start 198.745 96.859592)
		(end 198.745 97.205)
		(width 0.1)
		(layer "In7.Cu")
		(net 504)
	)
	(segment
		(start 201.47 108.96)
		(end 198 105.49)
		(width 0.1)
		(layer "In7.Cu")
		(net 504)
	)
	(segment
		(start 200.545 96.859592)
		(end 200.545 97.205)
		(width 0.1)
		(layer "In7.Cu")
		(net 504)
	)
	(segment
		(start 205 119.95)
		(end 204.375 119.325)
		(width 0.1)
		(layer "In7.Cu")
		(net 504)
	)
	(segment
		(start 198 105.49)
		(end 198 102.52)
		(width 0.1)
		(layer "In7.Cu")
		(net 504)
	)
	(segment
		(start 197.866252 96.916252)
		(end 197.866252 93.125)
		(width 0.1)
		(layer "In7.Cu")
		(net 504)
	)
	(segment
		(start 201.741252 97.691252)
		(end 201.48 97.43)
		(width 0.1)
		(layer "In7.Cu")
		(net 504)
	)
	(arc
		(start 199.195 96.859592)
		(mid 199.129099 96.700493)
		(end 198.97 96.634592)
		(width 0.1)
		(layer "In7.Cu")
		(net 504)
	)
	(arc
		(start 199.645 97.205)
		(mid 199.579099 97.364099)
		(end 199.42 97.43)
		(width 0.1)
		(layer "In7.Cu")
		(net 504)
	)
	(arc
		(start 199.87 96.634592)
		(mid 199.710901 96.700493)
		(end 199.645 96.859592)
		(width 0.1)
		(layer "In7.Cu")
		(net 504)
	)
	(arc
		(start 200.32 97.43)
		(mid 200.160901 97.364099)
		(end 200.095 97.205)
		(width 0.1)
		(layer "In7.Cu")
		(net 504)
	)
	(arc
		(start 201.22 97.43)
		(mid 201.060901 97.364099)
		(end 200.995 97.205)
		(width 0.1)
		(layer "In7.Cu")
		(net 504)
	)
	(arc
		(start 200.995 96.859592)
		(mid 200.929099 96.700493)
		(end 200.77 96.634592)
		(width 0.1)
		(layer "In7.Cu")
		(net 504)
	)
	(arc
		(start 198.97 96.634592)
		(mid 198.810901 96.700493)
		(end 198.745 96.859592)
		(width 0.1)
		(layer "In7.Cu")
		(net 504)
	)
	(arc
		(start 200.545 97.205)
		(mid 200.479099 97.364099)
		(end 200.32 97.43)
		(width 0.1)
		(layer "In7.Cu")
		(net 504)
	)
	(arc
		(start 200.77 96.634592)
		(mid 200.610901 96.700493)
		(end 200.545 96.859592)
		(width 0.1)
		(layer "In7.Cu")
		(net 504)
	)
	(arc
		(start 200.095 96.859592)
		(mid 200.029099 96.700493)
		(end 199.87 96.634592)
		(width 0.1)
		(layer "In7.Cu")
		(net 504)
	)
	(arc
		(start 199.42 97.43)
		(mid 199.260901 97.364099)
		(end 199.195 97.205)
		(width 0.1)
		(layer "In7.Cu")
		(net 504)
	)
	(arc
		(start 198.745 97.205)
		(mid 198.679099 97.364099)
		(end 198.52 97.43)
		(width 0.1)
		(layer "In7.Cu")
		(net 504)
	)
	(segment
		(start 197.341252 94.1)
		(end 197.291252 94.15)
		(width 0.182)
		(layer "F.Cu")
		(net 505)
	)
	(segment
		(start 200.5 118.5)
		(end 201 118)
		(width 0.256)
		(layer "F.Cu")
		(net 505)
	)
	(segment
		(start 198.022851 94.1)
		(end 197.341252 94.1)
		(width 0.182)
		(layer "F.Cu")
		(net 505)
	)
	(via
		(at 201 118)
		(size 0.45)
		(drill 0.2)
		(layers "F.Cu" "B.Cu")
		(net 505)
	)
	(via
		(at 197.291252 94.15)
		(size 0.45)
		(drill 0.2)
		(layers "F.Cu" "B.Cu")
		(net 505)
	)
	(segment
		(start 197.291252 94.15)
		(end 196.476252 94.15)
		(width 0.184)
		(layer "B.Cu")
		(net 505)
	)
	(segment
		(start 197.291252 94.15)
		(end 197.406252 94.15)
		(width 0.184)
		(layer "B.Cu")
		(net 505)
	)
	(segment
		(start 197.406252 94.15)
		(end 198.006252 93.55)
		(width 0.184)
		(layer "B.Cu")
		(net 505)
	)
	(segment
		(start 196.476252 94.15)
		(end 196.176252 93.85)
		(width 0.184)
		(layer "B.Cu")
		(net 505)
	)
	(segment
		(start 194.36 94.15)
		(end 194.93 94.15)
		(width 0.1)
		(layer "In7.Cu")
		(net 505)
	)
	(segment
		(start 195.155 93.925)
		(end 195.155 93.565039)
		(width 0.1)
		(layer "In7.Cu")
		(net 505)
	)
	(segment
		(start 193.14 95.37)
		(end 194.36 94.15)
		(width 0.1)
		(layer "In7.Cu")
		(net 505)
	)
	(segment
		(start 196.505 93.565039)
		(end 196.505 93.925)
		(width 0.1)
		(layer "In7.Cu")
		(net 505)
	)
	(segment
		(start 196.055 93.925)
		(end 196.055 93.565039)
		(width 0.1)
		(layer "In7.Cu")
		(net 505)
	)
	(segment
		(start 196.73 94.15)
		(end 196.78 94.15)
		(width 0.1)
		(layer "In7.Cu")
		(net 505)
	)
	(segment
		(start 195.605 93.565039)
		(end 195.605 93.925)
		(width 0.1)
		(layer "In7.Cu")
		(net 505)
	)
	(segment
		(start 201 118)
		(end 200.7 117.7)
		(width 0.1)
		(layer "In7.Cu")
		(net 505)
	)
	(segment
		(start 193.14 107.22)
		(end 193.14 95.37)
		(width 0.1)
		(layer "In7.Cu")
		(net 505)
	)
	(segment
		(start 200.7 114.78)
		(end 193.14 107.22)
		(width 0.1)
		(layer "In7.Cu")
		(net 505)
	)
	(segment
		(start 200.7 117.7)
		(end 200.7 114.78)
		(width 0.1)
		(layer "In7.Cu")
		(net 505)
	)
	(segment
		(start 196.78 94.15)
		(end 197.291252 94.15)
		(width 0.1)
		(layer "In7.Cu")
		(net 505)
	)
	(arc
		(start 195.155 93.565039)
		(mid 195.220901 93.40594)
		(end 195.38 93.340039)
		(width 0.1)
		(layer "In7.Cu")
		(net 505)
	)
	(arc
		(start 195.38 93.340039)
		(mid 195.539099 93.40594)
		(end 195.605 93.565039)
		(width 0.1)
		(layer "In7.Cu")
		(net 505)
	)
	(arc
		(start 196.055 93.565039)
		(mid 196.120901 93.40594)
		(end 196.28 93.340039)
		(width 0.1)
		(layer "In7.Cu")
		(net 505)
	)
	(arc
		(start 195.83 94.15)
		(mid 195.989099 94.084099)
		(end 196.055 93.925)
		(width 0.1)
		(layer "In7.Cu")
		(net 505)
	)
	(arc
		(start 194.93 94.15)
		(mid 195.089099 94.084099)
		(end 195.155 93.925)
		(width 0.1)
		(layer "In7.Cu")
		(net 505)
	)
	(arc
		(start 196.505 93.925)
		(mid 196.570901 94.084099)
		(end 196.73 94.15)
		(width 0.1)
		(layer "In7.Cu")
		(net 505)
	)
	(arc
		(start 196.28 93.340039)
		(mid 196.439099 93.40594)
		(end 196.505 93.565039)
		(width 0.1)
		(layer "In7.Cu")
		(net 505)
	)
	(arc
		(start 195.605 93.925)
		(mid 195.670901 94.084099)
		(end 195.83 94.15)
		(width 0.1)
		(layer "In7.Cu")
		(net 505)
	)
	(segment
		(start 201.5 121.5)
		(end 202.014406 120.985594)
		(width 0.256)
		(layer "F.Cu")
		(net 506)
	)
	(segment
		(start 198.022851 94.6)
		(end 197.041252 94.6)
		(width 0.182)
		(layer "F.Cu")
		(net 506)
	)
	(segment
		(start 202.014406 120.985594)
		(end 202.025 120.985594)
		(width 0.256)
		(layer "F.Cu")
		(net 506)
	)
	(segment
		(start 197.041252 94.6)
		(end 196.991252 94.65)
		(width 0.182)
		(layer "F.Cu")
		(net 506)
	)
	(via
		(at 202.025 120.985594)
		(size 0.45)
		(drill 0.2)
		(layers "F.Cu" "B.Cu")
		(net 506)
	)
	(via
		(at 196.991252 94.65)
		(size 0.45)
		(drill 0.2)
		(layers "F.Cu" "B.Cu")
		(net 506)
	)
	(segment
		(start 197.906252 94.65)
		(end 198.006252 94.55)
		(width 0.184)
		(layer "B.Cu")
		(net 506)
	)
	(segment
		(start 196.376252 94.65)
		(end 196.176252 94.85)
		(width 0.184)
		(layer "B.Cu")
		(net 506)
	)
	(segment
		(start 196.991252 94.65)
		(end 197.906252 94.65)
		(width 0.184)
		(layer "B.Cu")
		(net 506)
	)
	(segment
		(start 196.991252 94.65)
		(end 196.376252 94.65)
		(width 0.184)
		(layer "B.Cu")
		(net 506)
	)
	(segment
		(start 194.33 94.65)
		(end 196.05 94.65)
		(width 0.1)
		(layer "In7.Cu")
		(net 506)
	)
	(segment
		(start 201 117.4)
		(end 201 114.78)
		(width 0.1)
		(layer "In7.Cu")
		(net 506)
	)
	(segment
		(start 202.025 120.985594)
		(end 201.375 120.335594)
		(width 0.1)
		(layer "In7.Cu")
		(net 506)
	)
	(segment
		(start 201.375 117.775)
		(end 201 117.4)
		(width 0.1)
		(layer "In7.Cu")
		(net 506)
	)
	(segment
		(start 201 114.78)
		(end 195.474974 109.254975)
		(width 0.1)
		(layer "In7.Cu")
		(net 506)
	)
	(segment
		(start 195.474974 108.512512)
		(end 195.227488 108.760001)
		(width 0.1)
		(layer "In7.Cu")
		(net 506)
	)
	(segment
		(start 195.722462 108.512513)
		(end 195.722462 108.512512)
		(width 0.1)
		(layer "In7.Cu")
		(net 506)
	)
	(segment
		(start 194.98 108.76)
		(end 194.034974 107.814975)
		(width 0.1)
		(layer "In7.Cu")
		(net 506)
	)
	(segment
		(start 196.225 94.825)
		(end 196.225 95.126403)
		(width 0.1)
		(layer "In7.Cu")
		(net 506)
	)
	(segment
		(start 193.49 107.27)
		(end 193.49 95.49)
		(width 0.1)
		(layer "In7.Cu")
		(net 506)
	)
	(segment
		(start 193.49 95.49)
		(end 194.33 94.65)
		(width 0.1)
		(layer "In7.Cu")
		(net 506)
	)
	(segment
		(start 194.282461 107.319999)
		(end 194.282461 107.32)
		(width 0.1)
		(layer "In7.Cu")
		(net 506)
	)
	(segment
		(start 194.034974 107.567487)
		(end 194.282461 107.319999)
		(width 0.1)
		(layer "In7.Cu")
		(net 506)
	)
	(segment
		(start 195.722461 108.759999)
		(end 195.722461 108.76)
		(width 0.1)
		(layer "In7.Cu")
		(net 506)
	)
	(segment
		(start 196.75 94.65)
		(end 196.991252 94.65)
		(width 0.1)
		(layer "In7.Cu")
		(net 506)
	)
	(segment
		(start 193.54 107.32)
		(end 193.49 107.27)
		(width 0.1)
		(layer "In7.Cu")
		(net 506)
	)
	(segment
		(start 201.375 120.335594)
		(end 201.375 117.775)
		(width 0.1)
		(layer "In7.Cu")
		(net 506)
	)
	(segment
		(start 194.282462 107.072513)
		(end 194.282462 107.072512)
		(width 0.1)
		(layer "In7.Cu")
		(net 506)
	)
	(segment
		(start 196.575 95.126403)
		(end 196.575 94.825)
		(width 0.1)
		(layer "In7.Cu")
		(net 506)
	)
	(segment
		(start 195.474974 109.007487)
		(end 195.722461 108.759999)
		(width 0.1)
		(layer "In7.Cu")
		(net 506)
	)
	(segment
		(start 195.227488 108.760001)
		(end 195.227487 108.759999)
		(width 0.1)
		(layer "In7.Cu")
		(net 506)
	)
	(segment
		(start 194.034974 107.072512)
		(end 193.787488 107.320001)
		(width 0.1)
		(layer "In7.Cu")
		(net 506)
	)
	(segment
		(start 193.787488 107.320001)
		(end 193.787487 107.319999)
		(width 0.1)
		(layer "In7.Cu")
		(net 506)
	)
	(arc
		(start 196.225 95.126403)
		(mid 196.276256 95.250147)
		(end 196.4 95.301403)
		(width 0.1)
		(layer "In7.Cu")
		(net 506)
	)
	(arc
		(start 195.474974 109.254975)
		(mid 195.423718 109.131231)
		(end 195.474974 109.007487)
		(width 0.1)
		(layer "In7.Cu")
		(net 506)
	)
	(arc
		(start 196.575 94.825)
		(mid 196.626256 94.701256)
		(end 196.75 94.65)
		(width 0.1)
		(layer "In7.Cu")
		(net 506)
	)
	(arc
		(start 194.282461 107.32)
		(mid 194.333718 107.196257)
		(end 194.282462 107.072513)
		(width 0.1)
		(layer "In7.Cu")
		(net 506)
	)
	(arc
		(start 196.4 95.301403)
		(mid 196.523744 95.250147)
		(end 196.575 95.126403)
		(width 0.1)
		(layer "In7.Cu")
		(net 506)
	)
	(arc
		(start 193.787487 107.319999)
		(mid 193.663744 107.371256)
		(end 193.54 107.32)
		(width 0.1)
		(layer "In7.Cu")
		(net 506)
	)
	(arc
		(start 195.227487 108.759999)
		(mid 195.103744 108.811256)
		(end 194.98 108.76)
		(width 0.1)
		(layer "In7.Cu")
		(net 506)
	)
	(arc
		(start 196.05 94.65)
		(mid 196.173744 94.701256)
		(end 196.225 94.825)
		(width 0.1)
		(layer "In7.Cu")
		(net 506)
	)
	(arc
		(start 194.034974 107.814975)
		(mid 193.983718 107.691231)
		(end 194.034974 107.567487)
		(width 0.1)
		(layer "In7.Cu")
		(net 506)
	)
	(arc
		(start 195.722461 108.76)
		(mid 195.773718 108.636257)
		(end 195.722462 108.512513)
		(width 0.1)
		(layer "In7.Cu")
		(net 506)
	)
	(arc
		(start 195.722462 108.512512)
		(mid 195.598718 108.461256)
		(end 195.474974 108.512512)
		(width 0.1)
		(layer "In7.Cu")
		(net 506)
	)
	(arc
		(start 194.282462 107.072512)
		(mid 194.158718 107.021256)
		(end 194.034974 107.072512)
		(width 0.1)
		(layer "In7.Cu")
		(net 506)
	)
	(segment
		(start 201.5 118.5)
		(end 202 118)
		(width 0.256)
		(layer "F.Cu")
		(net 507)
	)
	(segment
		(start 197.341252 96.1)
		(end 197.291252 96.15)
		(width 0.184)
		(layer "F.Cu")
		(net 507)
	)
	(segment
		(start 198.022851 96.1)
		(end 197.341252 96.1)
		(width 0.184)
		(layer "F.Cu")
		(net 507)
	)
	(via
		(at 197.291252 96.15)
		(size 0.45)
		(drill 0.2)
		(layers "F.Cu" "B.Cu")
		(net 507)
	)
	(via
		(at 202 118)
		(size 0.45)
		(drill 0.2)
		(layers "F.Cu" "B.Cu")
		(net 507)
	)
	(segment
		(start 196.176252 97.85)
		(end 196.176252 96.85)
		(width 0.184)
		(layer "B.Cu")
		(net 507)
	)
	(segment
		(start 196.876252 96.15)
		(end 196.176252 96.85)
		(width 0.184)
		(layer "B.Cu")
		(net 507)
	)
	(segment
		(start 197.291252 96.15)
		(end 196.876252 96.15)
		(width 0.184)
		(layer "B.Cu")
		(net 507)
	)
	(segment
		(start 202 118)
		(end 201.84 117.84)
		(width 0.1)
		(layer "In7.Cu")
		(net 507)
	)
	(segment
		(start 198.581369 110.778527)
		(end 198.581368 110.778526)
		(width 0.1)
		(layer "In7.Cu")
		(net 507)
	)
	(segment
		(start 197.909618 110.955304)
		(end 197.909617 110.955303)
		(width 0.1)
		(layer "In7.Cu")
		(net 507)
	)
	(segment
		(start 197.662131 110.46033)
		(end 197.662131 110.460329)
		(width 0.1)
		(layer "In7.Cu")
		(net 507)
	)
	(segment
		(start 197.838907 110.283553)
		(end 197.662131 110.46033)
		(width 0.1)
		(layer "In7.Cu")
		(net 507)
	)
	(segment
		(start 201.84 117.84)
		(end 201.84 117.53)
		(width 0.1)
		(layer "In7.Cu")
		(net 507)
	)
	(segment
		(start 196.15 97.12)
		(end 197.12 97.12)
		(width 0.1)
		(layer "In7.Cu")
		(net 507)
	)
	(segment
		(start 201.056239 113.253397)
		(end 201.056238 113.253396)
		(width 0.1)
		(layer "In7.Cu")
		(net 507)
	)
	(segment
		(start 197.591421 109.788579)
		(end 194.31 106.507158)
		(width 0.1)
		(layer "In7.Cu")
		(net 507)
	)
	(segment
		(start 200.561265 112.758423)
		(end 200.561264 112.758422)
		(width 0.1)
		(layer "In7.Cu")
		(net 507)
	)
	(segment
		(start 199.323829 111.768475)
		(end 199.147053 111.945252)
		(width 0.1)
		(layer "In7.Cu")
		(net 507)
	)
	(segment
		(start 199.818803 112.263449)
		(end 199.642027 112.440226)
		(width 0.1)
		(layer "In7.Cu")
		(net 507)
	)
	(segment
		(start 198.899566 111.697764)
		(end 199.076343 111.520988)
		(width 0.1)
		(layer "In7.Cu")
		(net 507)
	)
	(segment
		(start 198.157105 110.955304)
		(end 198.157105 110.955303)
		(width 0.1)
		(layer "In7.Cu")
		(net 507)
	)
	(segment
		(start 198.404592 111.20279)
		(end 198.581369 111.026014)
		(width 0.1)
		(layer "In7.Cu")
		(net 507)
	)
	(segment
		(start 195.225 97.762158)
		(end 195.075493 97.612651)
		(width 0.1)
		(layer "In7.Cu")
		(net 507)
	)
	(segment
		(start 195.790687 97.479316)
		(end 196.15 97.12)
		(width 0.1)
		(layer "In7.Cu")
		(net 507)
	)
	(segment
		(start 199.889514 112.9352)
		(end 199.889513 112.935199)
		(width 0.1)
		(layer "In7.Cu")
		(net 507)
	)
	(segment
		(start 199.39454 112.192738)
		(end 199.571317 112.015962)
		(width 0.1)
		(layer "In7.Cu")
		(net 507)
	)
	(segment
		(start 200.561265 113.00591)
		(end 200.561264 113.00591)
		(width 0.1)
		(layer "In7.Cu")
		(net 507)
	)
	(segment
		(start 197.43 96.288748)
		(end 197.291252 96.15)
		(width 0.1)
		(layer "In7.Cu")
		(net 507)
	)
	(segment
		(start 199.147053 111.945252)
		(end 199.147053 111.945251)
		(width 0.1)
		(layer "In7.Cu")
		(net 507)
	)
	(segment
		(start 200.137001 112.9352)
		(end 200.137001 112.935199)
		(width 0.1)
		(layer "In7.Cu")
		(net 507)
	)
	(segment
		(start 197.12 97.12)
		(end 197.43 96.81)
		(width 0.1)
		(layer "In7.Cu")
		(net 507)
	)
	(segment
		(start 201.69 113.890551)
		(end 201.516816 113.717367)
		(width 0.1)
		(layer "In7.Cu")
		(net 507)
	)
	(segment
		(start 197.43 96.81)
		(end 197.43 96.288748)
		(width 0.1)
		(layer "In7.Cu")
		(net 507)
	)
	(segment
		(start 200.313777 112.758423)
		(end 200.137001 112.9352)
		(width 0.1)
		(layer "In7.Cu")
		(net 507)
	)
	(segment
		(start 200.384488 113.430174)
		(end 200.384487 113.430173)
		(width 0.1)
		(layer "In7.Cu")
		(net 507)
	)
	(segment
		(start 195.790688 97.479315)
		(end 195.790687 97.479316)
		(width 0.1)
		(layer "In7.Cu")
		(net 507)
	)
	(segment
		(start 198.828855 111.273501)
		(end 198.652079 111.450278)
		(width 0.1)
		(layer "In7.Cu")
		(net 507)
	)
	(segment
		(start 200.879462 113.925148)
		(end 200.879461 113.925147)
		(width 0.1)
		(layer "In7.Cu")
		(net 507)
	)
	(segment
		(start 198.581369 111.026014)
		(end 198.581368 111.026014)
		(width 0.1)
		(layer "In7.Cu")
		(net 507)
	)
	(segment
		(start 197.591421 110.036066)
		(end 197.59142 110.036066)
		(width 0.1)
		(layer "In7.Cu")
		(net 507)
	)
	(segment
		(start 195.358337 97.329809)
		(end 195.358337 97.329808)
		(width 0.1)
		(layer "In7.Cu")
		(net 507)
	)
	(segment
		(start 198.652079 111.450278)
		(end 198.652079 111.450277)
		(width 0.1)
		(layer "In7.Cu")
		(net 507)
	)
	(segment
		(start 199.571317 111.768475)
		(end 199.571316 111.768474)
		(width 0.1)
		(layer "In7.Cu")
		(net 507)
	)
	(segment
		(start 195.075494 97.329808)
		(end 195.075493 97.329809)
		(width 0.1)
		(layer "In7.Cu")
		(net 507)
	)
	(segment
		(start 197.414644 110.46033)
		(end 197.414643 110.460329)
		(width 0.1)
		(layer "In7.Cu")
		(net 507)
	)
	(segment
		(start 199.39454 112.440226)
		(end 199.394539 112.440225)
		(width 0.1)
		(layer "In7.Cu")
		(net 507)
	)
	(segment
		(start 198.333881 110.778527)
		(end 198.157105 110.955304)
		(width 0.1)
		(layer "In7.Cu")
		(net 507)
	)
	(segment
		(start 201.303725 113.748371)
		(end 201.126949 113.925148)
		(width 0.1)
		(layer "In7.Cu")
		(net 507)
	)
	(segment
		(start 201.056239 113.500884)
		(end 201.056238 113.500884)
		(width 0.1)
		(layer "In7.Cu")
		(net 507)
	)
	(segment
		(start 199.889514 112.687712)
		(end 200.066291 112.510936)
		(width 0.1)
		(layer "In7.Cu")
		(net 507)
	)
	(segment
		(start 200.066291 112.510936)
		(end 200.06629 112.510936)
		(width 0.1)
		(layer "In7.Cu")
		(net 507)
	)
	(segment
		(start 200.384488 113.182686)
		(end 200.561265 113.00591)
		(width 0.1)
		(layer "In7.Cu")
		(net 507)
	)
	(segment
		(start 198.086395 110.53104)
		(end 198.086394 110.53104)
		(width 0.1)
		(layer "In7.Cu")
		(net 507)
	)
	(segment
		(start 197.414644 110.212842)
		(end 197.591421 110.036066)
		(width 0.1)
		(layer "In7.Cu")
		(net 507)
	)
	(segment
		(start 200.631975 113.430174)
		(end 200.631975 113.430173)
		(width 0.1)
		(layer "In7.Cu")
		(net 507)
	)
	(segment
		(start 198.404592 111.450278)
		(end 198.404591 111.450277)
		(width 0.1)
		(layer "In7.Cu")
		(net 507)
	)
	(segment
		(start 198.899566 111.945252)
		(end 198.899565 111.945251)
		(width 0.1)
		(layer "In7.Cu")
		(net 507)
	)
	(segment
		(start 200.808751 113.253397)
		(end 200.631975 113.430174)
		(width 0.1)
		(layer "In7.Cu")
		(net 507)
	)
	(segment
		(start 199.571317 112.015962)
		(end 199.571316 112.015962)
		(width 0.1)
		(layer "In7.Cu")
		(net 507)
	)
	(segment
		(start 195.358337 97.329808)
		(end 195.507845 97.479316)
		(width 0.1)
		(layer "In7.Cu")
		(net 507)
	)
	(segment
		(start 194.31 98.96)
		(end 195.225 98.045)
		(width 0.1)
		(layer "In7.Cu")
		(net 507)
	)
	(segment
		(start 199.076343 111.520988)
		(end 199.076342 111.520988)
		(width 0.1)
		(layer "In7.Cu")
		(net 507)
	)
	(segment
		(start 197.909618 110.707816)
		(end 198.086395 110.53104)
		(width 0.1)
		(layer "In7.Cu")
		(net 507)
	)
	(segment
		(start 199.642027 112.440226)
		(end 199.642027 112.440225)
		(width 0.1)
		(layer "In7.Cu")
		(net 507)
	)
	(segment
		(start 201.126949 113.925148)
		(end 201.126949 113.925147)
		(width 0.1)
		(layer "In7.Cu")
		(net 507)
	)
	(segment
		(start 198.086395 110.283553)
		(end 198.086394 110.283552)
		(width 0.1)
		(layer "In7.Cu")
		(net 507)
	)
	(segment
		(start 201.69 117.38)
		(end 201.69 113.890551)
		(width 0.1)
		(layer "In7.Cu")
		(net 507)
	)
	(segment
		(start 200.879462 113.67766)
		(end 201.056239 113.500884)
		(width 0.1)
		(layer "In7.Cu")
		(net 507)
	)
	(segment
		(start 199.076343 111.273501)
		(end 199.076342 111.2735)
		(width 0.1)
		(layer "In7.Cu")
		(net 507)
	)
	(segment
		(start 194.31 106.507158)
		(end 194.31 98.96)
		(width 0.1)
		(layer "In7.Cu")
		(net 507)
	)
	(segment
		(start 201.84 117.53)
		(end 201.69 117.38)
		(width 0.1)
		(layer "In7.Cu")
		(net 507)
	)
	(segment
		(start 200.066291 112.263449)
		(end 200.06629 112.263448)
		(width 0.1)
		(layer "In7.Cu")
		(net 507)
	)
	(arc
		(start 198.086394 110.53104)
		(mid 198.137651 110.407297)
		(end 198.086395 110.283553)
		(width 0.1)
		(layer "In7.Cu")
		(net 507)
	)
	(arc
		(start 200.06629 112.510936)
		(mid 200.117547 112.387193)
		(end 200.066291 112.263449)
		(width 0.1)
		(layer "In7.Cu")
		(net 507)
	)
	(arc
		(start 199.076342 111.2735)
		(mid 198.952598 111.222244)
		(end 198.828855 111.273501)
		(width 0.1)
		(layer "In7.Cu")
		(net 507)
	)
	(arc
		(start 200.137001 112.935199)
		(mid 200.013258 112.986456)
		(end 199.889514 112.9352)
		(width 0.1)
		(layer "In7.Cu")
		(net 507)
	)
	(arc
		(start 198.581368 110.778526)
		(mid 198.457624 110.72727)
		(end 198.333881 110.778527)
		(width 0.1)
		(layer "In7.Cu")
		(net 507)
	)
	(arc
		(start 195.075493 97.329809)
		(mid 195.216916 97.271229)
		(end 195.358337 97.329809)
		(width 0.1)
		(layer "In7.Cu")
		(net 507)
	)
	(arc
		(start 201.126949 113.925147)
		(mid 201.003206 113.976404)
		(end 200.879462 113.925148)
		(width 0.1)
		(layer "In7.Cu")
		(net 507)
	)
	(arc
		(start 199.076342 111.520988)
		(mid 199.127599 111.397245)
		(end 199.076343 111.273501)
		(width 0.1)
		(layer "In7.Cu")
		(net 507)
	)
	(arc
		(start 201.516816 113.717367)
		(mid 201.404632 113.698589)
		(end 201.303725 113.748371)
		(width 0.1)
		(layer "In7.Cu")
		(net 507)
	)
	(arc
		(start 195.507845 97.479316)
		(mid 195.649267 97.537894)
		(end 195.790688 97.479315)
		(width 0.1)
		(layer "In7.Cu")
		(net 507)
	)
	(arc
		(start 198.157105 110.955303)
		(mid 198.033362 111.00656)
		(end 197.909618 110.955304)
		(width 0.1)
		(layer "In7.Cu")
		(net 507)
	)
	(arc
		(start 199.394539 112.440225)
		(mid 199.343283 112.316481)
		(end 199.39454 112.192738)
		(width 0.1)
		(layer "In7.Cu")
		(net 507)
	)
	(arc
		(start 200.561264 113.00591)
		(mid 200.612521 112.882167)
		(end 200.561265 112.758423)
		(width 0.1)
		(layer "In7.Cu")
		(net 507)
	)
	(arc
		(start 197.414643 110.460329)
		(mid 197.363387 110.336585)
		(end 197.414644 110.212842)
		(width 0.1)
		(layer "In7.Cu")
		(net 507)
	)
	(arc
		(start 199.889513 112.935199)
		(mid 199.838257 112.811455)
		(end 199.889514 112.687712)
		(width 0.1)
		(layer "In7.Cu")
		(net 507)
	)
	(arc
		(start 200.384487 113.430173)
		(mid 200.333231 113.306429)
		(end 200.384488 113.182686)
		(width 0.1)
		(layer "In7.Cu")
		(net 507)
	)
	(arc
		(start 199.571316 112.015962)
		(mid 199.622573 111.892219)
		(end 199.571317 111.768475)
		(width 0.1)
		(layer "In7.Cu")
		(net 507)
	)
	(arc
		(start 200.06629 112.263448)
		(mid 199.942546 112.212192)
		(end 199.818803 112.263449)
		(width 0.1)
		(layer "In7.Cu")
		(net 507)
	)
	(arc
		(start 199.571316 111.768474)
		(mid 199.447572 111.717218)
		(end 199.323829 111.768475)
		(width 0.1)
		(layer "In7.Cu")
		(net 507)
	)
	(arc
		(start 197.59142 110.036066)
		(mid 197.642677 109.912323)
		(end 197.591421 109.788579)
		(width 0.1)
		(layer "In7.Cu")
		(net 507)
	)
	(arc
		(start 198.652079 111.450277)
		(mid 198.528336 111.501534)
		(end 198.404592 111.450278)
		(width 0.1)
		(layer "In7.Cu")
		(net 507)
	)
	(arc
		(start 195.225 98.045)
		(mid 195.283579 97.903578)
		(end 195.225 97.762158)
		(width 0.1)
		(layer "In7.Cu")
		(net 507)
	)
	(arc
		(start 198.086394 110.283552)
		(mid 197.96265 110.232296)
		(end 197.838907 110.283553)
		(width 0.1)
		(layer "In7.Cu")
		(net 507)
	)
	(arc
		(start 197.909617 110.955303)
		(mid 197.858361 110.831559)
		(end 197.909618 110.707816)
		(width 0.1)
		(layer "In7.Cu")
		(net 507)
	)
	(arc
		(start 200.561264 112.758422)
		(mid 200.43752 112.707166)
		(end 200.313777 112.758423)
		(width 0.1)
		(layer "In7.Cu")
		(net 507)
	)
	(arc
		(start 195.075493 97.612651)
		(mid 195.016915 97.471229)
		(end 195.075494 97.329808)
		(width 0.1)
		(layer "In7.Cu")
		(net 507)
	)
	(arc
		(start 198.404591 111.450277)
		(mid 198.353335 111.326533)
		(end 198.404592 111.20279)
		(width 0.1)
		(layer "In7.Cu")
		(net 507)
	)
	(arc
		(start 197.662131 110.460329)
		(mid 197.538388 110.511586)
		(end 197.414644 110.46033)
		(width 0.1)
		(layer "In7.Cu")
		(net 507)
	)
	(arc
		(start 200.879461 113.925147)
		(mid 200.828205 113.801403)
		(end 200.879462 113.67766)
		(width 0.1)
		(layer "In7.Cu")
		(net 507)
	)
	(arc
		(start 199.147053 111.945251)
		(mid 199.02331 111.996508)
		(end 198.899566 111.945252)
		(width 0.1)
		(layer "In7.Cu")
		(net 507)
	)
	(arc
		(start 198.581368 111.026014)
		(mid 198.632625 110.902271)
		(end 198.581369 110.778527)
		(width 0.1)
		(layer "In7.Cu")
		(net 507)
	)
	(arc
		(start 201.056238 113.253396)
		(mid 200.932494 113.20214)
		(end 200.808751 113.253397)
		(width 0.1)
		(layer "In7.Cu")
		(net 507)
	)
	(arc
		(start 201.056238 113.500884)
		(mid 201.107495 113.377141)
		(end 201.056239 113.253397)
		(width 0.1)
		(layer "In7.Cu")
		(net 507)
	)
	(arc
		(start 200.631975 113.430173)
		(mid 200.508232 113.48143)
		(end 200.384488 113.430174)
		(width 0.1)
		(layer "In7.Cu")
		(net 507)
	)
	(arc
		(start 199.642027 112.440225)
		(mid 199.518284 112.491482)
		(end 199.39454 112.440226)
		(width 0.1)
		(layer "In7.Cu")
		(net 507)
	)
	(arc
		(start 198.899565 111.945251)
		(mid 198.848309 111.821507)
		(end 198.899566 111.697764)
		(width 0.1)
		(layer "In7.Cu")
		(net 507)
	)
	(segment
		(start 199.2 97.841252)
		(end 199.2 97.277149)
		(width 0.184)
		(layer "F.Cu")
		(net 508)
	)
	(segment
		(start 198.891252 98.15)
		(end 199.2 97.841252)
		(width 0.184)
		(layer "F.Cu")
		(net 508)
	)
	(segment
		(start 202.5 120.5)
		(end 203 120)
		(width 0.256)
		(layer "F.Cu")
		(net 508)
	)
	(via
		(at 203 120)
		(size 0.45)
		(drill 0.2)
		(layers "F.Cu" "B.Cu")
		(net 508)
	)
	(via
		(at 198.891252 98.15)
		(size 0.45)
		(drill 0.2)
		(layers "F.Cu" "B.Cu")
		(net 508)
	)
	(segment
		(start 198.891252 97.535)
		(end 198.991252 97.435)
		(width 0.184)
		(layer "B.Cu")
		(net 508)
	)
	(segment
		(start 198.891252 98.15)
		(end 198.891252 97.535)
		(width 0.184)
		(layer "B.Cu")
		(net 508)
	)
	(segment
		(start 198.891252 98.665)
		(end 198.991252 98.765)
		(width 0.184)
		(layer "B.Cu")
		(net 508)
	)
	(segment
		(start 198.891252 98.15)
		(end 198.891252 98.665)
		(width 0.184)
		(layer "B.Cu")
		(net 508)
	)
	(segment
		(start 200.156337 110.71006)
		(end 200.156338 110.710059)
		(width 0.1)
		(layer "In7.Cu")
		(net 508)
	)
	(segment
		(start 203.375 119.625)
		(end 203 120)
		(width 0.1)
		(layer "In7.Cu")
		(net 508)
	)
	(segment
		(start 199.927132 110.515)
		(end 199.944206 110.497927)
		(width 0.1)
		(layer "In7.Cu")
		(net 508)
	)
	(segment
		(start 197.784008 107.311215)
		(end 197.784009 107.311216)
		(width 0.1)
		(layer "In7.Cu")
		(net 508)
	)
	(segment
		(start 197.147611 107.700123)
		(end 197.53652 107.311215)
		(width 0.1)
		(layer "In7.Cu")
		(net 508)
	)
	(segment
		(start 197.3951 107.947612)
		(end 197.395099 107.947613)
		(width 0.1)
		(layer "In7.Cu")
		(net 508)
	)
	(segment
		(start 199.375 109.927512)
		(end 199.374999 109.927513)
		(width 0.1)
		(layer "In7.Cu")
		(net 508)
	)
	(segment
		(start 202.7 114.4)
		(end 202.7 116)
		(width 0.1)
		(layer "In7.Cu")
		(net 508)
	)
	(segment
		(start 198.031495 107.80619)
		(end 198.031496 107.806189)
		(width 0.1)
		(layer "In7.Cu")
		(net 508)
	)
	(segment
		(start 197.890073 108.690073)
		(end 197.890074 108.690074)
		(width 0.1)
		(layer "In7.Cu")
		(net 508)
	)
	(segment
		(start 199.268933 109.043628)
		(end 198.880025 109.432537)
		(width 0.1)
		(layer "In7.Cu")
		(net 508)
	)
	(segment
		(start 198.773958 108.301165)
		(end 198.773959 108.301166)
		(width 0.1)
		(layer "In7.Cu")
		(net 508)
	)
	(segment
		(start 202.89 114.21)
		(end 202.7 114.4)
		(width 0.1)
		(layer "In7.Cu")
		(net 508)
	)
	(segment
		(start 199.375 110.175)
		(end 199.715 110.515)
		(width 0.1)
		(layer "In7.Cu")
		(net 508)
	)
	(segment
		(start 198.773958 108.548653)
		(end 198.38505 108.937562)
		(width 0.1)
		(layer "In7.Cu")
		(net 508)
	)
	(segment
		(start 198.278983 108.053678)
		(end 197.890075 108.442587)
		(width 0.1)
		(layer "In7.Cu")
		(net 508)
	)
	(segment
		(start 197.784008 107.558703)
		(end 197.3951 107.947612)
		(width 0.1)
		(layer "In7.Cu")
		(net 508)
	)
	(segment
		(start 197.642586 108.195098)
		(end 198.031495 107.80619)
		(width 0.1)
		(layer "In7.Cu")
		(net 508)
	)
	(segment
		(start 198.52647 108.301165)
		(end 198.526471 108.301164)
		(width 0.1)
		(layer "In7.Cu")
		(net 508)
	)
	(segment
		(start 197.289033 107.063728)
		(end 196.900125 107.452637)
		(width 0.1)
		(layer "In7.Cu")
		(net 508)
	)
	(segment
		(start 197.289033 106.81624)
		(end 197.289034 106.816241)
		(width 0.1)
		(layer "In7.Cu")
		(net 508)
	)
	(segment
		(start 197.890075 108.442587)
		(end 197.890074 108.442588)
		(width 0.1)
		(layer "In7.Cu")
		(net 508)
	)
	(segment
		(start 199.127511 109.680023)
		(end 199.51642 109.291115)
		(width 0.1)
		(layer "In7.Cu")
		(net 508)
	)
	(segment
		(start 198.278983 107.80619)
		(end 198.278984 107.806191)
		(width 0.1)
		(layer "In7.Cu")
		(net 508)
	)
	(segment
		(start 197.3951 108.1951)
		(end 197.395098 108.195098)
		(width 0.1)
		(layer "In7.Cu")
		(net 508)
	)
	(segment
		(start 197.395098 108.195098)
		(end 197.395099 108.195099)
		(width 0.1)
		(layer "In7.Cu")
		(net 508)
	)
	(segment
		(start 198.891252 98.15)
		(end 196.24 100.801252)
		(width 0.1)
		(layer "In7.Cu")
		(net 508)
	)
	(segment
		(start 197.890075 108.690075)
		(end 197.890073 108.690073)
		(width 0.1)
		(layer "In7.Cu")
		(net 508)
	)
	(segment
		(start 196.24 100.801252)
		(end 196.24 107.04)
		(width 0.1)
		(layer "In7.Cu")
		(net 508)
	)
	(segment
		(start 198.880025 109.680025)
		(end 198.880023 109.680023)
		(width 0.1)
		(layer "In7.Cu")
		(net 508)
	)
	(segment
		(start 203.375 116.675)
		(end 203.375 119.625)
		(width 0.1)
		(layer "In7.Cu")
		(net 508)
	)
	(segment
		(start 198.385048 109.185048)
		(end 198.385049 109.185049)
		(width 0.1)
		(layer "In7.Cu")
		(net 508)
	)
	(segment
		(start 198.38505 108.937562)
		(end 198.385049 108.937563)
		(width 0.1)
		(layer "In7.Cu")
		(net 508)
	)
	(segment
		(start 199.927133 110.514999)
		(end 199.927132 110.515)
		(width 0.1)
		(layer "In7.Cu")
		(net 508)
	)
	(segment
		(start 198.880025 109.432537)
		(end 198.880024 109.432538)
		(width 0.1)
		(layer "In7.Cu")
		(net 508)
	)
	(segment
		(start 196.900123 107.700123)
		(end 196.900124 107.700124)
		(width 0.1)
		(layer "In7.Cu")
		(net 508)
	)
	(segment
		(start 199.268933 108.79614)
		(end 199.268934 108.796141)
		(width 0.1)
		(layer "In7.Cu")
		(net 508)
	)
	(segment
		(start 198.880023 109.680023)
		(end 198.880024 109.680024)
		(width 0.1)
		(layer "In7.Cu")
		(net 508)
	)
	(segment
		(start 197.041545 106.81624)
		(end 197.041546 106.816239)
		(width 0.1)
		(layer "In7.Cu")
		(net 508)
	)
	(segment
		(start 199.763908 109.538603)
		(end 199.375 109.927512)
		(width 0.1)
		(layer "In7.Cu")
		(net 508)
	)
	(segment
		(start 196.24 107.04)
		(end 196.405149 107.205149)
		(width 0.1)
		(layer "In7.Cu")
		(net 508)
	)
	(segment
		(start 200.139264 110.939264)
		(end 202.89 113.69)
		(width 0.1)
		(layer "In7.Cu")
		(net 508)
	)
	(segment
		(start 202.7 116)
		(end 203.375 116.675)
		(width 0.1)
		(layer "In7.Cu")
		(net 508)
	)
	(segment
		(start 198.632536 109.185048)
		(end 199.021445 108.79614)
		(width 0.1)
		(layer "In7.Cu")
		(net 508)
	)
	(segment
		(start 200.139263 110.939263)
		(end 200.139264 110.939264)
		(width 0.1)
		(layer "In7.Cu")
		(net 508)
	)
	(segment
		(start 198.137561 108.690073)
		(end 198.52647 108.301165)
		(width 0.1)
		(layer "In7.Cu")
		(net 508)
	)
	(segment
		(start 199.51642 109.291115)
		(end 199.516421 109.291114)
		(width 0.1)
		(layer "In7.Cu")
		(net 508)
	)
	(segment
		(start 196.652636 107.205148)
		(end 197.041545 106.81624)
		(width 0.1)
		(layer "In7.Cu")
		(net 508)
	)
	(segment
		(start 200.156338 110.710059)
		(end 200.139263 110.727131)
		(width 0.1)
		(layer "In7.Cu")
		(net 508)
	)
	(segment
		(start 199.763908 109.291115)
		(end 199.763909 109.291116)
		(width 0.1)
		(layer "In7.Cu")
		(net 508)
	)
	(segment
		(start 196.900125 107.452637)
		(end 196.900124 107.452638)
		(width 0.1)
		(layer "In7.Cu")
		(net 508)
	)
	(segment
		(start 196.900125 107.700125)
		(end 196.900123 107.700123)
		(width 0.1)
		(layer "In7.Cu")
		(net 508)
	)
	(segment
		(start 202.89 113.69)
		(end 202.89 114.21)
		(width 0.1)
		(layer "In7.Cu")
		(net 508)
	)
	(segment
		(start 198.38505 109.18505)
		(end 198.385048 109.185048)
		(width 0.1)
		(layer "In7.Cu")
		(net 508)
	)
	(segment
		(start 199.021445 108.79614)
		(end 199.021446 108.796139)
		(width 0.1)
		(layer "In7.Cu")
		(net 508)
	)
	(segment
		(start 197.53652 107.311215)
		(end 197.536521 107.311214)
		(width 0.1)
		(layer "In7.Cu")
		(net 508)
	)
	(arc
		(start 198.880024 109.680024)
		(mid 199.003768 109.73128)
		(end 199.127511 109.680023)
		(width 0.1)
		(layer "In7.Cu")
		(net 508)
	)
	(arc
		(start 197.536521 107.311214)
		(mid 197.660265 107.259958)
		(end 197.784008 107.311215)
		(width 0.1)
		(layer "In7.Cu")
		(net 508)
	)
	(arc
		(start 199.021446 108.796139)
		(mid 199.14519 108.744883)
		(end 199.268933 108.79614)
		(width 0.1)
		(layer "In7.Cu")
		(net 508)
	)
	(arc
		(start 198.880024 109.432538)
		(mid 198.828768 109.556282)
		(end 198.880025 109.680025)
		(width 0.1)
		(layer "In7.Cu")
		(net 508)
	)
	(arc
		(start 197.890074 108.690074)
		(mid 198.013818 108.74133)
		(end 198.137561 108.690073)
		(width 0.1)
		(layer "In7.Cu")
		(net 508)
	)
	(arc
		(start 197.784009 107.311216)
		(mid 197.835265 107.43496)
		(end 197.784008 107.558703)
		(width 0.1)
		(layer "In7.Cu")
		(net 508)
	)
	(arc
		(start 199.944206 110.497927)
		(mid 200.050272 110.453993)
		(end 200.156338 110.497927)
		(width 0.1)
		(layer "In7.Cu")
		(net 508)
	)
	(arc
		(start 197.395099 108.195099)
		(mid 197.518843 108.246355)
		(end 197.642586 108.195098)
		(width 0.1)
		(layer "In7.Cu")
		(net 508)
	)
	(arc
		(start 198.526471 108.301164)
		(mid 198.650215 108.249908)
		(end 198.773958 108.301165)
		(width 0.1)
		(layer "In7.Cu")
		(net 508)
	)
	(arc
		(start 196.900124 107.452638)
		(mid 196.848868 107.576382)
		(end 196.900125 107.700125)
		(width 0.1)
		(layer "In7.Cu")
		(net 508)
	)
	(arc
		(start 197.041546 106.816239)
		(mid 197.16529 106.764983)
		(end 197.289033 106.81624)
		(width 0.1)
		(layer "In7.Cu")
		(net 508)
	)
	(arc
		(start 198.773959 108.301166)
		(mid 198.825215 108.42491)
		(end 198.773958 108.548653)
		(width 0.1)
		(layer "In7.Cu")
		(net 508)
	)
	(arc
		(start 199.516421 109.291114)
		(mid 199.640165 109.239858)
		(end 199.763908 109.291115)
		(width 0.1)
		(layer "In7.Cu")
		(net 508)
	)
	(arc
		(start 197.289034 106.816241)
		(mid 197.34029 106.939985)
		(end 197.289033 107.063728)
		(width 0.1)
		(layer "In7.Cu")
		(net 508)
	)
	(arc
		(start 198.385049 109.185049)
		(mid 198.508793 109.236305)
		(end 198.632536 109.185048)
		(width 0.1)
		(layer "In7.Cu")
		(net 508)
	)
	(arc
		(start 197.890074 108.442588)
		(mid 197.838818 108.566332)
		(end 197.890075 108.690075)
		(width 0.1)
		(layer "In7.Cu")
		(net 508)
	)
	(arc
		(start 196.900124 107.700124)
		(mid 197.023868 107.75138)
		(end 197.147611 107.700123)
		(width 0.1)
		(layer "In7.Cu")
		(net 508)
	)
	(arc
		(start 198.031496 107.806189)
		(mid 198.15524 107.754933)
		(end 198.278983 107.80619)
		(width 0.1)
		(layer "In7.Cu")
		(net 508)
	)
	(arc
		(start 197.395099 107.947613)
		(mid 197.343843 108.071357)
		(end 197.3951 108.1951)
		(width 0.1)
		(layer "In7.Cu")
		(net 508)
	)
	(arc
		(start 198.385049 108.937563)
		(mid 198.333793 109.061307)
		(end 198.38505 109.18505)
		(width 0.1)
		(layer "In7.Cu")
		(net 508)
	)
	(arc
		(start 199.374999 109.927513)
		(mid 199.323743 110.051257)
		(end 199.375 110.175)
		(width 0.1)
		(layer "In7.Cu")
		(net 508)
	)
	(arc
		(start 200.156338 110.497927)
		(mid 200.200271 110.603993)
		(end 200.156337 110.71006)
		(width 0.1)
		(layer "In7.Cu")
		(net 508)
	)
	(arc
		(start 200.139263 110.727131)
		(mid 200.095329 110.833197)
		(end 200.139263 110.939263)
		(width 0.1)
		(layer "In7.Cu")
		(net 508)
	)
	(arc
		(start 198.278984 107.806191)
		(mid 198.33024 107.929935)
		(end 198.278983 108.053678)
		(width 0.1)
		(layer "In7.Cu")
		(net 508)
	)
	(arc
		(start 199.715 110.515)
		(mid 199.821068 110.558935)
		(end 199.927133 110.514999)
		(width 0.1)
		(layer "In7.Cu")
		(net 508)
	)
	(arc
		(start 196.405149 107.205149)
		(mid 196.528893 107.256405)
		(end 196.652636 107.205148)
		(width 0.1)
		(layer "In7.Cu")
		(net 508)
	)
	(arc
		(start 199.268934 108.796141)
		(mid 199.32019 108.919885)
		(end 199.268933 109.043628)
		(width 0.1)
		(layer "In7.Cu")
		(net 508)
	)
	(arc
		(start 199.763909 109.291116)
		(mid 199.815165 109.41486)
		(end 199.763908 109.538603)
		(width 0.1)
		(layer "In7.Cu")
		(net 508)
	)
	(segment
		(start 197.341252 95.1)
		(end 197.291252 95.15)
		(width 0.182)
		(layer "F.Cu")
		(net 509)
	)
	(segment
		(start 202.5 119.5)
		(end 203 119)
		(width 0.256)
		(layer "F.Cu")
		(net 509)
	)
	(segment
		(start 198.022851 95.1)
		(end 197.341252 95.1)
		(width 0.182)
		(layer "F.Cu")
		(net 509)
	)
	(via
		(at 203 119)
		(size 0.45)
		(drill 0.2)
		(layers "F.Cu" "B.Cu")
		(net 509)
	)
	(via
		(at 197.291252 95.15)
		(size 0.45)
		(drill 0.2)
		(layers "F.Cu" "B.Cu")
		(net 509)
	)
	(segment
		(start 197.691252 95.55)
		(end 197.291252 95.15)
		(width 0.184)
		(layer "B.Cu")
		(net 509)
	)
	(segment
		(start 196.591252 95.85)
		(end 197.291252 95.15)
		(width 0.184)
		(layer "B.Cu")
		(net 509)
	)
	(segment
		(start 198.006252 95.55)
		(end 197.691252 95.55)
		(width 0.184)
		(layer "B.Cu")
		(net 509)
	)
	(segment
		(start 196.176252 95.85)
		(end 196.591252 95.85)
		(width 0.184)
		(layer "B.Cu")
		(net 509)
	)
	(segment
		(start 196.021047 97.988681)
		(end 196.372441 98.340075)
		(width 0.1)
		(layer "In7.Cu")
		(net 509)
	)
	(segment
		(start 202.5 117.9)
		(end 202.11 117.51)
		(width 0.1)
		(layer "In7.Cu")
		(net 509)
	)
	(segment
		(start 195.561428 98.519011)
		(end 195.877466 98.835049)
		(width 0.1)
		(layer "In7.Cu")
		(net 509)
	)
	(segment
		(start 196.55138 97.529059)
		(end 196.867418 97.845097)
		(width 0.1)
		(layer "In7.Cu")
		(net 509)
	)
	(segment
		(start 195.066452 99.013987)
		(end 195.38249 99.330025)
		(width 0.1)
		(layer "In7.Cu")
		(net 509)
	)
	(segment
		(start 203 119)
		(end 202.5 118.5)
		(width 0.1)
		(layer "In7.Cu")
		(net 509)
	)
	(segment
		(start 195.313939 98.519012)
		(end 195.31394 98.519011)
		(width 0.1)
		(layer "In7.Cu")
		(net 509)
	)
	(segment
		(start 195.135 99.577514)
		(end 195.135001 99.577512)
		(width 0.1)
		(layer "In7.Cu")
		(net 509)
	)
	(segment
		(start 195.629977 99.330026)
		(end 195.629978 99.330025)
		(width 0.1)
		(layer "In7.Cu")
		(net 509)
	)
	(segment
		(start 196.124953 98.83505)
		(end 196.124954 98.835049)
		(width 0.1)
		(layer "In7.Cu")
		(net 509)
	)
	(segment
		(start 195.135001 99.577512)
		(end 194.818964 99.261475)
		(width 0.1)
		(layer "In7.Cu")
		(net 509)
	)
	(segment
		(start 195.629978 99.330025)
		(end 195.629976 99.330024)
		(width 0.1)
		(layer "In7.Cu")
		(net 509)
	)
	(segment
		(start 196.619929 98.092584)
		(end 196.303892 97.776547)
		(width 0.1)
		(layer "In7.Cu")
		(net 509)
	)
	(segment
		(start 196.619929 98.340074)
		(end 196.619928 98.340072)
		(width 0.1)
		(layer "In7.Cu")
		(net 509)
	)
	(segment
		(start 202.11 117.51)
		(end 202.11 113.91)
		(width 0.1)
		(layer "In7.Cu")
		(net 509)
	)
	(segment
		(start 196.619928 98.092586)
		(end 196.619929 98.092584)
		(width 0.1)
		(layer "In7.Cu")
		(net 509)
	)
	(segment
		(start 194.81 100.15)
		(end 195.135 99.825)
		(width 0.1)
		(layer "In7.Cu")
		(net 509)
	)
	(segment
		(start 195.773561 97.98868)
		(end 195.773559 97.988681)
		(width 0.1)
		(layer "In7.Cu")
		(net 509)
	)
	(segment
		(start 197.114906 97.845097)
		(end 197.666252 97.293748)
		(width 0.1)
		(layer "In7.Cu")
		(net 509)
	)
	(segment
		(start 197.114905 97.845098)
		(end 197.114906 97.845097)
		(width 0.1)
		(layer "In7.Cu")
		(net 509)
	)
	(segment
		(start 197.666252 95.525)
		(end 197.291252 95.15)
		(width 0.1)
		(layer "In7.Cu")
		(net 509)
	)
	(segment
		(start 196.124954 98.835049)
		(end 196.124952 98.835048)
		(width 0.1)
		(layer "In7.Cu")
		(net 509)
	)
	(segment
		(start 196.124953 98.58756)
		(end 195.77356 98.236167)
		(width 0.1)
		(layer "In7.Cu")
		(net 509)
	)
	(segment
		(start 202.5 118.5)
		(end 202.5 117.9)
		(width 0.1)
		(layer "In7.Cu")
		(net 509)
	)
	(segment
		(start 196.303891 97.52906)
		(end 196.303892 97.529059)
		(width 0.1)
		(layer "In7.Cu")
		(net 509)
	)
	(segment
		(start 196.619928 98.340074)
		(end 196.619929 98.340074)
		(width 0.1)
		(layer "In7.Cu")
		(net 509)
	)
	(segment
		(start 194.81 106.61)
		(end 194.81 100.15)
		(width 0.1)
		(layer "In7.Cu")
		(net 509)
	)
	(segment
		(start 197.666252 97.293748)
		(end 197.666252 95.525)
		(width 0.1)
		(layer "In7.Cu")
		(net 509)
	)
	(segment
		(start 202.11 113.91)
		(end 194.81 106.61)
		(width 0.1)
		(layer "In7.Cu")
		(net 509)
	)
	(segment
		(start 194.818963 99.013988)
		(end 194.818964 99.013987)
		(width 0.1)
		(layer "In7.Cu")
		(net 509)
	)
	(segment
		(start 196.124952 98.587562)
		(end 196.124953 98.58756)
		(width 0.1)
		(layer "In7.Cu")
		(net 509)
	)
	(segment
		(start 195.629976 99.082538)
		(end 195.629977 99.082536)
		(width 0.1)
		(layer "In7.Cu")
		(net 509)
	)
	(segment
		(start 195.629977 99.082536)
		(end 195.31394 98.766499)
		(width 0.1)
		(layer "In7.Cu")
		(net 509)
	)
	(arc
		(start 195.629976 99.330024)
		(mid 195.681233 99.20628)
		(end 195.629976 99.082538)
		(width 0.1)
		(layer "In7.Cu")
		(net 509)
	)
	(arc
		(start 195.877466 98.835049)
		(mid 196.001209 98.886306)
		(end 196.124953 98.83505)
		(width 0.1)
		(layer "In7.Cu")
		(net 509)
	)
	(arc
		(start 195.31394 98.766499)
		(mid 195.262683 98.642756)
		(end 195.313939 98.519012)
		(width 0.1)
		(layer "In7.Cu")
		(net 509)
	)
	(arc
		(start 196.124952 98.835048)
		(mid 196.176209 98.711304)
		(end 196.124952 98.587562)
		(width 0.1)
		(layer "In7.Cu")
		(net 509)
	)
	(arc
		(start 195.135 99.825)
		(mid 195.186257 99.701256)
		(end 195.135 99.577514)
		(width 0.1)
		(layer "In7.Cu")
		(net 509)
	)
	(arc
		(start 196.372441 98.340075)
		(mid 196.496185 98.391331)
		(end 196.619928 98.340074)
		(width 0.1)
		(layer "In7.Cu")
		(net 509)
	)
	(arc
		(start 195.31394 98.519011)
		(mid 195.437684 98.467755)
		(end 195.561428 98.519011)
		(width 0.1)
		(layer "In7.Cu")
		(net 509)
	)
	(arc
		(start 195.773559 97.988681)
		(mid 195.897303 97.937425)
		(end 196.021047 97.988681)
		(width 0.1)
		(layer "In7.Cu")
		(net 509)
	)
	(arc
		(start 196.619928 98.340072)
		(mid 196.671185 98.216328)
		(end 196.619928 98.092586)
		(width 0.1)
		(layer "In7.Cu")
		(net 509)
	)
	(arc
		(start 195.38249 99.330025)
		(mid 195.506233 99.381282)
		(end 195.629977 99.330026)
		(width 0.1)
		(layer "In7.Cu")
		(net 509)
	)
	(arc
		(start 196.303892 97.776547)
		(mid 196.252635 97.652804)
		(end 196.303891 97.52906)
		(width 0.1)
		(layer "In7.Cu")
		(net 509)
	)
	(arc
		(start 196.867418 97.845097)
		(mid 196.991161 97.896354)
		(end 197.114905 97.845098)
		(width 0.1)
		(layer "In7.Cu")
		(net 509)
	)
	(arc
		(start 194.818964 99.261475)
		(mid 194.767707 99.137732)
		(end 194.818963 99.013988)
		(width 0.1)
		(layer "In7.Cu")
		(net 509)
	)
	(arc
		(start 195.77356 98.236167)
		(mid 195.722304 98.112423)
		(end 195.773561 97.98868)
		(width 0.1)
		(layer "In7.Cu")
		(net 509)
	)
	(arc
		(start 196.303892 97.529059)
		(mid 196.427636 97.477803)
		(end 196.55138 97.529059)
		(width 0.1)
		(layer "In7.Cu")
		(net 509)
	)
	(arc
		(start 194.818964 99.013987)
		(mid 194.942708 98.962731)
		(end 195.066452 99.013987)
		(width 0.1)
		(layer "In7.Cu")
		(net 509)
	)
	(segment
		(start 202.5 121.5)
		(end 203 121)
		(width 0.256)
		(layer "F.Cu")
		(net 510)
	)
	(segment
		(start 200.691252 98.05)
		(end 200.7 97.941252)
		(width 0.184)
		(layer "F.Cu")
		(net 510)
	)
	(segment
		(start 200.7 97.941252)
		(end 200.7 97.277149)
		(width 0.184)
		(layer "F.Cu")
		(net 510)
	)
	(via
		(at 200.691252 98.05)
		(size 0.45)
		(drill 0.2)
		(layers "F.Cu" "B.Cu")
		(net 510)
	)
	(via
		(at 203 121)
		(size 0.45)
		(drill 0.2)
		(layers "F.Cu" "B.Cu")
		(net 510)
	)
	(segment
		(start 200.691252 98.05)
		(end 200.691252 97.635)
		(width 0.184)
		(layer "B.Cu")
		(net 510)
	)
	(segment
		(start 200.691252 97.635)
		(end 200.891252 97.435)
		(width 0.184)
		(layer "B.Cu")
		(net 510)
	)
	(segment
		(start 200.691252 98.05)
		(end 200.691252 98.565)
		(width 0.184)
		(layer "B.Cu")
		(net 510)
	)
	(segment
		(start 200.691252 98.565)
		(end 200.891252 98.765)
		(width 0.184)
		(layer "B.Cu")
		(net 510)
	)
	(segment
		(start 203.01 114.54)
		(end 203.34 114.21)
		(width 0.1)
		(layer "In7.Cu")
		(net 510)
	)
	(segment
		(start 199.938435 99.271568)
		(end 200.691252 98.518748)
		(width 0.1)
		(layer "In7.Cu")
		(net 510)
	)
	(segment
		(start 197.675688 101.534315)
		(end 197.675687 101.534316)
		(width 0.1)
		(layer "In7.Cu")
		(net 510)
	)
	(segment
		(start 199.372749 99.837254)
		(end 199.372748 99.837255)
		(width 0.1)
		(layer "In7.Cu")
		(net 510)
	)
	(segment
		(start 200.691252 98.518748)
		(end 200.691252 98.05)
		(width 0.1)
		(layer "In7.Cu")
		(net 510)
	)
	(segment
		(start 198.241374 100.968629)
		(end 198.241374 100.968626)
		(width 0.1)
		(layer "In7.Cu")
		(net 510)
	)
	(segment
		(start 198.438057 99.468249)
		(end 198.438056 99.46825)
		(width 0.1)
		(layer "In7.Cu")
		(net 510)
	)
	(segment
		(start 199.938436 99.271567)
		(end 199.938435 99.271568)
		(width 0.1)
		(layer "In7.Cu")
		(net 510)
	)
	(segment
		(start 200.61 109.85)
		(end 196.54 105.78)
		(width 0.1)
		(layer "In7.Cu")
		(net 510)
	)
	(segment
		(start 198.807061 100.120097)
		(end 198.438056 99.751092)
		(width 0.1)
		(layer "In7.Cu")
		(net 510)
	)
	(segment
		(start 197.87237 100.033936)
		(end 197.872369 100.033937)
		(width 0.1)
		(layer "In7.Cu")
		(net 510)
	)
	(segment
		(start 197.306683 100.599623)
		(end 197.306682 100.599624)
		(width 0.1)
		(layer "In7.Cu")
		(net 510)
	)
	(segment
		(start 198.241374 100.685784)
		(end 197.872369 100.316779)
		(width 0.1)
		(layer "In7.Cu")
		(net 510)
	)
	(segment
		(start 197.11 101.817158)
		(end 196.740995 101.448153)
		(width 0.1)
		(layer "In7.Cu")
		(net 510)
	)
	(segment
		(start 199.286587 98.902563)
		(end 199.286587 98.902562)
		(width 0.1)
		(layer "In7.Cu")
		(net 510)
	)
	(segment
		(start 197.023839 101.165311)
		(end 197.023839 101.16531)
		(width 0.1)
		(layer "In7.Cu")
		(net 510)
	)
	(segment
		(start 199.372748 99.55441)
		(end 199.003743 99.185405)
		(width 0.1)
		(layer "In7.Cu")
		(net 510)
	)
	(segment
		(start 198.7209 99.468249)
		(end 199.089906 99.837255)
		(width 0.1)
		(layer "In7.Cu")
		(net 510)
	)
	(segment
		(start 198.807062 100.402941)
		(end 198.807061 100.402942)
		(width 0.1)
		(layer "In7.Cu")
		(net 510)
	)
	(segment
		(start 199.372748 99.837255)
		(end 199.372748 99.837252)
		(width 0.1)
		(layer "In7.Cu")
		(net 510)
	)
	(segment
		(start 199.003744 98.902562)
		(end 199.003743 98.902563)
		(width 0.1)
		(layer "In7.Cu")
		(net 510)
	)
	(segment
		(start 198.807061 100.402942)
		(end 198.807061 100.402939)
		(width 0.1)
		(layer "In7.Cu")
		(net 510)
	)
	(segment
		(start 200.61 110.81)
		(end 200.61 109.85)
		(width 0.1)
		(layer "In7.Cu")
		(net 510)
	)
	(segment
		(start 196.740996 101.16531)
		(end 196.740995 101.165311)
		(width 0.1)
		(layer "In7.Cu")
		(net 510)
	)
	(segment
		(start 198.241375 100.968628)
		(end 198.241374 100.968629)
		(width 0.1)
		(layer "In7.Cu")
		(net 510)
	)
	(segment
		(start 198.155213 100.033936)
		(end 198.524219 100.402942)
		(width 0.1)
		(layer "In7.Cu")
		(net 510)
	)
	(segment
		(start 197.589526 100.599624)
		(end 197.589526 100.599623)
		(width 0.1)
		(layer "In7.Cu")
		(net 510)
	)
	(segment
		(start 198.7209 99.46825)
		(end 198.7209 99.468249)
		(width 0.1)
		(layer "In7.Cu")
		(net 510)
	)
	(segment
		(start 197.675687 101.534316)
		(end 197.675687 101.534313)
		(width 0.1)
		(layer "In7.Cu")
		(net 510)
	)
	(segment
		(start 197.675687 101.251471)
		(end 197.306682 100.882466)
		(width 0.1)
		(layer "In7.Cu")
		(net 510)
	)
	(segment
		(start 198.155213 100.033937)
		(end 198.155213 100.033936)
		(width 0.1)
		(layer "In7.Cu")
		(net 510)
	)
	(segment
		(start 203.01 115.3)
		(end 203.01 114.54)
		(width 0.1)
		(layer "In7.Cu")
		(net 510)
	)
	(segment
		(start 203.575 120.425)
		(end 203.575 115.865)
		(width 0.1)
		(layer "In7.Cu")
		(net 510)
	)
	(segment
		(start 203 121)
		(end 203.575 120.425)
		(width 0.1)
		(layer "In7.Cu")
		(net 510)
	)
	(segment
		(start 203.34 114.21)
		(end 203.34 113.54)
		(width 0.1)
		(layer "In7.Cu")
		(net 510)
	)
	(segment
		(start 203.34 113.54)
		(end 200.61 110.81)
		(width 0.1)
		(layer "In7.Cu")
		(net 510)
	)
	(segment
		(start 197.589526 100.599623)
		(end 197.958532 100.968629)
		(width 0.1)
		(layer "In7.Cu")
		(net 510)
	)
	(segment
		(start 197.023839 101.16531)
		(end 197.392845 101.534316)
		(width 0.1)
		(layer "In7.Cu")
		(net 510)
	)
	(segment
		(start 196.54 105.78)
		(end 196.54 102.67)
		(width 0.1)
		(layer "In7.Cu")
		(net 510)
	)
	(segment
		(start 196.54 102.67)
		(end 197.11 102.1)
		(width 0.1)
		(layer "In7.Cu")
		(net 510)
	)
	(segment
		(start 203.575 115.865)
		(end 203.01 115.3)
		(width 0.1)
		(layer "In7.Cu")
		(net 510)
	)
	(segment
		(start 199.286587 98.902562)
		(end 199.655593 99.271568)
		(width 0.1)
		(layer "In7.Cu")
		(net 510)
	)
	(arc
		(start 199.003743 98.902563)
		(mid 199.145166 98.843983)
		(end 199.286587 98.902563)
		(width 0.1)
		(layer "In7.Cu")
		(net 510)
	)
	(arc
		(start 197.958532 100.968629)
		(mid 198.099954 101.027207)
		(end 198.241375 100.968628)
		(width 0.1)
		(layer "In7.Cu")
		(net 510)
	)
	(arc
		(start 198.438056 99.751092)
		(mid 198.379478 99.60967)
		(end 198.438057 99.468249)
		(width 0.1)
		(layer "In7.Cu")
		(net 510)
	)
	(arc
		(start 197.392845 101.534316)
		(mid 197.534267 101.592894)
		(end 197.675688 101.534315)
		(width 0.1)
		(layer "In7.Cu")
		(net 510)
	)
	(arc
		(start 199.089906 99.837255)
		(mid 199.231328 99.895833)
		(end 199.372749 99.837254)
		(width 0.1)
		(layer "In7.Cu")
		(net 510)
	)
	(arc
		(start 197.11 102.1)
		(mid 197.168579 101.958578)
		(end 197.11 101.817158)
		(width 0.1)
		(layer "In7.Cu")
		(net 510)
	)
	(arc
		(start 199.372748 99.837252)
		(mid 199.431327 99.69583)
		(end 199.372748 99.55441)
		(width 0.1)
		(layer "In7.Cu")
		(net 510)
	)
	(arc
		(start 197.675687 101.534313)
		(mid 197.734266 101.392891)
		(end 197.675687 101.251471)
		(width 0.1)
		(layer "In7.Cu")
		(net 510)
	)
	(arc
		(start 199.003743 99.185405)
		(mid 198.945165 99.043983)
		(end 199.003744 98.902562)
		(width 0.1)
		(layer "In7.Cu")
		(net 510)
	)
	(arc
		(start 197.306682 100.599624)
		(mid 197.448105 100.541044)
		(end 197.589526 100.599624)
		(width 0.1)
		(layer "In7.Cu")
		(net 510)
	)
	(arc
		(start 198.524219 100.402942)
		(mid 198.665641 100.46152)
		(end 198.807062 100.402941)
		(width 0.1)
		(layer "In7.Cu")
		(net 510)
	)
	(arc
		(start 197.872369 100.033937)
		(mid 198.013792 99.975357)
		(end 198.155213 100.033937)
		(width 0.1)
		(layer "In7.Cu")
		(net 510)
	)
	(arc
		(start 196.740995 101.165311)
		(mid 196.882418 101.106731)
		(end 197.023839 101.165311)
		(width 0.1)
		(layer "In7.Cu")
		(net 510)
	)
	(arc
		(start 198.241374 100.968626)
		(mid 198.299953 100.827204)
		(end 198.241374 100.685784)
		(width 0.1)
		(layer "In7.Cu")
		(net 510)
	)
	(arc
		(start 197.306682 100.882466)
		(mid 197.248104 100.741044)
		(end 197.306683 100.599623)
		(width 0.1)
		(layer "In7.Cu")
		(net 510)
	)
	(arc
		(start 198.807061 100.402939)
		(mid 198.86564 100.261517)
		(end 198.807061 100.120097)
		(width 0.1)
		(layer "In7.Cu")
		(net 510)
	)
	(arc
		(start 197.872369 100.316779)
		(mid 197.813791 100.175357)
		(end 197.87237 100.033936)
		(width 0.1)
		(layer "In7.Cu")
		(net 510)
	)
	(arc
		(start 199.655593 99.271568)
		(mid 199.797015 99.330146)
		(end 199.938436 99.271567)
		(width 0.1)
		(layer "In7.Cu")
		(net 510)
	)
	(arc
		(start 198.438056 99.46825)
		(mid 198.579479 99.40967)
		(end 198.7209 99.46825)
		(width 0.1)
		(layer "In7.Cu")
		(net 510)
	)
	(arc
		(start 196.740995 101.448153)
		(mid 196.682417 101.306731)
		(end 196.740996 101.16531)
		(width 0.1)
		(layer "In7.Cu")
		(net 510)
	)
	(segment
		(start 217.915 150.8)
		(end 217.3 150.8)
		(width 0.184)
		(layer "F.Cu")
		(net 511)
	)
	(segment
		(start 200.5 135.5)
		(end 201 136)
		(width 0.256)
		(layer "F.Cu")
		(net 511)
	)
	(via
		(at 201 136)
		(size 0.45)
		(drill 0.2)
		(layers "F.Cu" "B.Cu")
		(net 511)
	)
	(via
		(at 217.3 150.8)
		(size 0.45)
		(drill 0.2)
		(layers "F.Cu" "B.Cu")
		(net 511)
	)
	(segment
		(start 200.975 149.9)
		(end 201.225 149.9)
		(width 0.1)
		(layer "In5.Cu")
		(net 511)
	)
	(segment
		(start 209.67287 156.41797)
		(end 209.51887 156.26397)
		(width 0.1)
		(layer "In5.Cu")
		(net 511)
	)
	(segment
		(start 201.225 142.55)
		(end 200.975 142.55)
		(width 0.1)
		(layer "In5.Cu")
		(net 511)
	)
	(segment
		(start 201.225 148.85)
		(end 200.975 148.85)
		(width 0.1)
		(layer "In5.Cu")
		(net 511)
	)
	(segment
		(start 201.4 150.775)
		(end 201.4 151.207842)
		(width 0.1)
		(layer "In5.Cu")
		(net 511)
	)
	(segment
		(start 200.975 144.3)
		(end 201.225 144.3)
		(width 0.1)
		(layer "In5.Cu")
		(net 511)
	)
	(segment
		(start 201.225 146.05)
		(end 200.975 146.05)
		(width 0.1)
		(layer "In5.Cu")
		(net 511)
	)
	(segment
		(start 210.10918 155.39082)
		(end 211.4 154.1)
		(width 0.1)
		(layer "In5.Cu")
		(net 511)
	)
	(segment
		(start 201.225 144.65)
		(end 200.975 144.65)
		(width 0.1)
		(layer "In5.Cu")
		(net 511)
	)
	(segment
		(start 209.107184 156.983655)
		(end 209.107184 156.983656)
		(width 0.1)
		(layer "In5.Cu")
		(net 511)
	)
	(segment
		(start 208.953184 156.546814)
		(end 208.953184 156.546813)
		(width 0.1)
		(layer "In5.Cu")
		(net 511)
	)
	(segment
		(start 210.238556 155.852284)
		(end 210.084556 155.698284)
		(width 0.1)
		(layer "In5.Cu")
		(net 511)
	)
	(segment
		(start 210.084556 155.415442)
		(end 210.084556 155.415441)
		(width 0.1)
		(layer "In5.Cu")
		(net 511)
	)
	(segment
		(start 201.225 148.15)
		(end 200.975 148.15)
		(width 0.1)
		(layer "In5.Cu")
		(net 511)
	)
	(segment
		(start 202.975 157.75)
		(end 207.75 157.75)
		(width 0.1)
		(layer "In5.Cu")
		(net 511)
	)
	(segment
		(start 200.975 149.2)
		(end 201.225 149.2)
		(width 0.1)
		(layer "In5.Cu")
		(net 511)
	)
	(segment
		(start 201.225 140.275)
		(end 200.975 140.275)
		(width 0.1)
		(layer "In5.Cu")
		(net 511)
	)
	(segment
		(start 209.801714 155.981128)
		(end 209.955713 156.135127)
		(width 0.1)
		(layer "In5.Cu")
		(net 511)
	)
	(segment
		(start 209.51887 155.981128)
		(end 209.51887 155.981127)
		(width 0.1)
		(layer "In5.Cu")
		(net 511)
	)
	(segment
		(start 201 136)
		(end 201.4 136.4)
		(width 0.1)
		(layer "In5.Cu")
		(net 511)
	)
	(segment
		(start 200.975 150.6)
		(end 201.225 150.6)
		(width 0.1)
		(layer "In5.Cu")
		(net 511)
	)
	(segment
		(start 201.225 137.475)
		(end 200.975 137.475)
		(width 0.1)
		(layer "In5.Cu")
		(net 511)
	)
	(segment
		(start 200.975 140.625)
		(end 201.225 140.625)
		(width 0.1)
		(layer "In5.Cu")
		(net 511)
	)
	(segment
		(start 208.670342 157.1125)
		(end 208.824341 157.266499)
		(width 0.1)
		(layer "In5.Cu")
		(net 511)
	)
	(segment
		(start 209.67287 156.417969)
		(end 209.67287 156.41797)
		(width 0.1)
		(layer "In5.Cu")
		(net 511)
	)
	(segment
		(start 210.238556 155.852283)
		(end 210.238556 155.852284)
		(width 0.1)
		(layer "In5.Cu")
		(net 511)
	)
	(segment
		(start 201.225 138.875)
		(end 200.975 138.875)
		(width 0.1)
		(layer "In5.Cu")
		(net 511)
	)
	(segment
		(start 200.975 143.6)
		(end 201.225 143.6)
		(width 0.1)
		(layer "In5.Cu")
		(net 511)
	)
	(segment
		(start 200.975 145)
		(end 201.225 145)
		(width 0.1)
		(layer "In5.Cu")
		(net 511)
	)
	(segment
		(start 201.225 149.55)
		(end 200.975 149.55)
		(width 0.1)
		(layer "In5.Cu")
		(net 511)
	)
	(segment
		(start 200.975 138.525)
		(end 201.225 138.525)
		(width 0.1)
		(layer "In5.Cu")
		(net 511)
	)
	(segment
		(start 201.225 145.35)
		(end 200.975 145.35)
		(width 0.1)
		(layer "In5.Cu")
		(net 511)
	)
	(segment
		(start 209.672869 156.700813)
		(end 209.67287 156.700813)
		(width 0.1)
		(layer "In5.Cu")
		(net 511)
	)
	(segment
		(start 214.065 154.035)
		(end 217.3 150.8)
		(width 0.1)
		(layer "In5.Cu")
		(net 511)
	)
	(segment
		(start 200.975 148.5)
		(end 201.225 148.5)
		(width 0.1)
		(layer "In5.Cu")
		(net 511)
	)
	(segment
		(start 209.107183 157.266499)
		(end 209.107184 157.266499)
		(width 0.1)
		(layer "In5.Cu")
		(net 511)
	)
	(segment
		(start 210.238555 156.135127)
		(end 210.238556 156.135127)
		(width 0.1)
		(layer "In5.Cu")
		(net 511)
	)
	(segment
		(start 209.107184 156.983656)
		(end 208.953184 156.829656)
		(width 0.1)
		(layer "In5.Cu")
		(net 511)
	)
	(segment
		(start 201.225 147.45)
		(end 200.975 147.45)
		(width 0.1)
		(layer "In5.Cu")
		(net 511)
	)
	(segment
		(start 208.953184 156.546813)
		(end 208.953186 156.546814)
		(width 0.1)
		(layer "In5.Cu")
		(net 511)
	)
	(segment
		(start 207.75 157.75)
		(end 208.3875 157.1125)
		(width 0.1)
		(layer "In5.Cu")
		(net 511)
	)
	(segment
		(start 201.225 150.25)
		(end 200.975 150.25)
		(width 0.1)
		(layer "In5.Cu")
		(net 511)
	)
	(segment
		(start 200.975 147.8)
		(end 201.225 147.8)
		(width 0.1)
		(layer "In5.Cu")
		(net 511)
	)
	(segment
		(start 200.975 137.825)
		(end 201.225 137.825)
		(width 0.1)
		(layer "In5.Cu")
		(net 511)
	)
	(segment
		(start 201.225 143.25)
		(end 200.975 143.25)
		(width 0.1)
		(layer "In5.Cu")
		(net 511)
	)
	(segment
		(start 201.4 151.207842)
		(end 202.575 152.382842)
		(width 0.1)
		(layer "In5.Cu")
		(net 511)
	)
	(segment
		(start 201.225 139.575)
		(end 200.975 139.575)
		(width 0.1)
		(layer "In5.Cu")
		(net 511)
	)
	(segment
		(start 211.4 154.1)
		(end 214 154.1)
		(width 0.1)
		(layer "In5.Cu")
		(net 511)
	)
	(segment
		(start 201.225 143.95)
		(end 200.975 143.95)
		(width 0.1)
		(layer "In5.Cu")
		(net 511)
	)
	(segment
		(start 200.975 139.925)
		(end 201.225 139.925)
		(width 0.1)
		(layer "In5.Cu")
		(net 511)
	)
	(segment
		(start 209.236028 156.546814)
		(end 209.390027 156.700813)
		(width 0.1)
		(layer "In5.Cu")
		(net 511)
	)
	(segment
		(start 200.975 147.1)
		(end 201.225 147.1)
		(width 0.1)
		(layer "In5.Cu")
		(net 511)
	)
	(segment
		(start 202.575 157.35)
		(end 202.975 157.75)
		(width 0.1)
		(layer "In5.Cu")
		(net 511)
	)
	(segment
		(start 200.975 139.225)
		(end 201.225 139.225)
		(width 0.1)
		(layer "In5.Cu")
		(net 511)
	)
	(segment
		(start 201.225 138.175)
		(end 200.975 138.175)
		(width 0.1)
		(layer "In5.Cu")
		(net 511)
	)
	(segment
		(start 201.4 140.8)
		(end 201.4 142.375)
		(width 0.1)
		(layer "In5.Cu")
		(net 511)
	)
	(segment
		(start 200.975 142.9)
		(end 201.225 142.9)
		(width 0.1)
		(layer "In5.Cu")
		(net 511)
	)
	(segment
		(start 201.4 136.4)
		(end 201.4 137.3)
		(width 0.1)
		(layer "In5.Cu")
		(net 511)
	)
	(segment
		(start 200.975 146.4)
		(end 201.225 146.4)
		(width 0.1)
		(layer "In5.Cu")
		(net 511)
	)
	(segment
		(start 200.975 145.7)
		(end 201.225 145.7)
		(width 0.1)
		(layer "In5.Cu")
		(net 511)
	)
	(segment
		(start 214 154.1)
		(end 214.065 154.035)
		(width 0.1)
		(layer "In5.Cu")
		(net 511)
	)
	(segment
		(start 202.575 152.382842)
		(end 202.575 157.35)
		(width 0.1)
		(layer "In5.Cu")
		(net 511)
	)
	(segment
		(start 209.51887 155.981127)
		(end 209.518872 155.981128)
		(width 0.1)
		(layer "In5.Cu")
		(net 511)
	)
	(segment
		(start 210.084556 155.415441)
		(end 210.10918 155.39082)
		(width 0.1)
		(layer "In5.Cu")
		(net 511)
	)
	(segment
		(start 201.225 146.75)
		(end 200.975 146.75)
		(width 0.1)
		(layer "In5.Cu")
		(net 511)
	)
	(arc
		(start 200.8 150.425)
		(mid 200.851256 150.548744)
		(end 200.975 150.6)
		(width 0.1)
		(layer "In5.Cu")
		(net 511)
	)
	(arc
		(start 201.4 143.775)
		(mid 201.348744 143.898744)
		(end 201.225 143.95)
		(width 0.1)
		(layer "In5.Cu")
		(net 511)
	)
	(arc
		(start 201.225 145.7)
		(mid 201.348744 145.751256)
		(end 201.4 145.875)
		(width 0.1)
		(layer "In5.Cu")
		(net 511)
	)
	(arc
		(start 201.4 138.7)
		(mid 201.348744 138.823744)
		(end 201.225 138.875)
		(width 0.1)
		(layer "In5.Cu")
		(net 511)
	)
	(arc
		(start 209.67287 156.700813)
		(mid 209.731449 156.559391)
		(end 209.67287 156.417969)
		(width 0.1)
		(layer "In5.Cu")
		(net 511)
	)
	(arc
		(start 200.975 144.65)
		(mid 200.851256 144.701256)
		(end 200.8 144.825)
		(width 0.1)
		(layer "In5.Cu")
		(net 511)
	)
	(arc
		(start 210.084556 155.698284)
		(mid 210.025978 155.556863)
		(end 210.084556 155.415442)
		(width 0.1)
		(layer "In5.Cu")
		(net 511)
	)
	(arc
		(start 200.975 137.475)
		(mid 200.851256 137.526256)
		(end 200.8 137.65)
		(width 0.1)
		(layer "In5.Cu")
		(net 511)
	)
	(arc
		(start 200.8 149.025)
		(mid 200.851256 149.148744)
		(end 200.975 149.2)
		(width 0.1)
		(layer "In5.Cu")
		(net 511)
	)
	(arc
		(start 201.4 147.975)
		(mid 201.348744 148.098744)
		(end 201.225 148.15)
		(width 0.1)
		(layer "In5.Cu")
		(net 511)
	)
	(arc
		(start 201.225 140.625)
		(mid 201.348744 140.676256)
		(end 201.4 140.8)
		(width 0.1)
		(layer "In5.Cu")
		(net 511)
	)
	(arc
		(start 201.225 148.5)
		(mid 201.348744 148.551256)
		(end 201.4 148.675)
		(width 0.1)
		(layer "In5.Cu")
		(net 511)
	)
	(arc
		(start 200.975 138.175)
		(mid 200.851256 138.226256)
		(end 200.8 138.35)
		(width 0.1)
		(layer "In5.Cu")
		(net 511)
	)
	(arc
		(start 200.975 146.75)
		(mid 200.851256 146.801256)
		(end 200.8 146.925)
		(width 0.1)
		(layer "In5.Cu")
		(net 511)
	)
	(arc
		(start 200.8 148.325)
		(mid 200.851256 148.448744)
		(end 200.975 148.5)
		(width 0.1)
		(layer "In5.Cu")
		(net 511)
	)
	(arc
		(start 201.225 143.6)
		(mid 201.348744 143.651256)
		(end 201.4 143.775)
		(width 0.1)
		(layer "In5.Cu")
		(net 511)
	)
	(arc
		(start 200.8 144.825)
		(mid 200.851256 144.948744)
		(end 200.975 145)
		(width 0.1)
		(layer "In5.Cu")
		(net 511)
	)
	(arc
		(start 200.8 137.65)
		(mid 200.851256 137.773744)
		(end 200.975 137.825)
		(width 0.1)
		(layer "In5.Cu")
		(net 511)
	)
	(arc
		(start 200.975 146.05)
		(mid 200.851256 146.101256)
		(end 200.8 146.225)
		(width 0.1)
		(layer "In5.Cu")
		(net 511)
	)
	(arc
		(start 200.8 140.45)
		(mid 200.851256 140.573744)
		(end 200.975 140.625)
		(width 0.1)
		(layer "In5.Cu")
		(net 511)
	)
	(arc
		(start 209.107184 157.266499)
		(mid 209.165763 157.125077)
		(end 209.107184 156.983655)
		(width 0.1)
		(layer "In5.Cu")
		(net 511)
	)
	(arc
		(start 201.4 147.275)
		(mid 201.348744 147.398744)
		(end 201.225 147.45)
		(width 0.1)
		(layer "In5.Cu")
		(net 511)
	)
	(arc
		(start 201.4 137.3)
		(mid 201.348744 137.423744)
		(end 201.225 137.475)
		(width 0.1)
		(layer "In5.Cu")
		(net 511)
	)
	(arc
		(start 209.518872 155.981128)
		(mid 209.660293 155.92255)
		(end 209.801714 155.981128)
		(width 0.1)
		(layer "In5.Cu")
		(net 511)
	)
	(arc
		(start 201.4 144.475)
		(mid 201.348744 144.598744)
		(end 201.225 144.65)
		(width 0.1)
		(layer "In5.Cu")
		(net 511)
	)
	(arc
		(start 200.975 138.875)
		(mid 200.851256 138.926256)
		(end 200.8 139.05)
		(width 0.1)
		(layer "In5.Cu")
		(net 511)
	)
	(arc
		(start 200.8 143.425)
		(mid 200.851256 143.548744)
		(end 200.975 143.6)
		(width 0.1)
		(layer "In5.Cu")
		(net 511)
	)
	(arc
		(start 201.4 139.4)
		(mid 201.348744 139.523744)
		(end 201.225 139.575)
		(width 0.1)
		(layer "In5.Cu")
		(net 511)
	)
	(arc
		(start 200.975 140.275)
		(mid 200.851256 140.326256)
		(end 200.8 140.45)
		(width 0.1)
		(layer "In5.Cu")
		(net 511)
	)
	(arc
		(start 200.975 147.45)
		(mid 200.851256 147.501256)
		(end 200.8 147.625)
		(width 0.1)
		(layer "In5.Cu")
		(net 511)
	)
	(arc
		(start 200.975 148.15)
		(mid 200.851256 148.201256)
		(end 200.8 148.325)
		(width 0.1)
		(layer "In5.Cu")
		(net 511)
	)
	(arc
		(start 201.225 150.6)
		(mid 201.348744 150.651256)
		(end 201.4 150.775)
		(width 0.1)
		(layer "In5.Cu")
		(net 511)
	)
	(arc
		(start 201.4 143.075)
		(mid 201.348744 143.198744)
		(end 201.225 143.25)
		(width 0.1)
		(layer "In5.Cu")
		(net 511)
	)
	(arc
		(start 209.390027 156.700813)
		(mid 209.531448 156.759391)
		(end 209.672869 156.700813)
		(width 0.1)
		(layer "In5.Cu")
		(net 511)
	)
	(arc
		(start 200.975 143.25)
		(mid 200.851256 143.301256)
		(end 200.8 143.425)
		(width 0.1)
		(layer "In5.Cu")
		(net 511)
	)
	(arc
		(start 201.4 148.675)
		(mid 201.348744 148.798744)
		(end 201.225 148.85)
		(width 0.1)
		(layer "In5.Cu")
		(net 511)
	)
	(arc
		(start 201.4 145.175)
		(mid 201.348744 145.298744)
		(end 201.225 145.35)
		(width 0.1)
		(layer "In5.Cu")
		(net 511)
	)
	(arc
		(start 201.4 150.075)
		(mid 201.348744 150.198744)
		(end 201.225 150.25)
		(width 0.1)
		(layer "In5.Cu")
		(net 511)
	)
	(arc
		(start 201.225 144.3)
		(mid 201.348744 144.351256)
		(end 201.4 144.475)
		(width 0.1)
		(layer "In5.Cu")
		(net 511)
	)
	(arc
		(start 201.4 146.575)
		(mid 201.348744 146.698744)
		(end 201.225 146.75)
		(width 0.1)
		(layer "In5.Cu")
		(net 511)
	)
	(arc
		(start 201.225 139.925)
		(mid 201.348744 139.976256)
		(end 201.4 140.1)
		(width 0.1)
		(layer "In5.Cu")
		(net 511)
	)
	(arc
		(start 200.8 139.75)
		(mid 200.851256 139.873744)
		(end 200.975 139.925)
		(width 0.1)
		(layer "In5.Cu")
		(net 511)
	)
	(arc
		(start 200.975 139.575)
		(mid 200.851256 139.626256)
		(end 200.8 139.75)
		(width 0.1)
		(layer "In5.Cu")
		(net 511)
	)
	(arc
		(start 210.238556 156.135127)
		(mid 210.297135 155.993705)
		(end 210.238556 155.852283)
		(width 0.1)
		(layer "In5.Cu")
		(net 511)
	)
	(arc
		(start 209.51887 156.26397)
		(mid 209.460292 156.122549)
		(end 209.51887 155.981128)
		(width 0.1)
		(layer "In5.Cu")
		(net 511)
	)
	(arc
		(start 200.8 139.05)
		(mid 200.851256 139.173744)
		(end 200.975 139.225)
		(width 0.1)
		(layer "In5.Cu")
		(net 511)
	)
	(arc
		(start 200.975 150.25)
		(mid 200.851256 150.301256)
		(end 200.8 150.425)
		(width 0.1)
		(layer "In5.Cu")
		(net 511)
	)
	(arc
		(start 200.975 149.55)
		(mid 200.851256 149.601256)
		(end 200.8 149.725)
		(width 0.1)
		(layer "In5.Cu")
		(net 511)
	)
	(arc
		(start 201.4 145.875)
		(mid 201.348744 145.998744)
		(end 201.225 146.05)
		(width 0.1)
		(layer "In5.Cu")
		(net 511)
	)
	(arc
		(start 200.8 146.225)
		(mid 200.851256 146.348744)
		(end 200.975 146.4)
		(width 0.1)
		(layer "In5.Cu")
		(net 511)
	)
	(arc
		(start 201.4 138)
		(mid 201.348744 138.123744)
		(end 201.225 138.175)
		(width 0.1)
		(layer "In5.Cu")
		(net 511)
	)
	(arc
		(start 201.4 142.375)
		(mid 201.348744 142.498744)
		(end 201.225 142.55)
		(width 0.1)
		(layer "In5.Cu")
		(net 511)
	)
	(arc
		(start 201.225 147.1)
		(mid 201.348744 147.151256)
		(end 201.4 147.275)
		(width 0.1)
		(layer "In5.Cu")
		(net 511)
	)
	(arc
		(start 201.225 145)
		(mid 201.348744 145.051256)
		(end 201.4 145.175)
		(width 0.1)
		(layer "In5.Cu")
		(net 511)
	)
	(arc
		(start 201.225 149.2)
		(mid 201.348744 149.251256)
		(end 201.4 149.375)
		(width 0.1)
		(layer "In5.Cu")
		(net 511)
	)
	(arc
		(start 201.225 146.4)
		(mid 201.348744 146.451256)
		(end 201.4 146.575)
		(width 0.1)
		(layer "In5.Cu")
		(net 511)
	)
	(arc
		(start 200.8 138.35)
		(mid 200.851256 138.473744)
		(end 200.975 138.525)
		(width 0.1)
		(layer "In5.Cu")
		(net 511)
	)
	(arc
		(start 200.975 142.55)
		(mid 200.851256 142.601256)
		(end 200.8 142.725)
		(width 0.1)
		(layer "In5.Cu")
		(net 511)
	)
	(arc
		(start 200.975 143.95)
		(mid 200.851256 144.001256)
		(end 200.8 144.125)
		(width 0.1)
		(layer "In5.Cu")
		(net 511)
	)
	(arc
		(start 201.225 147.8)
		(mid 201.348744 147.851256)
		(end 201.4 147.975)
		(width 0.1)
		(layer "In5.Cu")
		(net 511)
	)
	(arc
		(start 200.8 149.725)
		(mid 200.851256 149.848744)
		(end 200.975 149.9)
		(width 0.1)
		(layer "In5.Cu")
		(net 511)
	)
	(arc
		(start 201.4 149.375)
		(mid 201.348744 149.498744)
		(end 201.225 149.55)
		(width 0.1)
		(layer "In5.Cu")
		(net 511)
	)
	(arc
		(start 208.953186 156.546814)
		(mid 209.094607 156.488236)
		(end 209.236028 156.546814)
		(width 0.1)
		(layer "In5.Cu")
		(net 511)
	)
	(arc
		(start 200.8 145.525)
		(mid 200.851256 145.648744)
		(end 200.975 145.7)
		(width 0.1)
		(layer "In5.Cu")
		(net 511)
	)
	(arc
		(start 201.225 149.9)
		(mid 201.348744 149.951256)
		(end 201.4 150.075)
		(width 0.1)
		(layer "In5.Cu")
		(net 511)
	)
	(arc
		(start 200.975 145.35)
		(mid 200.851256 145.401256)
		(end 200.8 145.525)
		(width 0.1)
		(layer "In5.Cu")
		(net 511)
	)
	(arc
		(start 209.955713 156.135127)
		(mid 210.097134 156.193705)
		(end 210.238555 156.135127)
		(width 0.1)
		(layer "In5.Cu")
		(net 511)
	)
	(arc
		(start 201.225 139.225)
		(mid 201.348744 139.276256)
		(end 201.4 139.4)
		(width 0.1)
		(layer "In5.Cu")
		(net 511)
	)
	(arc
		(start 200.8 146.925)
		(mid 200.851256 147.048744)
		(end 200.975 147.1)
		(width 0.1)
		(layer "In5.Cu")
		(net 511)
	)
	(arc
		(start 201.225 138.525)
		(mid 201.348744 138.576256)
		(end 201.4 138.7)
		(width 0.1)
		(layer "In5.Cu")
		(net 511)
	)
	(arc
		(start 200.8 144.125)
		(mid 200.851256 144.248744)
		(end 200.975 144.3)
		(width 0.1)
		(layer "In5.Cu")
		(net 511)
	)
	(arc
		(start 201.225 142.9)
		(mid 201.348744 142.951256)
		(end 201.4 143.075)
		(width 0.1)
		(layer "In5.Cu")
		(net 511)
	)
	(arc
		(start 200.8 147.625)
		(mid 200.851256 147.748744)
		(end 200.975 147.8)
		(width 0.1)
		(layer "In5.Cu")
		(net 511)
	)
	(arc
		(start 208.824341 157.266499)
		(mid 208.965762 157.325077)
		(end 209.107183 157.266499)
		(width 0.1)
		(layer "In5.Cu")
		(net 511)
	)
	(arc
		(start 200.975 148.85)
		(mid 200.851256 148.901256)
		(end 200.8 149.025)
		(width 0.1)
		(layer "In5.Cu")
		(net 511)
	)
	(arc
		(start 208.3875 157.1125)
		(mid 208.528921 157.053922)
		(end 208.670342 157.1125)
		(width 0.1)
		(layer "In5.Cu")
		(net 511)
	)
	(arc
		(start 208.953184 156.829656)
		(mid 208.894606 156.688235)
		(end 208.953184 156.546814)
		(width 0.1)
		(layer "In5.Cu")
		(net 511)
	)
	(arc
		(start 201.225 137.825)
		(mid 201.348744 137.876256)
		(end 201.4 138)
		(width 0.1)
		(layer "In5.Cu")
		(net 511)
	)
	(arc
		(start 201.4 140.1)
		(mid 201.348744 140.223744)
		(end 201.225 140.275)
		(width 0.1)
		(layer "In5.Cu")
		(net 511)
	)
	(arc
		(start 200.8 142.725)
		(mid 200.851256 142.848744)
		(end 200.975 142.9)
		(width 0.1)
		(layer "In5.Cu")
		(net 511)
	)
	(segment
		(start 217.915 151.8)
		(end 217.750497 151.8)
		(width 0.184)
		(layer "F.Cu")
		(net 513)
	)
	(segment
		(start 217.750497 151.8)
		(end 217.3 151.349503)
		(width 0.184)
		(layer "F.Cu")
		(net 513)
	)
	(segment
		(start 199.5 137.5)
		(end 199 138)
		(width 0.256)
		(layer "F.Cu")
		(net 513)
	)
	(via
		(at 199 138)
		(size 0.45)
		(drill 0.2)
		(layers "F.Cu" "B.Cu")
		(net 513)
	)
	(via
		(at 217.3 151.349503)
		(size 0.45)
		(drill 0.2)
		(layers "F.Cu" "B.Cu")
		(net 513)
	)
	(segment
		(start 200.4 147.95)
		(end 200.434571 147.951201)
		(width 0.1)
		(layer "In5.Cu")
		(net 513)
	)
	(segment
		(start 200.4 146.55)
		(end 200.434571 146.551201)
		(width 0.1)
		(layer "In5.Cu")
		(net 513)
	)
	(segment
		(start 200.575 146.725)
		(end 200.573799 146.759571)
		(width 0.1)
		(layer "In5.Cu")
		(net 513)
	)
	(segment
		(start 199.776201 148.440429)
		(end 199.775 148.475)
		(width 0.1)
		(layer "In5.Cu")
		(net 513)
	)
	(segment
		(start 199.851551 149.72766)
		(end 199.80266 149.776551)
		(width 0.1)
		(layer "In5.Cu")
		(net 513)
	)
	(segment
		(start 199.915429 146.901201)
		(end 199.851551 146.92766)
		(width 0.1)
		(layer "In5.Cu")
		(net 513)
	)
	(segment
		(start 211.223573 155.598694)
		(end 211.223574 155.598693)
		(width 0.1)
		(layer "In5.Cu")
		(net 513)
	)
	(segment
		(start 200.4 149)
		(end 199.95 149)
		(width 0.1)
		(layer "In5.Cu")
		(net 513)
	)
	(segment
		(start 211.718549 155.103718)
		(end 211.71855 155.103717)
		(width 0.1)
		(layer "In5.Cu")
		(net 513)
	)
	(segment
		(start 200.498449 147.27766)
		(end 200.54734 147.326551)
		(width 0.1)
		(layer "In5.Cu")
		(net 513)
	)
	(segment
		(start 199.95 146.55)
		(end 200.4 146.55)
		(width 0.1)
		(layer "In5.Cu")
		(net 513)
	)
	(segment
		(start 199.851551 147.62766)
		(end 199.80266 147.676551)
		(width 0.1)
		(layer "In5.Cu")
		(net 513)
	)
	(segment
		(start 199.851551 149.02766)
		(end 199.80266 149.076551)
		(width 0.1)
		(layer "In5.Cu")
		(net 513)
	)
	(segment
		(start 200.54734 146.626551)
		(end 200.573799 146.690429)
		(width 0.1)
		(layer "In5.Cu")
		(net 513)
	)
	(segment
		(start 199.915429 149.348799)
		(end 199.95 149.35)
		(width 0.1)
		(layer "In5.Cu")
		(net 513)
	)
	(segment
		(start 211.025001 157.627512)
		(end 210.233622 156.836133)
		(width 0.1)
		(layer "In5.Cu")
		(net 513)
	)
	(segment
		(start 199.775 147.075)
		(end 199.776201 147.109571)
		(width 0.1)
		(layer "In5.Cu")
		(net 513)
	)
	(segment
		(start 200.4 148.65)
		(end 200.434571 148.651201)
		(width 0.1)
		(layer "In5.Cu")
		(net 513)
	)
	(segment
		(start 199.776201 147.109571)
		(end 199.80266 147.173449)
		(width 0.1)
		(layer "In5.Cu")
		(net 513)
	)
	(segment
		(start 210.976086 156.093669)
		(end 211.767466 156.885049)
		(width 0.1)
		(layer "In5.Cu")
		(net 513)
	)
	(segment
		(start 200.573799 148.090429)
		(end 200.575 148.125)
		(width 0.1)
		(layer "In5.Cu")
		(net 513)
	)
	(segment
		(start 199.775 149.175)
		(end 199.776201 149.209571)
		(width 0.1)
		(layer "In5.Cu")
		(net 513)
	)
	(segment
		(start 199 138)
		(end 199.4 138.4)
		(width 0.1)
		(layer "In5.Cu")
		(net 513)
	)
	(segment
		(start 202.375 157.55)
		(end 202.8 157.975)
		(width 0.1)
		(layer "In5.Cu")
		(net 513)
	)
	(segment
		(start 211.519977 157.380026)
		(end 211.519978 157.380025)
		(width 0.1)
		(layer "In5.Cu")
		(net 513)
	)
	(segment
		(start 200.4 147.25)
		(end 200.434571 147.251201)
		(width 0.1)
		(layer "In5.Cu")
		(net 513)
	)
	(segment
		(start 199.95 148.3)
		(end 199.915429 148.301201)
		(width 0.1)
		(layer "In5.Cu")
		(net 513)
	)
	(segment
		(start 199.776201 149.209571)
		(end 199.80266 149.273449)
		(width 0.1)
		(layer "In5.Cu")
		(net 513)
	)
	(segment
		(start 213.004906 155.895097)
		(end 213.313045 155.586955)
		(width 0.1)
		(layer "In5.Cu")
		(net 513)
	)
	(segment
		(start 212.509928 156.142586)
		(end 212.509929 156.142584)
		(width 0.1)
		(layer "In5.Cu")
		(net 513)
	)
	(segment
		(start 200.434571 146.898799)
		(end 200.4 146.9)
		(width 0.1)
		(layer "In5.Cu")
		(net 513)
	)
	(segment
		(start 199.776201 149.840429)
		(end 199.776201 150.101201)
		(width 0.1)
		(layer "In5.Cu")
		(net 513)
	)
	(segment
		(start 211.471062 155.598693)
		(end 212.262442 156.390073)
		(width 0.1)
		(layer "In5.Cu")
		(net 513)
	)
	(segment
		(start 212.014953 156.88505)
		(end 212.014954 156.885049)
		(width 0.1)
		(layer "In5.Cu")
		(net 513)
	)
	(segment
		(start 200.573799 146.759571)
		(end 200.54734 146.823449)
		(width 0.1)
		(layer "In5.Cu")
		(net 513)
	)
	(segment
		(start 210.728597 156.09367)
		(end 210.728598 156.093669)
		(width 0.1)
		(layer "In5.Cu")
		(net 513)
	)
	(segment
		(start 212.014953 156.63756)
		(end 211.223574 155.846181)
		(width 0.1)
		(layer "In5.Cu")
		(net 513)
	)
	(segment
		(start 200.573799 148.859571)
		(end 200.54734 148.923449)
		(width 0.1)
		(layer "In5.Cu")
		(net 513)
	)
	(segment
		(start 211.519978 157.380025)
		(end 211.519976 157.380024)
		(width 0.1)
		(layer "In5.Cu")
		(net 513)
	)
	(segment
		(start 199.80266 146.473449)
		(end 199.851551 146.52234)
		(width 0.1)
		(layer "In5.Cu")
		(net 513)
	)
	(segment
		(start 200.54734 147.326551)
		(end 200.573799 147.390429)
		(width 0.1)
		(layer "In5.Cu")
		(net 513)
	)
	(segment
		(start 210.233621 156.588646)
		(end 210.233622 156.588645)
		(width 0.1)
		(layer "In5.Cu")
		(net 513)
	)
	(segment
		(start 199.95 146.9)
		(end 199.915429 146.901201)
		(width 0.1)
		(layer "In5.Cu")
		(net 513)
	)
	(segment
		(start 200.434571 148.998799)
		(end 200.4 149)
		(width 0.1)
		(layer "In5.Cu")
		(net 513)
	)
	(segment
		(start 211.519977 157.132536)
		(end 210.728598 156.341157)
		(width 0.1)
		(layer "In5.Cu")
		(net 513)
	)
	(segment
		(start 199.95 148.65)
		(end 200.4 148.65)
		(width 0.1)
		(layer "In5.Cu")
		(net 513)
	)
	(segment
		(start 200.434571 146.551201)
		(end 200.498449 146.57766)
		(width 0.1)
		(layer "In5.Cu")
		(net 513)
	)
	(segment
		(start 211.519976 157.132538)
		(end 211.519977 157.132536)
		(width 0.1)
		(layer "In5.Cu")
		(net 513)
	)
	(segment
		(start 200.573799 149.490429)
		(end 200.575 149.525)
		(width 0.1)
		(layer "In5.Cu")
		(net 513)
	)
	(segment
		(start 200.573799 147.459571)
		(end 200.54734 147.523449)
		(width 0.1)
		(layer "In5.Cu")
		(net 513)
	)
	(segment
		(start 199.851551 147.22234)
		(end 199.915429 147.248799)
		(width 0.1)
		(layer "In5.Cu")
		(net 513)
	)
	(segment
		(start 199.80266 148.573449)
		(end 199.851551 148.62234)
		(width 0.1)
		(layer "In5.Cu")
		(net 513)
	)
	(segment
		(start 199.851551 147.92234)
		(end 199.915429 147.948799)
		(width 0.1)
		(layer "In5.Cu")
		(net 513)
	)
	(segment
		(start 199.915429 149.701201)
		(end 199.851551 149.72766)
		(width 0.1)
		(layer "In5.Cu")
		(net 513)
	)
	(segment
		(start 200.498449 149.37766)
		(end 200.54734 149.426551)
		(width 0.1)
		(layer "In5.Cu")
		(net 513)
	)
	(segment
		(start 210.48111 156.588645)
		(end 211.27249 157.380025)
		(width 0.1)
		(layer "In5.Cu")
		(net 513)
	)
	(segment
		(start 200.498449 146.57766)
		(end 200.54734 146.626551)
		(width 0.1)
		(layer "In5.Cu")
		(net 513)
	)
	(segment
		(start 200.573799 148.790429)
		(end 200.575 148.825)
		(width 0.1)
		(layer "In5.Cu")
		(net 513)
	)
	(segment
		(start 200.4 146.9)
		(end 199.95 146.9)
		(width 0.1)
		(layer "In5.Cu")
		(net 513)
	)
	(segment
		(start 216.825 152.075)
		(end 216.825 151.824503)
		(width 0.1)
		(layer "In5.Cu")
		(net 513)
	)
	(segment
		(start 211.966038 155.103717)
		(end 212.757418 155.895097)
		(width 0.1)
		(layer "In5.Cu")
		(net 513)
	)
	(segment
		(start 199.776201 147.040429)
		(end 199.775 147.075)
		(width 0.1)
		(layer "In5.Cu")
		(net 513)
	)
	(segment
		(start 200.54734 148.026551)
		(end 200.573799 148.090429)
		(width 0.1)
		(layer "In5.Cu")
		(net 513)
	)
	(segment
		(start 200.54734 148.726551)
		(end 200.573799 148.790429)
		(width 0.1)
		(layer "In5.Cu")
		(net 513)
	)
	(segment
		(start 200.54734 147.523449)
		(end 200.498449 147.57234)
		(width 0.1)
		(layer "In5.Cu")
		(net 513)
	)
	(segment
		(start 199.775 146.375)
		(end 199.776201 146.409571)
		(width 0.1)
		(layer "In5.Cu")
		(net 513)
	)
	(segment
		(start 199.80266 147.173449)
		(end 199.851551 147.22234)
		(width 0.1)
		(layer "In5.Cu")
		(net 513)
	)
	(segment
		(start 200.434571 149.698799)
		(end 200.4 149.7)
		(width 0.1)
		(layer "In5.Cu")
		(net 513)
	)
	(segment
		(start 199.851551 149.32234)
		(end 199.915429 149.348799)
		(width 0.1)
		(layer "In5.Cu")
		(net 513)
	)
	(segment
		(start 200.573799 148.159571)
		(end 200.54734 148.223449)
		(width 0.1)
		(layer "In5.Cu")
		(net 513)
	)
	(segment
		(start 199.915429 146.548799)
		(end 199.95 146.55)
		(width 0.1)
		(layer "In5.Cu")
		(net 513)
	)
	(segment
		(start 199.80266 147.873449)
		(end 199.851551 147.92234)
		(width 0.1)
		(layer "In5.Cu")
		(net 513)
	)
	(segment
		(start 199.915429 149.001201)
		(end 199.851551 149.02766)
		(width 0.1)
		(layer "In5.Cu")
		(net 513)
	)
	(segment
		(start 200.54734 149.623449)
		(end 200.498449 149.67234)
		(width 0.1)
		(layer "In5.Cu")
		(net 513)
	)
	(segment
		(start 199.80266 149.273449)
		(end 199.851551 149.32234)
		(width 0.1)
		(layer "In5.Cu")
		(net 513)
	)
	(segment
		(start 199.915429 148.648799)
		(end 199.95 148.65)
		(width 0.1)
		(layer "In5.Cu")
		(net 513)
	)
	(segment
		(start 200.434571 147.951201)
		(end 200.498449 147.97766)
		(width 0.1)
		(layer "In5.Cu")
		(net 513)
	)
	(segment
		(start 210.925 157.975)
		(end 211.025 157.875)
		(width 0.1)
		(layer "In5.Cu")
		(net 513)
	)
	(segment
		(start 199.915429 147.248799)
		(end 199.95 147.25)
		(width 0.1)
		(layer "In5.Cu")
		(net 513)
	)
	(segment
		(start 200.575 145.332842)
		(end 199.775 146.132842)
		(width 0.1)
		(layer "In5.Cu")
		(net 513)
	)
	(segment
		(start 212.509929 156.390074)
		(end 212.50993 156.390073)
		(width 0.1)
		(layer "In5.Cu")
		(net 513)
	)
	(segment
		(start 200.434571 147.598799)
		(end 200.4 147.6)
		(width 0.1)
		(layer "In5.Cu")
		(net 513)
	)
	(segment
		(start 200.434571 147.251201)
		(end 200.498449 147.27766)
		(width 0.1)
		(layer "In5.Cu")
		(net 513)
	)
	(segment
		(start 202.375 152.7)
		(end 202.375 157.55)
		(width 0.1)
		(layer "In5.Cu")
		(net 513)
	)
	(segment
		(start 199.80266 147.676551)
		(end 199.776201 147.740429)
		(width 0.1)
		(layer "In5.Cu")
		(net 513)
	)
	(segment
		(start 200.575 148.825)
		(end 200.573799 148.859571)
		(width 0.1)
		(layer "In5.Cu")
		(net 513)
	)
	(segment
		(start 200.4 148.3)
		(end 199.95 148.3)
		(width 0.1)
		(layer "In5.Cu")
		(net 513)
	)
	(segment
		(start 202.8 157.975)
		(end 210.925 157.975)
		(width 0.1)
		(layer "In5.Cu")
		(net 513)
	)
	(segment
		(start 199.851551 146.52234)
		(end 199.915429 146.548799)
		(width 0.1)
		(layer "In5.Cu")
		(net 513)
	)
	(segment
		(start 200.573799 149.559571)
		(end 200.54734 149.623449)
		(width 0.1)
		(layer "In5.Cu")
		(net 513)
	)
	(segment
		(start 200.573799 147.390429)
		(end 200.575 147.425)
		(width 0.1)
		(layer "In5.Cu")
		(net 513)
	)
	(segment
		(start 200.54734 148.923449)
		(end 200.498449 148.97234)
		(width 0.1)
		(layer "In5.Cu")
		(net 513)
	)
	(segment
		(start 199.95 147.25)
		(end 200.4 147.25)
		(width 0.1)
		(layer "In5.Cu")
		(net 513)
	)
	(segment
		(start 199.915429 148.301201)
		(end 199.851551 148.32766)
		(width 0.1)
		(layer "In5.Cu")
		(net 513)
	)
	(segment
		(start 199.95 149)
		(end 199.915429 149.001201)
		(width 0.1)
		(layer "In5.Cu")
		(net 513)
	)
	(segment
		(start 199.4 138.4)
		(end 200.3 138.4)
		(width 0.1)
		(layer "In5.Cu")
		(net 513)
	)
	(segment
		(start 200.3 138.4)
		(end 200.575 138.675)
		(width 0.1)
		(layer "In5.Cu")
		(net 513)
	)
	(segment
		(start 200.498449 148.27234)
		(end 200.434571 148.298799)
		(width 0.1)
		(layer "In5.Cu")
		(net 513)
	)
	(segment
		(start 200.573799 146.690429)
		(end 200.575 146.725)
		(width 0.1)
		(layer "In5.Cu")
		(net 513)
	)
	(segment
		(start 200.498449 148.97234)
		(end 200.434571 148.998799)
		(width 0.1)
		(layer "In5.Cu")
		(net 513)
	)
	(segment
		(start 199.95 147.95)
		(end 200.4 147.95)
		(width 0.1)
		(layer "In5.Cu")
		(net 513)
	)
	(segment
		(start 200.54734 146.823449)
		(end 200.498449 146.87234)
		(width 0.1)
		(layer "In5.Cu")
		(net 513)
	)
	(segment
		(start 199.95 149.35)
		(end 200.4 149.35)
		(width 0.1)
		(layer "In5.Cu")
		(net 513)
	)
	(segment
		(start 216.825 151.824503)
		(end 217.3 151.349503)
		(width 0.1)
		(layer "In5.Cu")
		(net 513)
	)
	(segment
		(start 200.4 149.35)
		(end 200.434571 149.351201)
		(width 0.1)
		(layer "In5.Cu")
		(net 513)
	)
	(segment
		(start 200.575 147.425)
		(end 200.573799 147.459571)
		(width 0.1)
		(layer "In5.Cu")
		(net 513)
	)
	(segment
		(start 200.498449 149.67234)
		(end 200.434571 149.698799)
		(width 0.1)
		(layer "In5.Cu")
		(net 513)
	)
	(segment
		(start 200.4 149.7)
		(end 199.95 149.7)
		(width 0.1)
		(layer "In5.Cu")
		(net 513)
	)
	(segment
		(start 212.50993 156.390073)
		(end 212.509928 156.390072)
		(width 0.1)
		(layer "In5.Cu")
		(net 513)
	)
	(segment
		(start 199.776201 147.809571)
		(end 199.80266 147.873449)
		(width 0.1)
		(layer "In5.Cu")
		(net 513)
	)
	(segment
		(start 199.775 148.475)
		(end 199.776201 148.509571)
		(width 0.1)
		(layer "In5.Cu")
		(net 513)
	)
	(segment
		(start 199.915429 147.948799)
		(end 199.95 147.95)
		(width 0.1)
		(layer "In5.Cu")
		(net 513)
	)
	(segment
		(start 211.025 157.627514)
		(end 211.025001 157.627512)
		(width 0.1)
		(layer "In5.Cu")
		(net 513)
	)
	(segment
		(start 200.498449 147.57234)
		(end 200.434571 147.598799)
		(width 0.1)
		(layer "In5.Cu")
		(net 513)
	)
	(segment
		(start 199.776201 147.740429)
		(end 199.775 147.775)
		(width 0.1)
		(layer "In5.Cu")
		(net 513)
	)
	(segment
		(start 199.851551 148.62234)
		(end 199.915429 148.648799)
		(width 0.1)
		(layer "In5.Cu")
		(net 513)
	)
	(segment
		(start 200.54734 148.223449)
		(end 200.498449 148.27234)
		(width 0.1)
		(layer "In5.Cu")
		(net 513)
	)
	(segment
		(start 199.775 146.132842)
		(end 199.775 146.375)
		(width 0.1)
		(layer "In5.Cu")
		(net 513)
	)
	(segment
		(start 199.80266 148.376551)
		(end 199.776201 148.440429)
		(width 0.1)
		(layer "In5.Cu")
		(net 513)
	)
	(segment
		(start 200.498449 146.87234)
		(end 200.434571 146.898799)
		(width 0.1)
		(layer "In5.Cu")
		(net 513)
	)
	(segment
		(start 200.434571 148.651201)
		(end 200.498449 148.67766)
		(width 0.1)
		(layer "In5.Cu")
		(net 513)
	)
	(segment
		(start 199.776201 146.409571)
		(end 199.80266 146.473449)
		(width 0.1)
		(layer "In5.Cu")
		(net 513)
	)
	(segment
		(start 200.575 148.125)
		(end 200.573799 148.159571)
		(width 0.1)
		(layer "In5.Cu")
		(net 513)
	)
	(segment
		(start 199.776201 150.101201)
		(end 202.375 152.7)
		(width 0.1)
		(layer "In5.Cu")
		(net 513)
	)
	(segment
		(start 199.95 147.6)
		(end 199.915429 147.601201)
		(width 0.1)
		(layer "In5.Cu")
		(net 513)
	)
	(segment
		(start 199.776201 148.509571)
		(end 199.80266 148.573449)
		(width 0.1)
		(layer "In5.Cu")
		(net 513)
	)
	(segment
		(start 212.014954 156.885049)
		(end 212.014952 156.885048)
		(width 0.1)
		(layer "In5.Cu")
		(net 513)
	)
	(segment
		(start 213.004905 155.895098)
		(end 213.004906 155.895097)
		(width 0.1)
		(layer "In5.Cu")
		(net 513)
	)
	(segment
		(start 212.509929 156.142584)
		(end 211.71855 155.351205)
		(width 0.1)
		(layer "In5.Cu")
		(net 513)
	)
	(segment
		(start 199.775 147.775)
		(end 199.776201 147.809571)
		(width 0.1)
		(layer "In5.Cu")
		(net 513)
	)
	(segment
		(start 200.4 147.6)
		(end 199.95 147.6)
		(width 0.1)
		(layer "In5.Cu")
		(net 513)
	)
	(segment
		(start 199.851551 148.32766)
		(end 199.80266 148.376551)
		(width 0.1)
		(layer "In5.Cu")
		(net 513)
	)
	(segment
		(start 199.80266 149.776551)
		(end 199.776201 149.840429)
		(width 0.1)
		(layer "In5.Cu")
		(net 513)
	)
	(segment
		(start 199.776201 149.140429)
		(end 199.775 149.175)
		(width 0.1)
		(layer "In5.Cu")
		(net 513)
	)
	(segment
		(start 200.54734 149.426551)
		(end 200.573799 149.490429)
		(width 0.1)
		(layer "In5.Cu")
		(net 513)
	)
	(segment
		(start 199.95 149.7)
		(end 199.915429 149.701201)
		(width 0.1)
		(layer "In5.Cu")
		(net 513)
	)
	(segment
		(start 200.434571 148.298799)
		(end 200.4 148.3)
		(width 0.1)
		(layer "In5.Cu")
		(net 513)
	)
	(segment
		(start 200.434571 149.351201)
		(end 200.498449 149.37766)
		(width 0.1)
		(layer "In5.Cu")
		(net 513)
	)
	(segment
		(start 212.014952 156.637562)
		(end 212.014953 156.63756)
		(width 0.1)
		(layer "In5.Cu")
		(net 513)
	)
	(segment
		(start 199.851551 146.92766)
		(end 199.80266 146.976551)
		(width 0.1)
		(layer "In5.Cu")
		(net 513)
	)
	(segment
		(start 200.575 138.675)
		(end 200.575 145.332842)
		(width 0.1)
		(layer "In5.Cu")
		(net 513)
	)
	(segment
		(start 199.80266 149.076551)
		(end 199.776201 149.140429)
		(width 0.1)
		(layer "In5.Cu")
		(net 513)
	)
	(segment
		(start 213.313045 155.586955)
		(end 216.825 152.075)
		(width 0.1)
		(layer "In5.Cu")
		(net 513)
	)
	(segment
		(start 200.575 149.525)
		(end 200.573799 149.559571)
		(width 0.1)
		(layer "In5.Cu")
		(net 513)
	)
	(segment
		(start 200.498449 147.97766)
		(end 200.54734 148.026551)
		(width 0.1)
		(layer "In5.Cu")
		(net 513)
	)
	(segment
		(start 200.498449 148.67766)
		(end 200.54734 148.726551)
		(width 0.1)
		(layer "In5.Cu")
		(net 513)
	)
	(segment
		(start 199.915429 147.601201)
		(end 199.851551 147.62766)
		(width 0.1)
		(layer "In5.Cu")
		(net 513)
	)
	(segment
		(start 199.80266 146.976551)
		(end 199.776201 147.040429)
		(width 0.1)
		(layer "In5.Cu")
		(net 513)
	)
	(arc
		(start 210.728598 156.341157)
		(mid 210.677341 156.217414)
		(end 210.728597 156.09367)
		(width 0.1)
		(layer "In5.Cu")
		(net 513)
	)
	(arc
		(start 212.509928 156.390072)
		(mid 212.561185 156.266328)
		(end 212.509928 156.142586)
		(width 0.1)
		(layer "In5.Cu")
		(net 513)
	)
	(arc
		(start 212.757418 155.895097)
		(mid 212.881161 155.946354)
		(end 213.004905 155.895098)
		(width 0.1)
		(layer "In5.Cu")
		(net 513)
	)
	(arc
		(start 212.014952 156.885048)
		(mid 212.066209 156.761304)
		(end 212.014952 156.637562)
		(width 0.1)
		(layer "In5.Cu")
		(net 513)
	)
	(arc
		(start 211.27249 157.380025)
		(mid 211.396233 157.431282)
		(end 211.519977 157.380026)
		(width 0.1)
		(layer "In5.Cu")
		(net 513)
	)
	(arc
		(start 210.233622 156.588645)
		(mid 210.357366 156.537389)
		(end 210.48111 156.588645)
		(width 0.1)
		(layer "In5.Cu")
		(net 513)
	)
	(arc
		(start 211.71855 155.103717)
		(mid 211.842294 155.052461)
		(end 211.966038 155.103717)
		(width 0.1)
		(layer "In5.Cu")
		(net 513)
	)
	(arc
		(start 211.519976 157.380024)
		(mid 211.571233 157.25628)
		(end 211.519976 157.132538)
		(width 0.1)
		(layer "In5.Cu")
		(net 513)
	)
	(arc
		(start 211.025 157.875)
		(mid 211.076257 157.751256)
		(end 211.025 157.627514)
		(width 0.1)
		(layer "In5.Cu")
		(net 513)
	)
	(arc
		(start 211.767466 156.885049)
		(mid 211.891209 156.936306)
		(end 212.014953 156.88505)
		(width 0.1)
		(layer "In5.Cu")
		(net 513)
	)
	(arc
		(start 212.262442 156.390073)
		(mid 212.386185 156.44133)
		(end 212.509929 156.390074)
		(width 0.1)
		(layer "In5.Cu")
		(net 513)
	)
	(arc
		(start 210.233622 156.836133)
		(mid 210.182365 156.71239)
		(end 210.233621 156.588646)
		(width 0.1)
		(layer "In5.Cu")
		(net 513)
	)
	(arc
		(start 210.728598 156.093669)
		(mid 210.852342 156.042413)
		(end 210.976086 156.093669)
		(width 0.1)
		(layer "In5.Cu")
		(net 513)
	)
	(arc
		(start 211.223574 155.846181)
		(mid 211.172317 155.722438)
		(end 211.223573 155.598694)
		(width 0.1)
		(layer "In5.Cu")
		(net 513)
	)
	(arc
		(start 211.223574 155.598693)
		(mid 211.347318 155.547437)
		(end 211.471062 155.598693)
		(width 0.1)
		(layer "In5.Cu")
		(net 513)
	)
	(arc
		(start 211.71855 155.351205)
		(mid 211.667293 155.227462)
		(end 211.718549 155.103718)
		(width 0.1)
		(layer "In5.Cu")
		(net 513)
	)
	(segment
		(start 167.080001 80.600001)
		(end 166.445001 81.235001)
		(width 0.201)
		(layer "F.Cu")
		(net 514)
	)
	(segment
		(start 203.5 123.5)
		(end 204 123)
		(width 0.256)
		(layer "F.Cu")
		(net 514)
	)
	(via
		(at 167.080001 80.600001)
		(size 0.45)
		(drill 0.2)
		(layers "F.Cu" "B.Cu")
		(net 514)
	)
	(via
		(at 204 123)
		(size 0.45)
		(drill 0.2)
		(layers "F.Cu" "B.Cu")
		(net 514)
	)
	(segment
		(start 207.8 103.5)
		(end 208.5 102.8)
		(width 0.1)
		(layer "In7.Cu")
		(net 514)
	)
	(segment
		(start 204 123)
		(end 204.4 123.4)
		(width 0.1)
		(layer "In7.Cu")
		(net 514)
	)
	(segment
		(start 183.5 78.3)
		(end 182.2 77)
		(width 0.1)
		(layer "In7.Cu")
		(net 514)
	)
	(segment
		(start 199.5 84.8)
		(end 199.5 81.5)
		(width 0.1)
		(layer "In7.Cu")
		(net 514)
	)
	(segment
		(start 207.8 117.8)
		(end 208.4 117.2)
		(width 0.1)
		(layer "In7.Cu")
		(net 514)
	)
	(segment
		(start 199.5 81.5)
		(end 196.3 78.3)
		(width 0.1)
		(layer "In7.Cu")
		(net 514)
	)
	(segment
		(start 207.8 121.6)
		(end 207.8 117.8)
		(width 0.1)
		(layer "In7.Cu")
		(net 514)
	)
	(segment
		(start 204.4 86.4)
		(end 201.1 86.4)
		(width 0.1)
		(layer "In7.Cu")
		(net 514)
	)
	(segment
		(start 208.5 102.8)
		(end 208.5 90.5)
		(width 0.1)
		(layer "In7.Cu")
		(net 514)
	)
	(segment
		(start 170.680002 77)
		(end 167.080001 80.600001)
		(width 0.1)
		(layer "In7.Cu")
		(net 514)
	)
	(segment
		(start 182.2 77)
		(end 170.680002 77)
		(width 0.1)
		(layer "In7.Cu")
		(net 514)
	)
	(segment
		(start 208.5 90.5)
		(end 204.4 86.4)
		(width 0.1)
		(layer "In7.Cu")
		(net 514)
	)
	(segment
		(start 206 123.4)
		(end 207.8 121.6)
		(width 0.1)
		(layer "In7.Cu")
		(net 514)
	)
	(segment
		(start 208.4 112.2)
		(end 207.8 111.6)
		(width 0.1)
		(layer "In7.Cu")
		(net 514)
	)
	(segment
		(start 208.4 117.2)
		(end 208.4 112.2)
		(width 0.1)
		(layer "In7.Cu")
		(net 514)
	)
	(segment
		(start 201.1 86.4)
		(end 199.5 84.8)
		(width 0.1)
		(layer "In7.Cu")
		(net 514)
	)
	(segment
		(start 204.4 123.4)
		(end 206 123.4)
		(width 0.1)
		(layer "In7.Cu")
		(net 514)
	)
	(segment
		(start 207.8 111.6)
		(end 207.8 103.5)
		(width 0.1)
		(layer "In7.Cu")
		(net 514)
	)
	(segment
		(start 196.3 78.3)
		(end 183.5 78.3)
		(width 0.1)
		(layer "In7.Cu")
		(net 514)
	)
	(segment
		(start 217.296314 152.000217)
		(end 217.296314 152.181314)
		(width 0.184)
		(layer "F.Cu")
		(net 515)
	)
	(segment
		(start 198.5 138.5)
		(end 198 139)
		(width 0.256)
		(layer "F.Cu")
		(net 515)
	)
	(segment
		(start 217.296314 152.181314)
		(end 217.915 152.8)
		(width 0.184)
		(layer "F.Cu")
		(net 515)
	)
	(via
		(at 198 139)
		(size 0.45)
		(drill 0.2)
		(layers "F.Cu" "B.Cu")
		(net 515)
	)
	(via
		(at 217.296314 152.000217)
		(size 0.45)
		(drill 0.2)
		(layers "F.Cu" "B.Cu")
		(net 515)
	)
	(segment
		(start 202.175 157.725)
		(end 202.65 158.2)
		(width 0.1)
		(layer "In5.Cu")
		(net 515)
	)
	(segment
		(start 214.008127 155.53589)
		(end 214.008128 155.53589)
		(width 0.1)
		(layer "In5.Cu")
		(net 515)
	)
	(segment
		(start 199.575 146.049999)
		(end 199.575 150.2)
		(width 0.1)
		(layer "In5.Cu")
		(net 515)
	)
	(segment
		(start 213.548507 156.808683)
		(end 213.548508 156.808682)
		(width 0.1)
		(layer "In5.Cu")
		(net 515)
	)
	(segment
		(start 213.018178 156.52584)
		(end 213.30102 156.808682)
		(width 0.1)
		(layer "In5.Cu")
		(net 515)
	)
	(segment
		(start 202.175 152.8)
		(end 202.175 153.8)
		(width 0.1)
		(layer "In5.Cu")
		(net 515)
	)
	(segment
		(start 216.719669 153.524693)
		(end 216.719669 153.524694)
		(width 0.1)
		(layer "In5.Cu")
		(net 515)
	)
	(segment
		(start 211.533252 158.010765)
		(end 211.533253 158.010765)
		(width 0.1)
		(layer "In5.Cu")
		(net 515)
	)
	(segment
		(start 214.538458 155.571244)
		(end 214.255615 155.288401)
		(width 0.1)
		(layer "In5.Cu")
		(net 515)
	)
	(segment
		(start 214.043482 156.313708)
		(end 214.043483 156.313707)
		(width 0.1)
		(layer "In5.Cu")
		(net 515)
	)
	(segment
		(start 216.719669 153.277206)
		(end 216.493239 153.050776)
		(width 0.1)
		(layer "In5.Cu")
		(net 515)
	)
	(segment
		(start 212.770689 156.525839)
		(end 212.77069 156.525838)
		(width 0.1)
		(layer "In5.Cu")
		(net 515)
	)
	(segment
		(start 212.275714 157.020814)
		(end 212.275715 157.020813)
		(width 0.1)
		(layer "In5.Cu")
		(net 515)
	)
	(segment
		(start 198.4 138.6)
		(end 200.2 138.6)
		(width 0.1)
		(layer "In5.Cu")
		(net 515)
	)
	(segment
		(start 216.245753 153.298265)
		(end 216.472182 153.524694)
		(width 0.1)
		(layer "In5.Cu")
		(net 515)
	)
	(segment
		(start 213.76064 155.535888)
		(end 213.760641 155.53589)
		(width 0.1)
		(layer "In5.Cu")
		(net 515)
	)
	(segment
		(start 214.255614 155.040914)
		(end 214.255615 155.040913)
		(width 0.1)
		(layer "In5.Cu")
		(net 515)
	)
	(segment
		(start 213.513153 156.030865)
		(end 213.795995 156.313707)
		(width 0.1)
		(layer "In5.Cu")
		(net 515)
	)
	(segment
		(start 213.053533 157.056169)
		(end 212.77069 156.773326)
		(width 0.1)
		(layer "In5.Cu")
		(net 515)
	)
	(segment
		(start 212.275715 157.020813)
		(end 212.275716 157.020815)
		(width 0.1)
		(layer "In5.Cu")
		(net 515)
	)
	(segment
		(start 198 139)
		(end 198.4 138.6)
		(width 0.1)
		(layer "In5.Cu")
		(net 515)
	)
	(segment
		(start 212.028227 157.51579)
		(end 212.028228 157.51579)
		(width 0.1)
		(layer "In5.Cu")
		(net 515)
	)
	(segment
		(start 215.21824 154.078288)
		(end 215.998266 153.298265)
		(width 0.1)
		(layer "In5.Cu")
		(net 515)
	)
	(segment
		(start 212.523202 157.020815)
		(end 212.523203 157.020815)
		(width 0.1)
		(layer "In5.Cu")
		(net 515)
	)
	(segment
		(start 213.760639 155.535889)
		(end 213.76064 155.535888)
		(width 0.1)
		(layer "In5.Cu")
		(net 515)
	)
	(segment
		(start 215.218239 154.078289)
		(end 215.21824 154.078288)
		(width 0.1)
		(layer "In5.Cu")
		(net 515)
	)
	(segment
		(start 200.375 145.25)
		(end 199.575 146.049999)
		(width 0.1)
		(layer "In5.Cu")
		(net 515)
	)
	(segment
		(start 202 154.675)
		(end 201.35 154.675)
		(width 0.1)
		(layer "In5.Cu")
		(net 515)
	)
	(segment
		(start 216.988214 152.308314)
		(end 217.296314 152.000217)
		(width 0.1)
		(layer "In5.Cu")
		(net 515)
	)
	(segment
		(start 212.063583 158.046119)
		(end 211.78074 157.763276)
		(width 0.1)
		(layer "In5.Cu")
		(net 515)
	)
	(segment
		(start 202.175 157.3)
		(end 202.175 157.725)
		(width 0.1)
		(layer "In5.Cu")
		(net 515)
	)
	(segment
		(start 212.063582 158.293608)
		(end 212.063583 158.293607)
		(width 0.1)
		(layer "In5.Cu")
		(net 515)
	)
	(segment
		(start 213.018177 156.52584)
		(end 213.018178 156.52584)
		(width 0.1)
		(layer "In5.Cu")
		(net 515)
	)
	(segment
		(start 214.255615 155.040913)
		(end 214.723266 154.573265)
		(width 0.1)
		(layer "In5.Cu")
		(net 515)
	)
	(segment
		(start 211.780739 157.515789)
		(end 211.78074 157.515788)
		(width 0.1)
		(layer "In5.Cu")
		(net 515)
	)
	(segment
		(start 212.028228 157.51579)
		(end 212.31107 157.798632)
		(width 0.1)
		(layer "In5.Cu")
		(net 515)
	)
	(segment
		(start 214.538457 155.818733)
		(end 214.538458 155.818732)
		(width 0.1)
		(layer "In5.Cu")
		(net 515)
	)
	(segment
		(start 213.265664 156.030864)
		(end 213.265665 156.030863)
		(width 0.1)
		(layer "In5.Cu")
		(net 515)
	)
	(segment
		(start 199.575 150.2)
		(end 202.175 152.8)
		(width 0.1)
		(layer "In5.Cu")
		(net 515)
	)
	(segment
		(start 215.501083 154.608619)
		(end 215.21824 154.325776)
		(width 0.1)
		(layer "In5.Cu")
		(net 515)
	)
	(segment
		(start 217.214644 153.029718)
		(end 217.214644 153.029719)
		(width 0.1)
		(layer "In5.Cu")
		(net 515)
	)
	(segment
		(start 216.740728 152.80329)
		(end 216.967157 153.029719)
		(width 0.1)
		(layer "In5.Cu")
		(net 515)
	)
	(segment
		(start 216.49324 152.803289)
		(end 216.493239 152.803289)
		(width 0.1)
		(layer "In5.Cu")
		(net 515)
	)
	(segment
		(start 213.053532 157.303658)
		(end 213.053533 157.303657)
		(width 0.1)
		(layer "In5.Cu")
		(net 515)
	)
	(segment
		(start 216.245752 153.298265)
		(end 216.245753 153.298265)
		(width 0.1)
		(layer "In5.Cu")
		(net 515)
	)
	(segment
		(start 212.558557 157.798633)
		(end 212.558558 157.798632)
		(width 0.1)
		(layer "In5.Cu")
		(net 515)
	)
	(segment
		(start 216.988215 152.308314)
		(end 216.988214 152.308314)
		(width 0.1)
		(layer "In5.Cu")
		(net 515)
	)
	(segment
		(start 201.35 157.125)
		(end 202 157.125)
		(width 0.1)
		(layer "In5.Cu")
		(net 515)
	)
	(segment
		(start 212.558558 157.551144)
		(end 212.275715 157.268301)
		(width 0.1)
		(layer "In5.Cu")
		(net 515)
	)
	(segment
		(start 201.35 154.325)
		(end 202 154.325)
		(width 0.1)
		(layer "In5.Cu")
		(net 515)
	)
	(segment
		(start 202 156.775)
		(end 201.35 156.775)
		(width 0.1)
		(layer "In5.Cu")
		(net 515)
	)
	(segment
		(start 213.265665 156.030863)
		(end 213.265666 156.030865)
		(width 0.1)
		(layer "In5.Cu")
		(net 515)
	)
	(segment
		(start 202 156.075)
		(end 201.35 156.075)
		(width 0.1)
		(layer "In5.Cu")
		(net 515)
	)
	(segment
		(start 214.043483 156.066219)
		(end 213.76064 155.783376)
		(width 0.1)
		(layer "In5.Cu")
		(net 515)
	)
	(segment
		(start 213.513152 156.030865)
		(end 213.513153 156.030865)
		(width 0.1)
		(layer "In5.Cu")
		(net 515)
	)
	(segment
		(start 201.35 156.425)
		(end 202 156.425)
		(width 0.1)
		(layer "In5.Cu")
		(net 515)
	)
	(segment
		(start 212.523203 157.020815)
		(end 212.806045 157.303657)
		(width 0.1)
		(layer "In5.Cu")
		(net 515)
	)
	(segment
		(start 211.533253 158.010765)
		(end 211.816095 158.293607)
		(width 0.1)
		(layer "In5.Cu")
		(net 515)
	)
	(segment
		(start 213.548508 156.561194)
		(end 213.265665 156.278351)
		(width 0.1)
		(layer "In5.Cu")
		(net 515)
	)
	(segment
		(start 214.008128 155.53589)
		(end 214.29097 155.818732)
		(width 0.1)
		(layer "In5.Cu")
		(net 515)
	)
	(segment
		(start 216.740727 152.80329)
		(end 216.740728 152.80329)
		(width 0.1)
		(layer "In5.Cu")
		(net 515)
	)
	(segment
		(start 202.65 158.2)
		(end 211.096531 158.2)
		(width 0.1)
		(layer "In5.Cu")
		(net 515)
	)
	(segment
		(start 202 153.975)
		(end 201.35 153.975)
		(width 0.1)
		(layer "In5.Cu")
		(net 515)
	)
	(segment
		(start 201.35 155.725)
		(end 202 155.725)
		(width 0.1)
		(layer "In5.Cu")
		(net 515)
	)
	(segment
		(start 211.78074 157.515788)
		(end 211.780741 157.51579)
		(width 0.1)
		(layer "In5.Cu")
		(net 515)
	)
	(segment
		(start 214.970753 154.573265)
		(end 215.253595 154.856107)
		(width 0.1)
		(layer "In5.Cu")
		(net 515)
	)
	(segment
		(start 200.2 138.6)
		(end 200.375 138.775)
		(width 0.1)
		(layer "In5.Cu")
		(net 515)
	)
	(segment
		(start 211.096531 158.2)
		(end 211.285766 158.010765)
		(width 0.1)
		(layer "In5.Cu")
		(net 515)
	)
	(segment
		(start 215.501082 154.856108)
		(end 215.501083 154.856107)
		(width 0.1)
		(layer "In5.Cu")
		(net 515)
	)
	(segment
		(start 200.375 138.775)
		(end 200.375 145.25)
		(width 0.1)
		(layer "In5.Cu")
		(net 515)
	)
	(segment
		(start 201.35 155.025)
		(end 202 155.025)
		(width 0.1)
		(layer "In5.Cu")
		(net 515)
	)
	(segment
		(start 212.77069 156.525838)
		(end 212.770691 156.52584)
		(width 0.1)
		(layer "In5.Cu")
		(net 515)
	)
	(segment
		(start 202 155.375)
		(end 201.35 155.375)
		(width 0.1)
		(layer "In5.Cu")
		(net 515)
	)
	(segment
		(start 216.493239 152.803289)
		(end 216.493241 152.80329)
		(width 0.1)
		(layer "In5.Cu")
		(net 515)
	)
	(segment
		(start 217.214644 152.782231)
		(end 216.988214 152.555801)
		(width 0.1)
		(layer "In5.Cu")
		(net 515)
	)
	(segment
		(start 214.970752 154.573265)
		(end 214.970753 154.573265)
		(width 0.1)
		(layer "In5.Cu")
		(net 515)
	)
	(arc
		(start 202 155.725)
		(mid 202.123744 155.776256)
		(end 202.175 155.9)
		(width 0.1)
		(layer "In5.Cu")
		(net 515)
	)
	(arc
		(start 215.501083 154.856107)
		(mid 215.552339 154.732363)
		(end 215.501083 154.608619)
		(width 0.1)
		(layer "In5.Cu")
		(net 515)
	)
	(arc
		(start 213.265666 156.030865)
		(mid 213.389409 155.979609)
		(end 213.513152 156.030865)
		(width 0.1)
		(layer "In5.Cu")
		(net 515)
	)
	(arc
		(start 216.493241 152.80329)
		(mid 216.616984 152.752034)
		(end 216.740727 152.80329)
		(width 0.1)
		(layer "In5.Cu")
		(net 515)
	)
	(arc
		(start 202.175 153.8)
		(mid 202.123744 153.923744)
		(end 202 153.975)
		(width 0.1)
		(layer "In5.Cu")
		(net 515)
	)
	(arc
		(start 213.548508 156.808682)
		(mid 213.599764 156.684938)
		(end 213.548508 156.561194)
		(width 0.1)
		(layer "In5.Cu")
		(net 515)
	)
	(arc
		(start 215.998266 153.298265)
		(mid 216.122009 153.247009)
		(end 216.245752 153.298265)
		(width 0.1)
		(layer "In5.Cu")
		(net 515)
	)
	(arc
		(start 212.275715 157.268301)
		(mid 212.224458 157.144558)
		(end 212.275714 157.020814)
		(width 0.1)
		(layer "In5.Cu")
		(net 515)
	)
	(arc
		(start 215.253595 154.856107)
		(mid 215.377338 154.907364)
		(end 215.501082 154.856108)
		(width 0.1)
		(layer "In5.Cu")
		(net 515)
	)
	(arc
		(start 202 156.425)
		(mid 202.123744 156.476256)
		(end 202.175 156.6)
		(width 0.1)
		(layer "In5.Cu")
		(net 515)
	)
	(arc
		(start 202 157.125)
		(mid 202.123744 157.176256)
		(end 202.175 157.3)
		(width 0.1)
		(layer "In5.Cu")
		(net 515)
	)
	(arc
		(start 213.795995 156.313707)
		(mid 213.919738 156.364964)
		(end 214.043482 156.313708)
		(width 0.1)
		(layer "In5.Cu")
		(net 515)
	)
	(arc
		(start 213.76064 155.783376)
		(mid 213.709383 155.659633)
		(end 213.760639 155.535889)
		(width 0.1)
		(layer "In5.Cu")
		(net 515)
	)
	(arc
		(start 212.806045 157.303657)
		(mid 212.929788 157.354914)
		(end 213.053532 157.303658)
		(width 0.1)
		(layer "In5.Cu")
		(net 515)
	)
	(arc
		(start 212.31107 157.798632)
		(mid 212.434813 157.849889)
		(end 212.558557 157.798633)
		(width 0.1)
		(layer "In5.Cu")
		(net 515)
	)
	(arc
		(start 212.77069 156.773326)
		(mid 212.719433 156.649583)
		(end 212.770689 156.525839)
		(width 0.1)
		(layer "In5.Cu")
		(net 515)
	)
	(arc
		(start 214.29097 155.818732)
		(mid 214.414713 155.869989)
		(end 214.538457 155.818733)
		(width 0.1)
		(layer "In5.Cu")
		(net 515)
	)
	(arc
		(start 211.78074 157.763276)
		(mid 211.729483 157.639533)
		(end 211.780739 157.515789)
		(width 0.1)
		(layer "In5.Cu")
		(net 515)
	)
	(arc
		(start 201.35 156.775)
		(mid 201.226256 156.826256)
		(end 201.175 156.95)
		(width 0.1)
		(layer "In5.Cu")
		(net 515)
	)
	(arc
		(start 214.723266 154.573265)
		(mid 214.847009 154.522009)
		(end 214.970752 154.573265)
		(width 0.1)
		(layer "In5.Cu")
		(net 515)
	)
	(arc
		(start 217.214644 153.029719)
		(mid 217.2659 152.905975)
		(end 217.214644 152.782231)
		(width 0.1)
		(layer "In5.Cu")
		(net 515)
	)
	(arc
		(start 211.780741 157.51579)
		(mid 211.904484 157.464534)
		(end 212.028227 157.51579)
		(width 0.1)
		(layer "In5.Cu")
		(net 515)
	)
	(arc
		(start 201.35 155.375)
		(mid 201.226256 155.426256)
		(end 201.175 155.55)
		(width 0.1)
		(layer "In5.Cu")
		(net 515)
	)
	(arc
		(start 201.175 154.85)
		(mid 201.226256 154.973744)
		(end 201.35 155.025)
		(width 0.1)
		(layer "In5.Cu")
		(net 515)
	)
	(arc
		(start 202.175 155.2)
		(mid 202.123744 155.323744)
		(end 202 155.375)
		(width 0.1)
		(layer "In5.Cu")
		(net 515)
	)
	(arc
		(start 212.275716 157.020815)
		(mid 212.399459 156.969559)
		(end 212.523202 157.020815)
		(width 0.1)
		(layer "In5.Cu")
		(net 515)
	)
	(arc
		(start 212.770691 156.52584)
		(mid 212.894434 156.474584)
		(end 213.018177 156.52584)
		(width 0.1)
		(layer "In5.Cu")
		(net 515)
	)
	(arc
		(start 202 154.325)
		(mid 202.123744 154.376256)
		(end 202.175 154.5)
		(width 0.1)
		(layer "In5.Cu")
		(net 515)
	)
	(arc
		(start 202.175 156.6)
		(mid 202.123744 156.723744)
		(end 202 156.775)
		(width 0.1)
		(layer "In5.Cu")
		(net 515)
	)
	(arc
		(start 201.175 154.15)
		(mid 201.226256 154.273744)
		(end 201.35 154.325)
		(width 0.1)
		(layer "In5.Cu")
		(net 515)
	)
	(arc
		(start 211.285766 158.010765)
		(mid 211.409509 157.959509)
		(end 211.533252 158.010765)
		(width 0.1)
		(layer "In5.Cu")
		(net 515)
	)
	(arc
		(start 216.493239 153.050776)
		(mid 216.441983 152.927032)
		(end 216.49324 152.803289)
		(width 0.1)
		(layer "In5.Cu")
		(net 515)
	)
	(arc
		(start 213.760641 155.53589)
		(mid 213.884384 155.484634)
		(end 214.008127 155.53589)
		(width 0.1)
		(layer "In5.Cu")
		(net 515)
	)
	(arc
		(start 201.35 154.675)
		(mid 201.226256 154.726256)
		(end 201.175 154.85)
		(width 0.1)
		(layer "In5.Cu")
		(net 515)
	)
	(arc
		(start 202.175 155.9)
		(mid 202.123744 156.023744)
		(end 202 156.075)
		(width 0.1)
		(layer "In5.Cu")
		(net 515)
	)
	(arc
		(start 214.538458 155.818732)
		(mid 214.589714 155.694988)
		(end 214.538458 155.571244)
		(width 0.1)
		(layer "In5.Cu")
		(net 515)
	)
	(arc
		(start 212.558558 157.798632)
		(mid 212.609814 157.674888)
		(end 212.558558 157.551144)
		(width 0.1)
		(layer "In5.Cu")
		(net 515)
	)
	(arc
		(start 216.472182 153.524694)
		(mid 216.595926 153.57595)
		(end 216.719669 153.524693)
		(width 0.1)
		(layer "In5.Cu")
		(net 515)
	)
	(arc
		(start 216.967157 153.029719)
		(mid 217.090901 153.080975)
		(end 217.214644 153.029718)
		(width 0.1)
		(layer "In5.Cu")
		(net 515)
	)
	(arc
		(start 202 155.025)
		(mid 202.123744 155.076256)
		(end 202.175 155.2)
		(width 0.1)
		(layer "In5.Cu")
		(net 515)
	)
	(arc
		(start 201.175 155.55)
		(mid 201.226256 155.673744)
		(end 201.35 155.725)
		(width 0.1)
		(layer "In5.Cu")
		(net 515)
	)
	(arc
		(start 214.043483 156.313707)
		(mid 214.094739 156.189963)
		(end 214.043483 156.066219)
		(width 0.1)
		(layer "In5.Cu")
		(net 515)
	)
	(arc
		(start 216.988214 152.555801)
		(mid 216.936958 152.432057)
		(end 216.988215 152.308314)
		(width 0.1)
		(layer "In5.Cu")
		(net 515)
	)
	(arc
		(start 213.053533 157.303657)
		(mid 213.104789 157.179913)
		(end 213.053533 157.056169)
		(width 0.1)
		(layer "In5.Cu")
		(net 515)
	)
	(arc
		(start 211.816095 158.293607)
		(mid 211.939838 158.344864)
		(end 212.063582 158.293608)
		(width 0.1)
		(layer "In5.Cu")
		(net 515)
	)
	(arc
		(start 214.255615 155.288401)
		(mid 214.204358 155.164658)
		(end 214.255614 155.040914)
		(width 0.1)
		(layer "In5.Cu")
		(net 515)
	)
	(arc
		(start 215.21824 154.325776)
		(mid 215.166983 154.202033)
		(end 215.218239 154.078289)
		(width 0.1)
		(layer "In5.Cu")
		(net 515)
	)
	(arc
		(start 213.30102 156.808682)
		(mid 213.424763 156.859939)
		(end 213.548507 156.808683)
		(width 0.1)
		(layer "In5.Cu")
		(net 515)
	)
	(arc
		(start 212.063583 158.293607)
		(mid 212.114839 158.169863)
		(end 212.063583 158.046119)
		(width 0.1)
		(layer "In5.Cu")
		(net 515)
	)
	(arc
		(start 202.175 154.5)
		(mid 202.123744 154.623744)
		(end 202 154.675)
		(width 0.1)
		(layer "In5.Cu")
		(net 515)
	)
	(arc
		(start 201.175 156.25)
		(mid 201.226256 156.373744)
		(end 201.35 156.425)
		(width 0.1)
		(layer "In5.Cu")
		(net 515)
	)
	(arc
		(start 213.265665 156.278351)
		(mid 213.214408 156.154608)
		(end 213.265664 156.030864)
		(width 0.1)
		(layer "In5.Cu")
		(net 515)
	)
	(arc
		(start 216.719669 153.524694)
		(mid 216.770925 153.40095)
		(end 216.719669 153.277206)
		(width 0.1)
		(layer "In5.Cu")
		(net 515)
	)
	(arc
		(start 201.35 153.975)
		(mid 201.226256 154.026256)
		(end 201.175 154.15)
		(width 0.1)
		(layer "In5.Cu")
		(net 515)
	)
	(arc
		(start 201.35 156.075)
		(mid 201.226256 156.126256)
		(end 201.175 156.25)
		(width 0.1)
		(layer "In5.Cu")
		(net 515)
	)
	(arc
		(start 201.175 156.95)
		(mid 201.226256 157.073744)
		(end 201.35 157.125)
		(width 0.1)
		(layer "In5.Cu")
		(net 515)
	)
	(segment
		(start 202 138)
		(end 202 138.04)
		(width 0.256)
		(layer "F.Cu")
		(net 516)
	)
	(segment
		(start 201.5 137.5)
		(end 202 138)
		(width 0.256)
		(layer "F.Cu")
		(net 516)
	)
	(segment
		(start 217.3 148.8)
		(end 217.915 148.8)
		(width 0.184)
		(layer "F.Cu")
		(net 516)
	)
	(via
		(at 202 138.04)
		(size 0.45)
		(drill 0.2)
		(layers "F.Cu" "B.Cu")
		(net 516)
	)
	(via
		(at 217.3 148.8)
		(size 0.45)
		(drill 0.2)
		(layers "F.Cu" "B.Cu")
		(net 516)
	)
	(segment
		(start 219 149.05)
		(end 218.75 148.8)
		(width 0.1)
		(layer "In5.Cu")
		(net 516)
	)
	(segment
		(start 218.75 148.8)
		(end 217.3 148.8)
		(width 0.1)
		(layer "In5.Cu")
		(net 516)
	)
	(segment
		(start 202.025 141.45)
		(end 201.775 141.45)
		(width 0.1)
		(layer "In5.Cu")
		(net 516)
	)
	(segment
		(start 207.717158 157.5)
		(end 211.317158 153.9)
		(width 0.1)
		(layer "In5.Cu")
		(net 516)
	)
	(segment
		(start 202 138.04)
		(end 201.6 138.44)
		(width 0.1)
		(layer "In5.Cu")
		(net 516)
	)
	(segment
		(start 201.6 139.275)
		(end 201.6 140.225)
		(width 0.1)
		(layer "In5.Cu")
		(net 516)
	)
	(segment
		(start 201.775 149.525)
		(end 202.025 149.525)
		(width 0.1)
		(layer "In5.Cu")
		(net 516)
	)
	(segment
		(start 211.317158 153.9)
		(end 213.669668 153.9)
		(width 0.1)
		(layer "In5.Cu")
		(net 516)
	)
	(segment
		(start 203.15 157.5)
		(end 207.717158 157.5)
		(width 0.1)
		(layer "In5.Cu")
		(net 516)
	)
	(segment
		(start 202.025 139.1)
		(end 201.775 139.1)
		(width 0.1)
		(layer "In5.Cu")
		(net 516)
	)
	(segment
		(start 201.6 150.05)
		(end 201.6 151.125)
		(width 0.1)
		(layer "In5.Cu")
		(net 516)
	)
	(segment
		(start 201.6 148.075)
		(end 201.6 148.65)
		(width 0.1)
		(layer "In5.Cu")
		(net 516)
	)
	(segment
		(start 201.6 141.625)
		(end 201.6 145.275)
		(width 0.1)
		(layer "In5.Cu")
		(net 516)
	)
	(segment
		(start 202.025 149.875)
		(end 201.775 149.875)
		(width 0.1)
		(layer "In5.Cu")
		(net 516)
	)
	(segment
		(start 219 150.2)
		(end 219 149.05)
		(width 0.1)
		(layer "In5.Cu")
		(net 516)
	)
	(segment
		(start 201.6 151.125)
		(end 202.775 152.3)
		(width 0.1)
		(layer "In5.Cu")
		(net 516)
	)
	(segment
		(start 201.775 140.4)
		(end 202.025 140.4)
		(width 0.1)
		(layer "In5.Cu")
		(net 516)
	)
	(segment
		(start 201.775 146.85)
		(end 202.025 146.85)
		(width 0.1)
		(layer "In5.Cu")
		(net 516)
	)
	(segment
		(start 217.625 150.125)
		(end 217.625 149.781577)
		(width 0.1)
		(layer "In5.Cu")
		(net 516)
	)
	(segment
		(start 201.6 138.44)
		(end 201.6 138.575)
		(width 0.1)
		(layer "In5.Cu")
		(net 516)
	)
	(segment
		(start 201.775 138.75)
		(end 202.025 138.75)
		(width 0.1)
		(layer "In5.Cu")
		(net 516)
	)
	(segment
		(start 213.739834 153.829834)
		(end 217.144669 150.425)
		(width 0.1)
		(layer "In5.Cu")
		(net 516)
	)
	(segment
		(start 202.775 157.125)
		(end 203.15 157.5)
		(width 0.1)
		(layer "In5.Cu")
		(net 516)
	)
	(segment
		(start 218.775 150.425)
		(end 219 150.2)
		(width 0.1)
		(layer "In5.Cu")
		(net 516)
	)
	(segment
		(start 202.025 145.8)
		(end 201.775 145.8)
		(width 0.1)
		(layer "In5.Cu")
		(net 516)
	)
	(segment
		(start 202.025 146.5)
		(end 201.775 146.5)
		(width 0.1)
		(layer "In5.Cu")
		(net 516)
	)
	(segment
		(start 202.025 147.9)
		(end 201.775 147.9)
		(width 0.1)
		(layer "In5.Cu")
		(net 516)
	)
	(segment
		(start 202.775 152.3)
		(end 202.775 157.125)
		(width 0.1)
		(layer "In5.Cu")
		(net 516)
	)
	(segment
		(start 218.525 150.425)
		(end 218.775 150.425)
		(width 0.1)
		(layer "In5.Cu")
		(net 516)
	)
	(segment
		(start 201.775 146.15)
		(end 202.025 146.15)
		(width 0.1)
		(layer "In5.Cu")
		(net 516)
	)
	(segment
		(start 201.775 148.825)
		(end 202.025 148.825)
		(width 0.1)
		(layer "In5.Cu")
		(net 516)
	)
	(segment
		(start 202.025 147.2)
		(end 201.775 147.2)
		(width 0.1)
		(layer "In5.Cu")
		(net 516)
	)
	(segment
		(start 201.775 145.45)
		(end 202.025 145.45)
		(width 0.1)
		(layer "In5.Cu")
		(net 516)
	)
	(segment
		(start 218.225 149.781577)
		(end 218.225 150.125)
		(width 0.1)
		(layer "In5.Cu")
		(net 516)
	)
	(segment
		(start 217.144669 150.425)
		(end 217.325 150.425)
		(width 0.1)
		(layer "In5.Cu")
		(net 516)
	)
	(segment
		(start 201.775 147.55)
		(end 202.025 147.55)
		(width 0.1)
		(layer "In5.Cu")
		(net 516)
	)
	(segment
		(start 213.669668 153.9)
		(end 213.739834 153.829834)
		(width 0.1)
		(layer "In5.Cu")
		(net 516)
	)
	(segment
		(start 202.025 140.75)
		(end 201.775 140.75)
		(width 0.1)
		(layer "In5.Cu")
		(net 516)
	)
	(segment
		(start 202.025 149.175)
		(end 201.775 149.175)
		(width 0.1)
		(layer "In5.Cu")
		(net 516)
	)
	(segment
		(start 201.775 141.1)
		(end 202.025 141.1)
		(width 0.1)
		(layer "In5.Cu")
		(net 516)
	)
	(arc
		(start 202.025 147.55)
		(mid 202.148744 147.601256)
		(end 202.2 147.725)
		(width 0.1)
		(layer "In5.Cu")
		(net 516)
	)
	(arc
		(start 202.2 141.275)
		(mid 202.148744 141.398744)
		(end 202.025 141.45)
		(width 0.1)
		(layer "In5.Cu")
		(net 516)
	)
	(arc
		(start 202.2 146.325)
		(mid 202.148744 146.448744)
		(end 202.025 146.5)
		(width 0.1)
		(layer "In5.Cu")
		(net 516)
	)
	(arc
		(start 202.025 145.45)
		(mid 202.148744 145.501256)
		(end 202.2 145.625)
		(width 0.1)
		(layer "In5.Cu")
		(net 516)
	)
	(arc
		(start 202.025 138.75)
		(mid 202.148744 138.801256)
		(end 202.2 138.925)
		(width 0.1)
		(layer "In5.Cu")
		(net 516)
	)
	(arc
		(start 218.225 150.125)
		(mid 218.312868 150.337132)
		(end 218.525 150.425)
		(width 0.1)
		(layer "In5.Cu")
		(net 516)
	)
	(arc
		(start 202.025 146.85)
		(mid 202.148744 146.901256)
		(end 202.2 147.025)
		(width 0.1)
		(layer "In5.Cu")
		(net 516)
	)
	(arc
		(start 217.325 150.425)
		(mid 217.537132 150.337132)
		(end 217.625 150.125)
		(width 0.1)
		(layer "In5.Cu")
		(net 516)
	)
	(arc
		(start 202.025 148.825)
		(mid 202.148744 148.876256)
		(end 202.2 149)
		(width 0.1)
		(layer "In5.Cu")
		(net 516)
	)
	(arc
		(start 217.925 149.481577)
		(mid 218.137132 149.569445)
		(end 218.225 149.781577)
		(width 0.1)
		(layer "In5.Cu")
		(net 516)
	)
	(arc
		(start 201.775 140.75)
		(mid 201.651256 140.801256)
		(end 201.6 140.925)
		(width 0.1)
		(layer "In5.Cu")
		(net 516)
	)
	(arc
		(start 201.775 147.9)
		(mid 201.651256 147.951256)
		(end 201.6 148.075)
		(width 0.1)
		(layer "In5.Cu")
		(net 516)
	)
	(arc
		(start 201.775 147.2)
		(mid 201.651256 147.251256)
		(end 201.6 147.375)
		(width 0.1)
		(layer "In5.Cu")
		(net 516)
	)
	(arc
		(start 201.6 140.225)
		(mid 201.651256 140.348744)
		(end 201.775 140.4)
		(width 0.1)
		(layer "In5.Cu")
		(net 516)
	)
	(arc
		(start 201.6 145.275)
		(mid 201.651256 145.398744)
		(end 201.775 145.45)
		(width 0.1)
		(layer "In5.Cu")
		(net 516)
	)
	(arc
		(start 201.775 149.175)
		(mid 201.651256 149.226256)
		(end 201.6 149.35)
		(width 0.1)
		(layer "In5.Cu")
		(net 516)
	)
	(arc
		(start 202.2 147.725)
		(mid 202.148744 147.848744)
		(end 202.025 147.9)
		(width 0.1)
		(layer "In5.Cu")
		(net 516)
	)
	(arc
		(start 202.2 147.025)
		(mid 202.148744 147.148744)
		(end 202.025 147.2)
		(width 0.1)
		(layer "In5.Cu")
		(net 516)
	)
	(arc
		(start 217.625 149.781577)
		(mid 217.712868 149.569445)
		(end 217.925 149.481577)
		(width 0.1)
		(layer "In5.Cu")
		(net 516)
	)
	(arc
		(start 202.2 140.575)
		(mid 202.148744 140.698744)
		(end 202.025 140.75)
		(width 0.1)
		(layer "In5.Cu")
		(net 516)
	)
	(arc
		(start 201.6 148.65)
		(mid 201.651256 148.773744)
		(end 201.775 148.825)
		(width 0.1)
		(layer "In5.Cu")
		(net 516)
	)
	(arc
		(start 202.025 149.525)
		(mid 202.148744 149.576256)
		(end 202.2 149.7)
		(width 0.1)
		(layer "In5.Cu")
		(net 516)
	)
	(arc
		(start 201.6 146.675)
		(mid 201.651256 146.798744)
		(end 201.775 146.85)
		(width 0.1)
		(layer "In5.Cu")
		(net 516)
	)
	(arc
		(start 202.025 146.15)
		(mid 202.148744 146.201256)
		(end 202.2 146.325)
		(width 0.1)
		(layer "In5.Cu")
		(net 516)
	)
	(arc
		(start 201.6 147.375)
		(mid 201.651256 147.498744)
		(end 201.775 147.55)
		(width 0.1)
		(layer "In5.Cu")
		(net 516)
	)
	(arc
		(start 202.2 149)
		(mid 202.148744 149.123744)
		(end 202.025 149.175)
		(width 0.1)
		(layer "In5.Cu")
		(net 516)
	)
	(arc
		(start 201.6 145.975)
		(mid 201.651256 146.098744)
		(end 201.775 146.15)
		(width 0.1)
		(layer "In5.Cu")
		(net 516)
	)
	(arc
		(start 201.775 141.45)
		(mid 201.651256 141.501256)
		(end 201.6 141.625)
		(width 0.1)
		(layer "In5.Cu")
		(net 516)
	)
	(arc
		(start 201.775 146.5)
		(mid 201.651256 146.551256)
		(end 201.6 146.675)
		(width 0.1)
		(layer "In5.Cu")
		(net 516)
	)
	(arc
		(start 201.6 140.925)
		(mid 201.651256 141.048744)
		(end 201.775 141.1)
		(width 0.1)
		(layer "In5.Cu")
		(net 516)
	)
	(arc
		(start 201.6 149.35)
		(mid 201.651256 149.473744)
		(end 201.775 149.525)
		(width 0.1)
		(layer "In5.Cu")
		(net 516)
	)
	(arc
		(start 201.775 149.875)
		(mid 201.651256 149.926256)
		(end 201.6 150.05)
		(width 0.1)
		(layer "In5.Cu")
		(net 516)
	)
	(arc
		(start 202.2 149.7)
		(mid 202.148744 149.823744)
		(end 202.025 149.875)
		(width 0.1)
		(layer "In5.Cu")
		(net 516)
	)
	(arc
		(start 202.025 141.1)
		(mid 202.148744 141.151256)
		(end 202.2 141.275)
		(width 0.1)
		(layer "In5.Cu")
		(net 516)
	)
	(arc
		(start 201.775 145.8)
		(mid 201.651256 145.851256)
		(end 201.6 145.975)
		(width 0.1)
		(layer "In5.Cu")
		(net 516)
	)
	(arc
		(start 202.2 145.625)
		(mid 202.148744 145.748744)
		(end 202.025 145.8)
		(width 0.1)
		(layer "In5.Cu")
		(net 516)
	)
	(arc
		(start 201.775 139.1)
		(mid 201.651256 139.151256)
		(end 201.6 139.275)
		(width 0.1)
		(layer "In5.Cu")
		(net 516)
	)
	(arc
		(start 201.6 138.575)
		(mid 201.651256 138.698744)
		(end 201.775 138.75)
		(width 0.1)
		(layer "In5.Cu")
		(net 516)
	)
	(arc
		(start 202.2 138.925)
		(mid 202.148744 139.048744)
		(end 202.025 139.1)
		(width 0.1)
		(layer "In5.Cu")
		(net 516)
	)
	(arc
		(start 202.025 140.4)
		(mid 202.148744 140.451256)
		(end 202.2 140.575)
		(width 0.1)
		(layer "In5.Cu")
		(net 516)
	)
	(segment
		(start 203 141)
		(end 202.5 140.5)
		(width 0.256)
		(layer "F.Cu")
		(net 517)
	)
	(via
		(at 219.7 146.1)
		(size 0.45)
		(drill 0.2)
		(layers "F.Cu" "B.Cu")
		(net 517)
	)
	(via
		(at 203 141)
		(size 0.45)
		(drill 0.2)
		(layers "F.Cu" "B.Cu")
		(net 517)
	)
	(segment
		(start 220.085 145.715)
		(end 221.084 145.715)
		(width 0.184)
		(layer "B.Cu")
		(net 517)
	)
	(segment
		(start 219.7 146.1)
		(end 220.085 145.715)
		(width 0.184)
		(layer "B.Cu")
		(net 517)
	)
	(segment
		(start 204.775 155.825)
		(end 204.775 155.345254)
		(width 0.1)
		(layer "In5.Cu")
		(net 517)
	)
	(segment
		(start 212.875 153.3)
		(end 216.35 149.825)
		(width 0.1)
		(layer "In5.Cu")
		(net 517)
	)
	(segment
		(start 208.1 156)
		(end 208.15 156)
		(width 0.1)
		(layer "In5.Cu")
		(net 517)
	)
	(segment
		(start 204.425 155.345254)
		(end 204.425 155.825)
		(width 0.1)
		(layer "In5.Cu")
		(net 517)
	)
	(segment
		(start 206.525 155.345254)
		(end 206.525 155.825)
		(width 0.1)
		(layer "In5.Cu")
		(net 517)
	)
	(segment
		(start 206.875 155.825)
		(end 206.875 155.345254)
		(width 0.1)
		(layer "In5.Cu")
		(net 517)
	)
	(segment
		(start 203.225 146.3)
		(end 203.025 146.3)
		(width 0.1)
		(layer "In5.Cu")
		(net 517)
	)
	(segment
		(start 203.225 151.2)
		(end 203.025 151.2)
		(width 0.1)
		(layer "In5.Cu")
		(net 517)
	)
	(segment
		(start 203.225 149.8)
		(end 203.025 149.8)
		(width 0.1)
		(layer "In5.Cu")
		(net 517)
	)
	(segment
		(start 205.475 155.825)
		(end 205.475 155.345254)
		(width 0.1)
		(layer "In5.Cu")
		(net 517)
	)
	(segment
		(start 203.225 147.7)
		(end 203.025 147.7)
		(width 0.1)
		(layer "In5.Cu")
		(net 517)
	)
	(segment
		(start 203.025 148.05)
		(end 203.225 148.05)
		(width 0.1)
		(layer "In5.Cu")
		(net 517)
	)
	(segment
		(start 203.4 152.075)
		(end 203.4 155.6)
		(width 0.1)
		(layer "In5.Cu")
		(net 517)
	)
	(segment
		(start 203.225 148.4)
		(end 203.025 148.4)
		(width 0.1)
		(layer "In5.Cu")
		(net 517)
	)
	(segment
		(start 204.075 155.825)
		(end 204.075 155.345254)
		(width 0.1)
		(layer "In5.Cu")
		(net 517)
	)
	(segment
		(start 203.225 150.5)
		(end 203.025 150.5)
		(width 0.1)
		(layer "In5.Cu")
		(net 517)
	)
	(segment
		(start 203.025 147.35)
		(end 203.225 147.35)
		(width 0.1)
		(layer "In5.Cu")
		(net 517)
	)
	(segment
		(start 207.925 155.345254)
		(end 207.925 155.825)
		(width 0.1)
		(layer "In5.Cu")
		(net 517)
	)
	(segment
		(start 218.2 146.1)
		(end 219.7 146.1)
		(width 0.1)
		(layer "In5.Cu")
		(net 517)
	)
	(segment
		(start 211.025 153.3)
		(end 212.875 153.3)
		(width 0.1)
		(layer "In5.Cu")
		(net 517)
	)
	(segment
		(start 207.575 155.825)
		(end 207.575 155.345254)
		(width 0.1)
		(layer "In5.Cu")
		(net 517)
	)
	(segment
		(start 203.4 155.6)
		(end 203.8 156)
		(width 0.1)
		(layer "In5.Cu")
		(net 517)
	)
	(segment
		(start 205.825 155.345254)
		(end 205.825 155.825)
		(width 0.1)
		(layer "In5.Cu")
		(net 517)
	)
	(segment
		(start 205.125 155.345254)
		(end 205.125 155.825)
		(width 0.1)
		(layer "In5.Cu")
		(net 517)
	)
	(segment
		(start 202.85 151.525)
		(end 203.4 152.075)
		(width 0.1)
		(layer "In5.Cu")
		(net 517)
	)
	(segment
		(start 203.025 150.15)
		(end 203.225 150.15)
		(width 0.1)
		(layer "In5.Cu")
		(net 517)
	)
	(segment
		(start 207.225 155.345254)
		(end 207.225 155.825)
		(width 0.1)
		(layer "In5.Cu")
		(net 517)
	)
	(segment
		(start 203.025 150.85)
		(end 203.225 150.85)
		(width 0.1)
		(layer "In5.Cu")
		(net 517)
	)
	(segment
		(start 216.35 149.825)
		(end 216.35 147.95)
		(width 0.1)
		(layer "In5.Cu")
		(net 517)
	)
	(segment
		(start 203.025 145.95)
		(end 203.225 145.95)
		(width 0.1)
		(layer "In5.Cu")
		(net 517)
	)
	(segment
		(start 203 141)
		(end 202.85 141.15)
		(width 0.1)
		(layer "In5.Cu")
		(net 517)
	)
	(segment
		(start 203.025 148.75)
		(end 203.225 148.75)
		(width 0.1)
		(layer "In5.Cu")
		(net 517)
	)
	(segment
		(start 208.15 156)
		(end 208.325 156)
		(width 0.1)
		(layer "In5.Cu")
		(net 517)
	)
	(segment
		(start 216.35 147.95)
		(end 218.2 146.1)
		(width 0.1)
		(layer "In5.Cu")
		(net 517)
	)
	(segment
		(start 203.225 149.1)
		(end 203.025 149.1)
		(width 0.1)
		(layer "In5.Cu")
		(net 517)
	)
	(segment
		(start 202.85 141.15)
		(end 202.85 145.775)
		(width 0.1)
		(layer "In5.Cu")
		(net 517)
	)
	(segment
		(start 203.025 146.65)
		(end 203.225 146.65)
		(width 0.1)
		(layer "In5.Cu")
		(net 517)
	)
	(segment
		(start 202.85 151.375)
		(end 202.85 151.525)
		(width 0.1)
		(layer "In5.Cu")
		(net 517)
	)
	(segment
		(start 203.8 156)
		(end 203.9 156)
		(width 0.1)
		(layer "In5.Cu")
		(net 517)
	)
	(segment
		(start 203.025 149.45)
		(end 203.225 149.45)
		(width 0.1)
		(layer "In5.Cu")
		(net 517)
	)
	(segment
		(start 208.325 156)
		(end 211.025 153.3)
		(width 0.1)
		(layer "In5.Cu")
		(net 517)
	)
	(segment
		(start 206.175 155.825)
		(end 206.175 155.345254)
		(width 0.1)
		(layer "In5.Cu")
		(net 517)
	)
	(segment
		(start 203.225 147)
		(end 203.025 147)
		(width 0.1)
		(layer "In5.Cu")
		(net 517)
	)
	(arc
		(start 203.4 151.025)
		(mid 203.348744 151.148744)
		(end 203.225 151.2)
		(width 0.1)
		(layer "In5.Cu")
		(net 517)
	)
	(arc
		(start 207.75 155.170254)
		(mid 207.873744 155.22151)
		(end 207.925 155.345254)
		(width 0.1)
		(layer "In5.Cu")
		(net 517)
	)
	(arc
		(start 203.025 151.2)
		(mid 202.901256 151.251256)
		(end 202.85 151.375)
		(width 0.1)
		(layer "In5.Cu")
		(net 517)
	)
	(arc
		(start 203.4 148.925)
		(mid 203.348744 149.048744)
		(end 203.225 149.1)
		(width 0.1)
		(layer "In5.Cu")
		(net 517)
	)
	(arc
		(start 205.825 155.825)
		(mid 205.876256 155.948744)
		(end 206 156)
		(width 0.1)
		(layer "In5.Cu")
		(net 517)
	)
	(arc
		(start 206 156)
		(mid 206.123744 155.948744)
		(end 206.175 155.825)
		(width 0.1)
		(layer "In5.Cu")
		(net 517)
	)
	(arc
		(start 203.225 150.15)
		(mid 203.348744 150.201256)
		(end 203.4 150.325)
		(width 0.1)
		(layer "In5.Cu")
		(net 517)
	)
	(arc
		(start 207.4 156)
		(mid 207.523744 155.948744)
		(end 207.575 155.825)
		(width 0.1)
		(layer "In5.Cu")
		(net 517)
	)
	(arc
		(start 204.075 155.345254)
		(mid 204.126256 155.22151)
		(end 204.25 155.170254)
		(width 0.1)
		(layer "In5.Cu")
		(net 517)
	)
	(arc
		(start 203.025 149.8)
		(mid 202.901256 149.851256)
		(end 202.85 149.975)
		(width 0.1)
		(layer "In5.Cu")
		(net 517)
	)
	(arc
		(start 203.025 146.3)
		(mid 202.901256 146.351256)
		(end 202.85 146.475)
		(width 0.1)
		(layer "In5.Cu")
		(net 517)
	)
	(arc
		(start 203.4 149.625)
		(mid 203.348744 149.748744)
		(end 203.225 149.8)
		(width 0.1)
		(layer "In5.Cu")
		(net 517)
	)
	(arc
		(start 203.225 146.65)
		(mid 203.348744 146.701256)
		(end 203.4 146.825)
		(width 0.1)
		(layer "In5.Cu")
		(net 517)
	)
	(arc
		(start 207.925 155.825)
		(mid 207.976256 155.948744)
		(end 208.1 156)
		(width 0.1)
		(layer "In5.Cu")
		(net 517)
	)
	(arc
		(start 203.225 145.95)
		(mid 203.348744 146.001256)
		(end 203.4 146.125)
		(width 0.1)
		(layer "In5.Cu")
		(net 517)
	)
	(arc
		(start 205.65 155.170254)
		(mid 205.773744 155.22151)
		(end 205.825 155.345254)
		(width 0.1)
		(layer "In5.Cu")
		(net 517)
	)
	(arc
		(start 203.225 148.75)
		(mid 203.348744 148.801256)
		(end 203.4 148.925)
		(width 0.1)
		(layer "In5.Cu")
		(net 517)
	)
	(arc
		(start 206.35 155.170254)
		(mid 206.473744 155.22151)
		(end 206.525 155.345254)
		(width 0.1)
		(layer "In5.Cu")
		(net 517)
	)
	(arc
		(start 202.85 147.175)
		(mid 202.901256 147.298744)
		(end 203.025 147.35)
		(width 0.1)
		(layer "In5.Cu")
		(net 517)
	)
	(arc
		(start 204.25 155.170254)
		(mid 204.373744 155.22151)
		(end 204.425 155.345254)
		(width 0.1)
		(layer "In5.Cu")
		(net 517)
	)
	(arc
		(start 203.225 148.05)
		(mid 203.348744 148.101256)
		(end 203.4 148.225)
		(width 0.1)
		(layer "In5.Cu")
		(net 517)
	)
	(arc
		(start 203.025 148.4)
		(mid 202.901256 148.451256)
		(end 202.85 148.575)
		(width 0.1)
		(layer "In5.Cu")
		(net 517)
	)
	(arc
		(start 202.85 149.975)
		(mid 202.901256 150.098744)
		(end 203.025 150.15)
		(width 0.1)
		(layer "In5.Cu")
		(net 517)
	)
	(arc
		(start 203.025 147.7)
		(mid 202.901256 147.751256)
		(end 202.85 147.875)
		(width 0.1)
		(layer "In5.Cu")
		(net 517)
	)
	(arc
		(start 203.025 150.5)
		(mid 202.901256 150.551256)
		(end 202.85 150.675)
		(width 0.1)
		(layer "In5.Cu")
		(net 517)
	)
	(arc
		(start 204.6 156)
		(mid 204.723744 155.948744)
		(end 204.775 155.825)
		(width 0.1)
		(layer "In5.Cu")
		(net 517)
	)
	(arc
		(start 205.125 155.825)
		(mid 205.176256 155.948744)
		(end 205.3 156)
		(width 0.1)
		(layer "In5.Cu")
		(net 517)
	)
	(arc
		(start 206.525 155.825)
		(mid 206.576256 155.948744)
		(end 206.7 156)
		(width 0.1)
		(layer "In5.Cu")
		(net 517)
	)
	(arc
		(start 203.225 147.35)
		(mid 203.348744 147.401256)
		(end 203.4 147.525)
		(width 0.1)
		(layer "In5.Cu")
		(net 517)
	)
	(arc
		(start 207.05 155.170254)
		(mid 207.173744 155.22151)
		(end 207.225 155.345254)
		(width 0.1)
		(layer "In5.Cu")
		(net 517)
	)
	(arc
		(start 207.575 155.345254)
		(mid 207.626256 155.22151)
		(end 207.75 155.170254)
		(width 0.1)
		(layer "In5.Cu")
		(net 517)
	)
	(arc
		(start 203.025 149.1)
		(mid 202.901256 149.151256)
		(end 202.85 149.275)
		(width 0.1)
		(layer "In5.Cu")
		(net 517)
	)
	(arc
		(start 204.775 155.345254)
		(mid 204.826256 155.22151)
		(end 204.95 155.170254)
		(width 0.1)
		(layer "In5.Cu")
		(net 517)
	)
	(arc
		(start 205.475 155.345254)
		(mid 205.526256 155.22151)
		(end 205.65 155.170254)
		(width 0.1)
		(layer "In5.Cu")
		(net 517)
	)
	(arc
		(start 203.4 147.525)
		(mid 203.348744 147.648744)
		(end 203.225 147.7)
		(width 0.1)
		(layer "In5.Cu")
		(net 517)
	)
	(arc
		(start 207.225 155.825)
		(mid 207.276256 155.948744)
		(end 207.4 156)
		(width 0.1)
		(layer "In5.Cu")
		(net 517)
	)
	(arc
		(start 206.175 155.345254)
		(mid 206.226256 155.22151)
		(end 206.35 155.170254)
		(width 0.1)
		(layer "In5.Cu")
		(net 517)
	)
	(arc
		(start 202.85 150.675)
		(mid 202.901256 150.798744)
		(end 203.025 150.85)
		(width 0.1)
		(layer "In5.Cu")
		(net 517)
	)
	(arc
		(start 202.85 149.275)
		(mid 202.901256 149.398744)
		(end 203.025 149.45)
		(width 0.1)
		(layer "In5.Cu")
		(net 517)
	)
	(arc
		(start 203.9 156)
		(mid 204.023744 155.948744)
		(end 204.075 155.825)
		(width 0.1)
		(layer "In5.Cu")
		(net 517)
	)
	(arc
		(start 203.4 150.325)
		(mid 203.348744 150.448744)
		(end 203.225 150.5)
		(width 0.1)
		(layer "In5.Cu")
		(net 517)
	)
	(arc
		(start 203.225 149.45)
		(mid 203.348744 149.501256)
		(end 203.4 149.625)
		(width 0.1)
		(layer "In5.Cu")
		(net 517)
	)
	(arc
		(start 202.85 146.475)
		(mid 202.901256 146.598744)
		(end 203.025 146.65)
		(width 0.1)
		(layer "In5.Cu")
		(net 517)
	)
	(arc
		(start 206.875 155.345254)
		(mid 206.926256 155.22151)
		(end 207.05 155.170254)
		(width 0.1)
		(layer "In5.Cu")
		(net 517)
	)
	(arc
		(start 202.85 145.775)
		(mid 202.901256 145.898744)
		(end 203.025 145.95)
		(width 0.1)
		(layer "In5.Cu")
		(net 517)
	)
	(arc
		(start 203.4 148.225)
		(mid 203.348744 148.348744)
		(end 203.225 148.4)
		(width 0.1)
		(layer "In5.Cu")
		(net 517)
	)
	(arc
		(start 204.95 155.170254)
		(mid 205.073744 155.22151)
		(end 205.125 155.345254)
		(width 0.1)
		(layer "In5.Cu")
		(net 517)
	)
	(arc
		(start 204.425 155.825)
		(mid 204.476256 155.948744)
		(end 204.6 156)
		(width 0.1)
		(layer "In5.Cu")
		(net 517)
	)
	(arc
		(start 203.4 146.125)
		(mid 203.348744 146.248744)
		(end 203.225 146.3)
		(width 0.1)
		(layer "In5.Cu")
		(net 517)
	)
	(arc
		(start 203.025 147)
		(mid 202.901256 147.051256)
		(end 202.85 147.175)
		(width 0.1)
		(layer "In5.Cu")
		(net 517)
	)
	(arc
		(start 205.3 156)
		(mid 205.423744 155.948744)
		(end 205.475 155.825)
		(width 0.1)
		(layer "In5.Cu")
		(net 517)
	)
	(arc
		(start 203.4 146.825)
		(mid 203.348744 146.948744)
		(end 203.225 147)
		(width 0.1)
		(layer "In5.Cu")
		(net 517)
	)
	(arc
		(start 203.225 150.85)
		(mid 203.348744 150.901256)
		(end 203.4 151.025)
		(width 0.1)
		(layer "In5.Cu")
		(net 517)
	)
	(arc
		(start 206.7 156)
		(mid 206.823744 155.948744)
		(end 206.875 155.825)
		(width 0.1)
		(layer "In5.Cu")
		(net 517)
	)
	(arc
		(start 202.85 147.875)
		(mid 202.901256 147.998744)
		(end 203.025 148.05)
		(width 0.1)
		(layer "In5.Cu")
		(net 517)
	)
	(arc
		(start 202.85 148.575)
		(mid 202.901256 148.698744)
		(end 203.025 148.75)
		(width 0.1)
		(layer "In5.Cu")
		(net 517)
	)
	(segment
		(start 203.5 137.5)
		(end 204 138)
		(width 0.256)
		(layer "F.Cu")
		(net 519)
	)
	(via
		(at 204 138)
		(size 0.45)
		(drill 0.2)
		(layers "F.Cu" "B.Cu")
		(net 519)
	)
	(via
		(at 223.2 145)
		(size 0.45)
		(drill 0.2)
		(layers "F.Cu" "B.Cu")
		(net 519)
	)
	(segment
		(start 223.2 145.715)
		(end 223.2 145)
		(width 0.184)
		(layer "B.Cu")
		(net 519)
	)
	(segment
		(start 203.975 139.775)
		(end 204.225 139.775)
		(width 0.1)
		(layer "In5.Cu")
		(net 519)
	)
	(segment
		(start 212.4 152.7)
		(end 215.725 149.375)
		(width 0.1)
		(layer "In5.Cu")
		(net 519)
	)
	(segment
		(start 203.625 143.875)
		(end 204.225 143.875)
		(width 0.1)
		(layer "In5.Cu")
		(net 519)
	)
	(segment
		(start 204.4 144.75)
		(end 204.4 145.8)
		(width 0.1)
		(layer "In5.Cu")
		(net 519)
	)
	(segment
		(start 205.075 151.3)
		(end 204.875 151.3)
		(width 0.1)
		(layer "In5.Cu")
		(net 519)
	)
	(segment
		(start 203.775 141.775)
		(end 204.225 141.775)
		(width 0.1)
		(layer "In5.Cu")
		(net 519)
	)
	(segment
		(start 215.725 149.375)
		(end 215.725 147.65)
		(width 0.1)
		(layer "In5.Cu")
		(net 519)
	)
	(segment
		(start 204.225 138.725)
		(end 203.975 138.725)
		(width 0.1)
		(layer "In5.Cu")
		(net 519)
	)
	(segment
		(start 204.225 142.825)
		(end 203.625 142.825)
		(width 0.1)
		(layer "In5.Cu")
		(net 519)
	)
	(segment
		(start 204.225 139.425)
		(end 203.975 139.425)
		(width 0.1)
		(layer "In5.Cu")
		(net 519)
	)
	(segment
		(start 204.7 146.1)
		(end 204.7 150.775)
		(width 0.1)
		(layer "In5.Cu")
		(net 519)
	)
	(segment
		(start 204.7 151.475)
		(end 204.7 151.525)
		(width 0.1)
		(layer "In5.Cu")
		(net 519)
	)
	(segment
		(start 204.4 138.4)
		(end 204.4 138.55)
		(width 0.1)
		(layer "In5.Cu")
		(net 519)
	)
	(segment
		(start 204 138)
		(end 204.4 138.4)
		(width 0.1)
		(layer "In5.Cu")
		(net 519)
	)
	(segment
		(start 204.4 145.8)
		(end 204.7 146.1)
		(width 0.1)
		(layer "In5.Cu")
		(net 519)
	)
	(segment
		(start 210.771814 152.7)
		(end 212.4 152.7)
		(width 0.1)
		(layer "In5.Cu")
		(net 519)
	)
	(segment
		(start 203.625 144.575)
		(end 204.225 144.575)
		(width 0.1)
		(layer "In5.Cu")
		(net 519)
	)
	(segment
		(start 204.4 140.65)
		(end 204.4 141.25)
		(width 0.1)
		(layer "In5.Cu")
		(net 519)
	)
	(segment
		(start 204.875 150.95)
		(end 205.075 150.95)
		(width 0.1)
		(layer "In5.Cu")
		(net 519)
	)
	(segment
		(start 203.975 139.075)
		(end 204.225 139.075)
		(width 0.1)
		(layer "In5.Cu")
		(net 519)
	)
	(segment
		(start 221.866421 145.375)
		(end 222.825 145.375)
		(width 0.1)
		(layer "In5.Cu")
		(net 519)
	)
	(segment
		(start 215.725 147.65)
		(end 218.175 145.2)
		(width 0.1)
		(layer "In5.Cu")
		(net 519)
	)
	(segment
		(start 222.825 145.375)
		(end 223.2 145)
		(width 0.1)
		(layer "In5.Cu")
		(net 519)
	)
	(segment
		(start 203.975 140.475)
		(end 204.225 140.475)
		(width 0.1)
		(layer "In5.Cu")
		(net 519)
	)
	(segment
		(start 204.225 144.225)
		(end 203.625 144.225)
		(width 0.1)
		(layer "In5.Cu")
		(net 519)
	)
	(segment
		(start 204.225 141.425)
		(end 203.775 141.425)
		(width 0.1)
		(layer "In5.Cu")
		(net 519)
	)
	(segment
		(start 204.7 151.525)
		(end 204.7 153.675)
		(width 0.1)
		(layer "In5.Cu")
		(net 519)
	)
	(segment
		(start 204.7 153.675)
		(end 205.55 154.525)
		(width 0.1)
		(layer "In5.Cu")
		(net 519)
	)
	(segment
		(start 204.225 140.125)
		(end 203.975 140.125)
		(width 0.1)
		(layer "In5.Cu")
		(net 519)
	)
	(segment
		(start 218.175 145.2)
		(end 221.691421 145.2)
		(width 0.1)
		(layer "In5.Cu")
		(net 519)
	)
	(segment
		(start 204.225 143.525)
		(end 203.625 143.525)
		(width 0.1)
		(layer "In5.Cu")
		(net 519)
	)
	(segment
		(start 203.625 142.475)
		(end 204.225 142.475)
		(width 0.1)
		(layer "In5.Cu")
		(net 519)
	)
	(segment
		(start 205.55 154.525)
		(end 208.946816 154.525)
		(width 0.1)
		(layer "In5.Cu")
		(net 519)
	)
	(segment
		(start 208.946816 154.525)
		(end 210.771814 152.7)
		(width 0.1)
		(layer "In5.Cu")
		(net 519)
	)
	(segment
		(start 204.225 142.125)
		(end 203.625 142.125)
		(width 0.1)
		(layer "In5.Cu")
		(net 519)
	)
	(segment
		(start 221.691421 145.2)
		(end 221.866421 145.375)
		(width 0.1)
		(layer "In5.Cu")
		(net 519)
	)
	(segment
		(start 203.625 143.175)
		(end 204.225 143.175)
		(width 0.1)
		(layer "In5.Cu")
		(net 519)
	)
	(arc
		(start 204.4 141.95)
		(mid 204.348744 142.073744)
		(end 204.225 142.125)
		(width 0.1)
		(layer "In5.Cu")
		(net 519)
	)
	(arc
		(start 204.225 139.775)
		(mid 204.348744 139.826256)
		(end 204.4 139.95)
		(width 0.1)
		(layer "In5.Cu")
		(net 519)
	)
	(arc
		(start 204.875 151.3)
		(mid 204.751256 151.351256)
		(end 204.7 151.475)
		(width 0.1)
		(layer "In5.Cu")
		(net 519)
	)
	(arc
		(start 203.625 144.225)
		(mid 203.501256 144.276256)
		(end 203.45 144.4)
		(width 0.1)
		(layer "In5.Cu")
		(net 519)
	)
	(arc
		(start 203.8 139.6)
		(mid 203.851256 139.723744)
		(end 203.975 139.775)
		(width 0.1)
		(layer "In5.Cu")
		(net 519)
	)
	(arc
		(start 203.45 143.7)
		(mid 203.501256 143.823744)
		(end 203.625 143.875)
		(width 0.1)
		(layer "In5.Cu")
		(net 519)
	)
	(arc
		(start 204.225 139.075)
		(mid 204.348744 139.126256)
		(end 204.4 139.25)
		(width 0.1)
		(layer "In5.Cu")
		(net 519)
	)
	(arc
		(start 205.075 150.95)
		(mid 205.198744 151.001256)
		(end 205.25 151.125)
		(width 0.1)
		(layer "In5.Cu")
		(net 519)
	)
	(arc
		(start 203.45 143)
		(mid 203.501256 143.123744)
		(end 203.625 143.175)
		(width 0.1)
		(layer "In5.Cu")
		(net 519)
	)
	(arc
		(start 203.975 140.125)
		(mid 203.851256 140.176256)
		(end 203.8 140.3)
		(width 0.1)
		(layer "In5.Cu")
		(net 519)
	)
	(arc
		(start 205.25 151.125)
		(mid 205.198744 151.248744)
		(end 205.075 151.3)
		(width 0.1)
		(layer "In5.Cu")
		(net 519)
	)
	(arc
		(start 203.45 142.3)
		(mid 203.501256 142.423744)
		(end 203.625 142.475)
		(width 0.1)
		(layer "In5.Cu")
		(net 519)
	)
	(arc
		(start 203.625 143.525)
		(mid 203.501256 143.576256)
		(end 203.45 143.7)
		(width 0.1)
		(layer "In5.Cu")
		(net 519)
	)
	(arc
		(start 204.4 139.25)
		(mid 204.348744 139.373744)
		(end 204.225 139.425)
		(width 0.1)
		(layer "In5.Cu")
		(net 519)
	)
	(arc
		(start 204.4 143.35)
		(mid 204.348744 143.473744)
		(end 204.225 143.525)
		(width 0.1)
		(layer "In5.Cu")
		(net 519)
	)
	(arc
		(start 203.775 141.425)
		(mid 203.651256 141.476256)
		(end 203.6 141.6)
		(width 0.1)
		(layer "In5.Cu")
		(net 519)
	)
	(arc
		(start 204.225 143.875)
		(mid 204.348744 143.926256)
		(end 204.4 144.05)
		(width 0.1)
		(layer "In5.Cu")
		(net 519)
	)
	(arc
		(start 203.975 139.425)
		(mid 203.851256 139.476256)
		(end 203.8 139.6)
		(width 0.1)
		(layer "In5.Cu")
		(net 519)
	)
	(arc
		(start 203.625 142.125)
		(mid 203.501256 142.176256)
		(end 203.45 142.3)
		(width 0.1)
		(layer "In5.Cu")
		(net 519)
	)
	(arc
		(start 203.45 144.4)
		(mid 203.501256 144.523744)
		(end 203.625 144.575)
		(width 0.1)
		(layer "In5.Cu")
		(net 519)
	)
	(arc
		(start 204.225 142.475)
		(mid 204.348744 142.526256)
		(end 204.4 142.65)
		(width 0.1)
		(layer "In5.Cu")
		(net 519)
	)
	(arc
		(start 204.4 142.65)
		(mid 204.348744 142.773744)
		(end 204.225 142.825)
		(width 0.1)
		(layer "In5.Cu")
		(net 519)
	)
	(arc
		(start 203.6 141.6)
		(mid 203.651256 141.723744)
		(end 203.775 141.775)
		(width 0.1)
		(layer "In5.Cu")
		(net 519)
	)
	(arc
		(start 203.625 142.825)
		(mid 203.501256 142.876256)
		(end 203.45 143)
		(width 0.1)
		(layer "In5.Cu")
		(net 519)
	)
	(arc
		(start 204.4 139.95)
		(mid 204.348744 140.073744)
		(end 204.225 140.125)
		(width 0.1)
		(layer "In5.Cu")
		(net 519)
	)
	(arc
		(start 203.8 140.3)
		(mid 203.851256 140.423744)
		(end 203.975 140.475)
		(width 0.1)
		(layer "In5.Cu")
		(net 519)
	)
	(arc
		(start 204.225 144.575)
		(mid 204.348744 144.626256)
		(end 204.4 144.75)
		(width 0.1)
		(layer "In5.Cu")
		(net 519)
	)
	(arc
		(start 204.4 141.25)
		(mid 204.348744 141.373744)
		(end 204.225 141.425)
		(width 0.1)
		(layer "In5.Cu")
		(net 519)
	)
	(arc
		(start 204.225 140.475)
		(mid 204.348744 140.526256)
		(end 204.4 140.65)
		(width 0.1)
		(layer "In5.Cu")
		(net 519)
	)
	(arc
		(start 203.975 138.725)
		(mid 203.851256 138.776256)
		(end 203.8 138.9)
		(width 0.1)
		(layer "In5.Cu")
		(net 519)
	)
	(arc
		(start 204.225 141.775)
		(mid 204.348744 141.826256)
		(end 204.4 141.95)
		(width 0.1)
		(layer "In5.Cu")
		(net 519)
	)
	(arc
		(start 204.7 150.775)
		(mid 204.751256 150.898744)
		(end 204.875 150.95)
		(width 0.1)
		(layer "In5.Cu")
		(net 519)
	)
	(arc
		(start 203.8 138.9)
		(mid 203.851256 139.023744)
		(end 203.975 139.075)
		(width 0.1)
		(layer "In5.Cu")
		(net 519)
	)
	(arc
		(start 204.225 143.175)
		(mid 204.348744 143.226256)
		(end 204.4 143.35)
		(width 0.1)
		(layer "In5.Cu")
		(net 519)
	)
	(arc
		(start 204.4 138.55)
		(mid 204.348744 138.673744)
		(end 204.225 138.725)
		(width 0.1)
		(layer "In5.Cu")
		(net 519)
	)
	(arc
		(start 204.4 144.05)
		(mid 204.348744 144.173744)
		(end 204.225 144.225)
		(width 0.1)
		(layer "In5.Cu")
		(net 519)
	)
	(segment
		(start 202.5 139.5)
		(end 203 140)
		(width 0.256)
		(layer "F.Cu")
		(net 520)
	)
	(via
		(at 223.79609 146.118969)
		(size 0.45)
		(drill 0.2)
		(layers "F.Cu" "B.Cu")
		(net 520)
	)
	(via
		(at 203 140)
		(size 0.45)
		(drill 0.2)
		(layers "F.Cu" "B.Cu")
		(net 520)
	)
	(segment
		(start 224.2 145.715059)
		(end 224.2 145.715)
		(width 0.184)
		(layer "B.Cu")
		(net 520)
	)
	(segment
		(start 223.79609 146.118969)
		(end 224.2 145.715059)
		(width 0.184)
		(layer "B.Cu")
		(net 520)
	)
	(segment
		(start 218.4 145.6)
		(end 216.125 147.875)
		(width 0.1)
		(layer "In5.Cu")
		(net 520)
	)
	(segment
		(start 204.3 154.925)
		(end 204.025 154.925)
		(width 0.1)
		(layer "In5.Cu")
		(net 520)
	)
	(segment
		(start 203.6 150.625)
		(end 203.6 149.725)
		(width 0.1)
		(layer "In5.Cu")
		(net 520)
	)
	(segment
		(start 222.2 146.7)
		(end 221.1 145.6)
		(width 0.1)
		(layer "In5.Cu")
		(net 520)
	)
	(segment
		(start 203.375 141.155331)
		(end 203.375 140.375)
		(width 0.1)
		(layer "In5.Cu")
		(net 520)
	)
	(segment
		(start 203.775 149.5)
		(end 204.125 149.5)
		(width 0.1)
		(layer "In5.Cu")
		(net 520)
	)
	(segment
		(start 203.775 146.7)
		(end 204.125 146.7)
		(width 0.1)
		(layer "In5.Cu")
		(net 520)
	)
	(segment
		(start 210.9375 153.1)
		(end 209.1125 154.925)
		(width 0.1)
		(layer "In5.Cu")
		(net 520)
	)
	(segment
		(start 203.6 154.5)
		(end 203.6 154.275)
		(width 0.1)
		(layer "In5.Cu")
		(net 520)
	)
	(segment
		(start 223.215059 146.7)
		(end 222.2 146.7)
		(width 0.1)
		(layer "In5.Cu")
		(net 520)
	)
	(segment
		(start 204.825 154.75)
		(end 204.825 154.690795)
		(width 0.1)
		(layer "In5.Cu")
		(net 520)
	)
	(segment
		(start 203.6 152.175)
		(end 203.6 151.575)
		(width 0.1)
		(layer "In5.Cu")
		(net 520)
	)
	(segment
		(start 209.1125 154.925)
		(end 205 154.925)
		(width 0.1)
		(layer "In5.Cu")
		(net 520)
	)
	(segment
		(start 203.775 154.1)
		(end 204.125 154.1)
		(width 0.1)
		(layer "In5.Cu")
		(net 520)
	)
	(segment
		(start 204.125 153.05)
		(end 203.775 153.05)
		(width 0.1)
		(layer "In5.Cu")
		(net 520)
	)
	(segment
		(start 204.125 149.15)
		(end 203.775 149.15)
		(width 0.1)
		(layer "In5.Cu")
		(net 520)
	)
	(segment
		(start 203.825 151.3)
		(end 204.075 151.3)
		(width 0.1)
		(layer "In5.Cu")
		(net 520)
	)
	(segment
		(start 203.05 145.05)
		(end 203.05 141.480331)
		(width 0.1)
		(layer "In5.Cu")
		(net 520)
	)
	(segment
		(start 203.05 141.480331)
		(end 203.375 141.155331)
		(width 0.1)
		(layer "In5.Cu")
		(net 520)
	)
	(segment
		(start 212.6 153.1)
		(end 210.9375 153.1)
		(width 0.1)
		(layer "In5.Cu")
		(net 520)
	)
	(segment
		(start 203.6 149.725)
		(end 203.6 149.675)
		(width 0.1)
		(layer "In5.Cu")
		(net 520)
	)
	(segment
		(start 216.125 149.575)
		(end 212.6 153.1)
		(width 0.1)
		(layer "In5.Cu")
		(net 520)
	)
	(segment
		(start 204.125 148.45)
		(end 203.775 148.45)
		(width 0.1)
		(layer "In5.Cu")
		(net 520)
	)
	(segment
		(start 203.775 148.8)
		(end 204.125 148.8)
		(width 0.1)
		(layer "In5.Cu")
		(net 520)
	)
	(segment
		(start 204.125 146.35)
		(end 203.775 146.35)
		(width 0.1)
		(layer "In5.Cu")
		(net 520)
	)
	(segment
		(start 216.125 147.875)
		(end 216.125 149.575)
		(width 0.1)
		(layer "In5.Cu")
		(net 520)
	)
	(segment
		(start 221.1 145.6)
		(end 218.4 145.6)
		(width 0.1)
		(layer "In5.Cu")
		(net 520)
	)
	(segment
		(start 204.125 152.35)
		(end 203.775 152.35)
		(width 0.1)
		(layer "In5.Cu")
		(net 520)
	)
	(segment
		(start 223.79609 146.118969)
		(end 223.215059 146.7)
		(width 0.1)
		(layer "In5.Cu")
		(net 520)
	)
	(segment
		(start 203.375 140.375)
		(end 203 140)
		(width 0.1)
		(layer "In5.Cu")
		(net 520)
	)
	(segment
		(start 203.775 148.1)
		(end 204.125 148.1)
		(width 0.1)
		(layer "In5.Cu")
		(net 520)
	)
	(segment
		(start 203.775 147.4)
		(end 204.125 147.4)
		(width 0.1)
		(layer "In5.Cu")
		(net 520)
	)
	(segment
		(start 203.6 146.175)
		(end 203.6 145.6)
		(width 0.1)
		(layer "In5.Cu")
		(net 520)
	)
	(segment
		(start 204.025 154.925)
		(end 203.6 154.5)
		(width 0.1)
		(layer "In5.Cu")
		(net 520)
	)
	(segment
		(start 203.6 151.575)
		(end 203.6 151.525)
		(width 0.1)
		(layer "In5.Cu")
		(net 520)
	)
	(segment
		(start 203.6 145.6)
		(end 203.05 145.05)
		(width 0.1)
		(layer "In5.Cu")
		(net 520)
	)
	(segment
		(start 204.125 147.75)
		(end 203.775 147.75)
		(width 0.1)
		(layer "In5.Cu")
		(net 520)
	)
	(segment
		(start 204.075 150.85)
		(end 203.825 150.85)
		(width 0.1)
		(layer "In5.Cu")
		(net 520)
	)
	(segment
		(start 204.125 147.05)
		(end 203.775 147.05)
		(width 0.1)
		(layer "In5.Cu")
		(net 520)
	)
	(segment
		(start 203.775 153.4)
		(end 204.125 153.4)
		(width 0.1)
		(layer "In5.Cu")
		(net 520)
	)
	(segment
		(start 203.775 152.7)
		(end 204.125 152.7)
		(width 0.1)
		(layer "In5.Cu")
		(net 520)
	)
	(segment
		(start 204.125 153.75)
		(end 203.775 153.75)
		(width 0.1)
		(layer "In5.Cu")
		(net 520)
	)
	(segment
		(start 204.475 154.690795)
		(end 204.475 154.75)
		(width 0.1)
		(layer "In5.Cu")
		(net 520)
	)
	(arc
		(start 204.3 151.075)
		(mid 204.234099 150.915901)
		(end 204.075 150.85)
		(width 0.1)
		(layer "In5.Cu")
		(net 520)
	)
	(arc
		(start 204.3 153.225)
		(mid 204.248744 153.101256)
		(end 204.125 153.05)
		(width 0.1)
		(layer "In5.Cu")
		(net 520)
	)
	(arc
		(start 203.775 153.05)
		(mid 203.651256 152.998744)
		(end 203.6 152.875)
		(width 0.1)
		(layer "In5.Cu")
		(net 520)
	)
	(arc
		(start 203.6 147.575)
		(mid 203.651256 147.451256)
		(end 203.775 147.4)
		(width 0.1)
		(layer "In5.Cu")
		(net 520)
	)
	(arc
		(start 203.775 148.45)
		(mid 203.651256 148.398744)
		(end 203.6 148.275)
		(width 0.1)
		(layer "In5.Cu")
		(net 520)
	)
	(arc
		(start 204.125 154.1)
		(mid 204.248744 154.048744)
		(end 204.3 153.925)
		(width 0.1)
		(layer "In5.Cu")
		(net 520)
	)
	(arc
		(start 204.3 147.925)
		(mid 204.248744 147.801256)
		(end 204.125 147.75)
		(width 0.1)
		(layer "In5.Cu")
		(net 520)
	)
	(arc
		(start 203.6 153.575)
		(mid 203.651256 153.451256)
		(end 203.775 153.4)
		(width 0.1)
		(layer "In5.Cu")
		(net 520)
	)
	(arc
		(start 204.125 147.4)
		(mid 204.248744 147.348744)
		(end 204.3 147.225)
		(width 0.1)
		(layer "In5.Cu")
		(net 520)
	)
	(arc
		(start 203.6 146.875)
		(mid 203.651256 146.751256)
		(end 203.775 146.7)
		(width 0.1)
		(layer "In5.Cu")
		(net 520)
	)
	(arc
		(start 204.3 147.225)
		(mid 204.248744 147.101256)
		(end 204.125 147.05)
		(width 0.1)
		(layer "In5.Cu")
		(net 520)
	)
	(arc
		(start 204.825 154.690795)
		(mid 204.773744 154.567051)
		(end 204.65 154.515795)
		(width 0.1)
		(layer "In5.Cu")
		(net 520)
	)
	(arc
		(start 204.3 153.925)
		(mid 204.248744 153.801256)
		(end 204.125 153.75)
		(width 0.1)
		(layer "In5.Cu")
		(net 520)
	)
	(arc
		(start 203.775 147.75)
		(mid 203.651256 147.698744)
		(end 203.6 147.575)
		(width 0.1)
		(layer "In5.Cu")
		(net 520)
	)
	(arc
		(start 204.125 146.7)
		(mid 204.248744 146.648744)
		(end 204.3 146.525)
		(width 0.1)
		(layer "In5.Cu")
		(net 520)
	)
	(arc
		(start 203.775 152.35)
		(mid 203.651256 152.298744)
		(end 203.6 152.175)
		(width 0.1)
		(layer "In5.Cu")
		(net 520)
	)
	(arc
		(start 203.825 150.85)
		(mid 203.665901 150.784099)
		(end 203.6 150.625)
		(width 0.1)
		(layer "In5.Cu")
		(net 520)
	)
	(arc
		(start 204.3 148.625)
		(mid 204.248744 148.501256)
		(end 204.125 148.45)
		(width 0.1)
		(layer "In5.Cu")
		(net 520)
	)
	(arc
		(start 203.775 149.15)
		(mid 203.651256 149.098744)
		(end 203.6 148.975)
		(width 0.1)
		(layer "In5.Cu")
		(net 520)
	)
	(arc
		(start 203.6 151.525)
		(mid 203.665901 151.365901)
		(end 203.825 151.3)
		(width 0.1)
		(layer "In5.Cu")
		(net 520)
	)
	(arc
		(start 204.125 152.7)
		(mid 204.248744 152.648744)
		(end 204.3 152.525)
		(width 0.1)
		(layer "In5.Cu")
		(net 520)
	)
	(arc
		(start 203.6 152.875)
		(mid 203.651256 152.751256)
		(end 203.775 152.7)
		(width 0.1)
		(layer "In5.Cu")
		(net 520)
	)
	(arc
		(start 205 154.925)
		(mid 204.876256 154.873744)
		(end 204.825 154.75)
		(width 0.1)
		(layer "In5.Cu")
		(net 520)
	)
	(arc
		(start 204.3 146.525)
		(mid 204.248744 146.401256)
		(end 204.125 146.35)
		(width 0.1)
		(layer "In5.Cu")
		(net 520)
	)
	(arc
		(start 204.125 148.8)
		(mid 204.248744 148.748744)
		(end 204.3 148.625)
		(width 0.1)
		(layer "In5.Cu")
		(net 520)
	)
	(arc
		(start 203.6 154.275)
		(mid 203.651256 154.151256)
		(end 203.775 154.1)
		(width 0.1)
		(layer "In5.Cu")
		(net 520)
	)
	(arc
		(start 204.125 149.5)
		(mid 204.248744 149.448744)
		(end 204.3 149.325)
		(width 0.1)
		(layer "In5.Cu")
		(net 520)
	)
	(arc
		(start 203.775 146.35)
		(mid 203.651256 146.298744)
		(end 203.6 146.175)
		(width 0.1)
		(layer "In5.Cu")
		(net 520)
	)
	(arc
		(start 203.6 148.275)
		(mid 203.651256 148.151256)
		(end 203.775 148.1)
		(width 0.1)
		(layer "In5.Cu")
		(net 520)
	)
	(arc
		(start 204.125 153.4)
		(mid 204.248744 153.348744)
		(end 204.3 153.225)
		(width 0.1)
		(layer "In5.Cu")
		(net 520)
	)
	(arc
		(start 204.075 151.3)
		(mid 204.234099 151.234099)
		(end 204.3 151.075)
		(width 0.1)
		(layer "In5.Cu")
		(net 520)
	)
	(arc
		(start 204.65 154.515795)
		(mid 204.526256 154.567051)
		(end 204.475 154.690795)
		(width 0.1)
		(layer "In5.Cu")
		(net 520)
	)
	(arc
		(start 204.475 154.75)
		(mid 204.423744 154.873744)
		(end 204.3 154.925)
		(width 0.1)
		(layer "In5.Cu")
		(net 520)
	)
	(arc
		(start 203.775 153.75)
		(mid 203.651256 153.698744)
		(end 203.6 153.575)
		(width 0.1)
		(layer "In5.Cu")
		(net 520)
	)
	(arc
		(start 203.6 149.675)
		(mid 203.651256 149.551256)
		(end 203.775 149.5)
		(width 0.1)
		(layer "In5.Cu")
		(net 520)
	)
	(arc
		(start 204.3 152.525)
		(mid 204.248744 152.401256)
		(end 204.125 152.35)
		(width 0.1)
		(layer "In5.Cu")
		(net 520)
	)
	(arc
		(start 204.3 149.325)
		(mid 204.248744 149.201256)
		(end 204.125 149.15)
		(width 0.1)
		(layer "In5.Cu")
		(net 520)
	)
	(arc
		(start 203.775 147.05)
		(mid 203.651256 146.998744)
		(end 203.6 146.875)
		(width 0.1)
		(layer "In5.Cu")
		(net 520)
	)
	(arc
		(start 203.6 148.975)
		(mid 203.651256 148.851256)
		(end 203.775 148.8)
		(width 0.1)
		(layer "In5.Cu")
		(net 520)
	)
	(arc
		(start 204.125 148.1)
		(mid 204.248744 148.048744)
		(end 204.3 147.925)
		(width 0.1)
		(layer "In5.Cu")
		(net 520)
	)
	(segment
		(start 203.5 134.5)
		(end 204 135)
		(width 0.256)
		(layer "F.Cu")
		(net 521)
	)
	(via
		(at 204 135)
		(size 0.45)
		(drill 0.2)
		(layers "F.Cu" "B.Cu")
		(net 521)
	)
	(via
		(at 222.1 145)
		(size 0.45)
		(drill 0.2)
		(layers "F.Cu" "B.Cu")
		(net 521)
	)
	(segment
		(start 222.1 145.715)
		(end 222.1 145)
		(width 0.184)
		(layer "B.Cu")
		(net 521)
	)
	(segment
		(start 205.1 147.1)
		(end 205.3 147.1)
		(width 0.1)
		(layer "In5.Cu")
		(net 521)
	)
	(segment
		(start 219.6 144.763689)
		(end 219.6 144.7)
		(width 0.1)
		(layer "In5.Cu")
		(net 521)
	)
	(segment
		(start 205.475 150.075)
		(end 205.475 150.125)
		(width 0.1)
		(layer "In5.Cu")
		(net 521)
	)
	(segment
		(start 204.6 135.6)
		(end 204.6 145.5)
		(width 0.1)
		(layer "In5.Cu")
		(net 521)
	)
	(segment
		(start 205.1 148.5)
		(end 205.3 148.5)
		(width 0.1)
		(layer "In5.Cu")
		(net 521)
	)
	(segment
		(start 204 135)
		(end 204.6 135.6)
		(width 0.1)
		(layer "In5.Cu")
		(net 521)
	)
	(segment
		(start 215.525 147.55)
		(end 218.55 144.525)
		(width 0.1)
		(layer "In5.Cu")
		(net 521)
	)
	(segment
		(start 220.65 144.7)
		(end 220.65 144.763689)
		(width 0.1)
		(layer "In5.Cu")
		(net 521)
	)
	(segment
		(start 219.25 144.7)
		(end 219.25 144.763689)
		(width 0.1)
		(layer "In5.Cu")
		(net 521)
	)
	(segment
		(start 205.475 153.75)
		(end 205.475 153.975)
		(width 0.1)
		(layer "In5.Cu")
		(net 521)
	)
	(segment
		(start 205.1 149.2)
		(end 205.3 149.2)
		(width 0.1)
		(layer "In5.Cu")
		(net 521)
	)
	(segment
		(start 212.3 152.5)
		(end 215.525 149.275)
		(width 0.1)
		(layer "In5.Cu")
		(net 521)
	)
	(segment
		(start 221.175 144.525)
		(end 221.225 144.525)
		(width 0.1)
		(layer "In5.Cu")
		(net 521)
	)
	(segment
		(start 205.3 146.75)
		(end 205.1 146.75)
		(width 0.1)
		(layer "In5.Cu")
		(net 521)
	)
	(segment
		(start 205.775 154.275)
		(end 208.913974 154.275)
		(width 0.1)
		(layer "In5.Cu")
		(net 521)
	)
	(segment
		(start 208.913974 154.275)
		(end 210.688972 152.5)
		(width 0.1)
		(layer "In5.Cu")
		(net 521)
	)
	(segment
		(start 218.55 144.525)
		(end 219.075 144.525)
		(width 0.1)
		(layer "In5.Cu")
		(net 521)
	)
	(segment
		(start 221 144.763689)
		(end 221 144.7)
		(width 0.1)
		(layer "In5.Cu")
		(net 521)
	)
	(segment
		(start 205.125 153.5)
		(end 205.275 153.5)
		(width 0.1)
		(layer "In5.Cu")
		(net 521)
	)
	(segment
		(start 205.125 152.7)
		(end 205.275 152.7)
		(width 0.1)
		(layer "In5.Cu")
		(net 521)
	)
	(segment
		(start 205.475 153.975)
		(end 205.775 154.275)
		(width 0.1)
		(layer "In5.Cu")
		(net 521)
	)
	(segment
		(start 210.688972 152.5)
		(end 212.3 152.5)
		(width 0.1)
		(layer "In5.Cu")
		(net 521)
	)
	(segment
		(start 221.625 144.525)
		(end 222.1 145)
		(width 0.1)
		(layer "In5.Cu")
		(net 521)
	)
	(segment
		(start 205.1 147.8)
		(end 205.3 147.8)
		(width 0.1)
		(layer "In5.Cu")
		(net 521)
	)
	(segment
		(start 205.475 146.375)
		(end 205.475 146.575)
		(width 0.1)
		(layer "In5.Cu")
		(net 521)
	)
	(segment
		(start 205.475 150.125)
		(end 205.475 152.1)
		(width 0.1)
		(layer "In5.Cu")
		(net 521)
	)
	(segment
		(start 205.3 149.55)
		(end 205.1 149.55)
		(width 0.1)
		(layer "In5.Cu")
		(net 521)
	)
	(segment
		(start 205.1 149.9)
		(end 205.3 149.9)
		(width 0.1)
		(layer "In5.Cu")
		(net 521)
	)
	(segment
		(start 204.6 145.5)
		(end 205.475 146.375)
		(width 0.1)
		(layer "In5.Cu")
		(net 521)
	)
	(segment
		(start 221.225 144.525)
		(end 221.625 144.525)
		(width 0.1)
		(layer "In5.Cu")
		(net 521)
	)
	(segment
		(start 205.3 148.85)
		(end 205.1 148.85)
		(width 0.1)
		(layer "In5.Cu")
		(net 521)
	)
	(segment
		(start 219.95 144.7)
		(end 219.95 144.763689)
		(width 0.1)
		(layer "In5.Cu")
		(net 521)
	)
	(segment
		(start 205.275 153.1)
		(end 205.125 153.1)
		(width 0.1)
		(layer "In5.Cu")
		(net 521)
	)
	(segment
		(start 215.525 149.275)
		(end 215.525 147.55)
		(width 0.1)
		(layer "In5.Cu")
		(net 521)
	)
	(segment
		(start 205.475 153.7)
		(end 205.475 153.75)
		(width 0.1)
		(layer "In5.Cu")
		(net 521)
	)
	(segment
		(start 205.275 152.3)
		(end 205.125 152.3)
		(width 0.1)
		(layer "In5.Cu")
		(net 521)
	)
	(segment
		(start 220.3 144.763689)
		(end 220.3 144.7)
		(width 0.1)
		(layer "In5.Cu")
		(net 521)
	)
	(segment
		(start 205.3 147.45)
		(end 205.1 147.45)
		(width 0.1)
		(layer "In5.Cu")
		(net 521)
	)
	(segment
		(start 205.3 148.15)
		(end 205.1 148.15)
		(width 0.1)
		(layer "In5.Cu")
		(net 521)
	)
	(arc
		(start 205.3 147.8)
		(mid 205.423744 147.851256)
		(end 205.475 147.975)
		(width 0.1)
		(layer "In5.Cu")
		(net 521)
	)
	(arc
		(start 204.925 146.925)
		(mid 204.976256 147.048744)
		(end 205.1 147.1)
		(width 0.1)
		(layer "In5.Cu")
		(net 521)
	)
	(arc
		(start 221 144.7)
		(mid 221.051256 144.576256)
		(end 221.175 144.525)
		(width 0.1)
		(layer "In5.Cu")
		(net 521)
	)
	(arc
		(start 205.275 152.7)
		(mid 205.416421 152.758579)
		(end 205.475 152.9)
		(width 0.1)
		(layer "In5.Cu")
		(net 521)
	)
	(arc
		(start 205.1 148.85)
		(mid 204.976256 148.901256)
		(end 204.925 149.025)
		(width 0.1)
		(layer "In5.Cu")
		(net 521)
	)
	(arc
		(start 219.425 144.938689)
		(mid 219.548744 144.887433)
		(end 219.6 144.763689)
		(width 0.1)
		(layer "In5.Cu")
		(net 521)
	)
	(arc
		(start 205.275 153.5)
		(mid 205.416421 153.558579)
		(end 205.475 153.7)
		(width 0.1)
		(layer "In5.Cu")
		(net 521)
	)
	(arc
		(start 204.925 152.5)
		(mid 204.983579 152.641421)
		(end 205.125 152.7)
		(width 0.1)
		(layer "In5.Cu")
		(net 521)
	)
	(arc
		(start 219.25 144.763689)
		(mid 219.301256 144.887433)
		(end 219.425 144.938689)
		(width 0.1)
		(layer "In5.Cu")
		(net 521)
	)
	(arc
		(start 205.475 148.675)
		(mid 205.423744 148.798744)
		(end 205.3 148.85)
		(width 0.1)
		(layer "In5.Cu")
		(net 521)
	)
	(arc
		(start 205.3 149.2)
		(mid 205.423744 149.251256)
		(end 205.475 149.375)
		(width 0.1)
		(layer "In5.Cu")
		(net 521)
	)
	(arc
		(start 220.3 144.7)
		(mid 220.351256 144.576256)
		(end 220.475 144.525)
		(width 0.1)
		(layer "In5.Cu")
		(net 521)
	)
	(arc
		(start 219.775 144.525)
		(mid 219.898744 144.576256)
		(end 219.95 144.7)
		(width 0.1)
		(layer "In5.Cu")
		(net 521)
	)
	(arc
		(start 219.075 144.525)
		(mid 219.198744 144.576256)
		(end 219.25 144.7)
		(width 0.1)
		(layer "In5.Cu")
		(net 521)
	)
	(arc
		(start 204.925 149.025)
		(mid 204.976256 149.148744)
		(end 205.1 149.2)
		(width 0.1)
		(layer "In5.Cu")
		(net 521)
	)
	(arc
		(start 205.1 149.55)
		(mid 204.976256 149.601256)
		(end 204.925 149.725)
		(width 0.1)
		(layer "In5.Cu")
		(net 521)
	)
	(arc
		(start 219.95 144.763689)
		(mid 220.001256 144.887433)
		(end 220.125 144.938689)
		(width 0.1)
		(layer "In5.Cu")
		(net 521)
	)
	(arc
		(start 205.3 149.9)
		(mid 205.423744 149.951256)
		(end 205.475 150.075)
		(width 0.1)
		(layer "In5.Cu")
		(net 521)
	)
	(arc
		(start 205.475 146.575)
		(mid 205.423744 146.698744)
		(end 205.3 146.75)
		(width 0.1)
		(layer "In5.Cu")
		(net 521)
	)
	(arc
		(start 205.125 153.1)
		(mid 204.983579 153.158579)
		(end 204.925 153.3)
		(width 0.1)
		(layer "In5.Cu")
		(net 521)
	)
	(arc
		(start 205.1 148.15)
		(mid 204.976256 148.201256)
		(end 204.925 148.325)
		(width 0.1)
		(layer "In5.Cu")
		(net 521)
	)
	(arc
		(start 205.1 146.75)
		(mid 204.976256 146.801256)
		(end 204.925 146.925)
		(width 0.1)
		(layer "In5.Cu")
		(net 521)
	)
	(arc
		(start 205.475 152.1)
		(mid 205.416421 152.241421)
		(end 205.275 152.3)
		(width 0.1)
		(layer "In5.Cu")
		(net 521)
	)
	(arc
		(start 204.925 147.625)
		(mid 204.976256 147.748744)
		(end 205.1 147.8)
		(width 0.1)
		(layer "In5.Cu")
		(net 521)
	)
	(arc
		(start 220.825 144.938689)
		(mid 220.948744 144.887433)
		(end 221 144.763689)
		(width 0.1)
		(layer "In5.Cu")
		(net 521)
	)
	(arc
		(start 219.6 144.7)
		(mid 219.651256 144.576256)
		(end 219.775 144.525)
		(width 0.1)
		(layer "In5.Cu")
		(net 521)
	)
	(arc
		(start 205.475 147.275)
		(mid 205.423744 147.398744)
		(end 205.3 147.45)
		(width 0.1)
		(layer "In5.Cu")
		(net 521)
	)
	(arc
		(start 204.925 153.3)
		(mid 204.983579 153.441421)
		(end 205.125 153.5)
		(width 0.1)
		(layer "In5.Cu")
		(net 521)
	)
	(arc
		(start 205.475 152.9)
		(mid 205.416421 153.041421)
		(end 205.275 153.1)
		(width 0.1)
		(layer "In5.Cu")
		(net 521)
	)
	(arc
		(start 220.475 144.525)
		(mid 220.598744 144.576256)
		(end 220.65 144.7)
		(width 0.1)
		(layer "In5.Cu")
		(net 521)
	)
	(arc
		(start 220.125 144.938689)
		(mid 220.248744 144.887433)
		(end 220.3 144.763689)
		(width 0.1)
		(layer "In5.Cu")
		(net 521)
	)
	(arc
		(start 205.475 147.975)
		(mid 205.423744 148.098744)
		(end 205.3 148.15)
		(width 0.1)
		(layer "In5.Cu")
		(net 521)
	)
	(arc
		(start 204.925 148.325)
		(mid 204.976256 148.448744)
		(end 205.1 148.5)
		(width 0.1)
		(layer "In5.Cu")
		(net 521)
	)
	(arc
		(start 205.125 152.3)
		(mid 204.983579 152.358579)
		(end 204.925 152.5)
		(width 0.1)
		(layer "In5.Cu")
		(net 521)
	)
	(arc
		(start 205.3 147.1)
		(mid 205.423744 147.151256)
		(end 205.475 147.275)
		(width 0.1)
		(layer "In5.Cu")
		(net 521)
	)
	(arc
		(start 204.925 149.725)
		(mid 204.976256 149.848744)
		(end 205.1 149.9)
		(width 0.1)
		(layer "In5.Cu")
		(net 521)
	)
	(arc
		(start 205.475 149.375)
		(mid 205.423744 149.498744)
		(end 205.3 149.55)
		(width 0.1)
		(layer "In5.Cu")
		(net 521)
	)
	(arc
		(start 220.65 144.763689)
		(mid 220.701256 144.887433)
		(end 220.825 144.938689)
		(width 0.1)
		(layer "In5.Cu")
		(net 521)
	)
	(arc
		(start 205.3 148.5)
		(mid 205.423744 148.551256)
		(end 205.475 148.675)
		(width 0.1)
		(layer "In5.Cu")
		(net 521)
	)
	(arc
		(start 205.1 147.45)
		(mid 204.976256 147.501256)
		(end 204.925 147.625)
		(width 0.1)
		(layer "In5.Cu")
		(net 521)
	)
	(segment
		(start 201.2 97.277149)
		(end 201.2 97.958748)
		(width 0.184)
		(layer "F.Cu")
		(net 522)
	)
	(segment
		(start 201.2 97.958748)
		(end 201.291252 98.05)
		(width 0.184)
		(layer "F.Cu")
		(net 522)
	)
	(segment
		(start 203.5 118.5)
		(end 204 118)
		(width 0.256)
		(layer "F.Cu")
		(net 522)
	)
	(via
		(at 201.291252 98.05)
		(size 0.45)
		(drill 0.2)
		(layers "F.Cu" "B.Cu")
		(net 522)
	)
	(via
		(at 204 118)
		(size 0.45)
		(drill 0.2)
		(layers "F.Cu" "B.Cu")
		(net 522)
	)
	(segment
		(start 201.891252 98.765)
		(end 201.891252 98.65)
		(width 0.184)
		(layer "B.Cu")
		(net 522)
	)
	(segment
		(start 201.891252 98.65)
		(end 201.291252 98.05)
		(width 0.184)
		(layer "B.Cu")
		(net 522)
	)
	(segment
		(start 199.031906 107.070505)
		(end 198.819948 107.28246)
		(width 0.1)
		(layer "In7.Cu")
		(net 522)
	)
	(segment
		(start 197.028203 105.685)
		(end 197.555 105.685)
		(width 0.1)
		(layer "In7.Cu")
		(net 522)
	)
	(segment
		(start 199.067435 107.529947)
		(end 199.067436 107.529949)
		(width 0.1)
		(layer "In7.Cu")
		(net 522)
	)
	(segment
		(start 200.516826 108.555426)
		(end 200.516828 108.555427)
		(width 0.1)
		(layer "In7.Cu")
		(net 522)
	)
	(segment
		(start 198.572461 107.034973)
		(end 198.572462 107.034975)
		(width 0.1)
		(layer "In7.Cu")
		(net 522)
	)
	(segment
		(start 200.799844 109.509844)
		(end 201.02 109.73)
		(width 0.1)
		(layer "In7.Cu")
		(net 522)
	)
	(segment
		(start 199.031904 107.070504)
		(end 199.031906 107.070505)
		(width 0.1)
		(layer "In7.Cu")
		(net 522)
	)
	(segment
		(start 197.028203 104.285)
		(end 197.555 104.285)
		(width 0.1)
		(layer "In7.Cu")
		(net 522)
	)
	(segment
		(start 200.057383 108.519895)
		(end 200.057384 108.519897)
		(width 0.1)
		(layer "In7.Cu")
		(net 522)
	)
	(segment
		(start 201.291252 98.05)
		(end 201.291252 98.828748)
		(width 0.1)
		(layer "In7.Cu")
		(net 522)
	)
	(segment
		(start 199.56241 108.024923)
		(end 199.774365 107.812965)
		(width 0.1)
		(layer "In7.Cu")
		(net 522)
	)
	(segment
		(start 197.555 105.335)
		(end 197.028203 105.335)
		(width 0.1)
		(layer "In7.Cu")
		(net 522)
	)
	(segment
		(start 203.775 113.475)
		(end 203.775 117.775)
		(width 0.1)
		(layer "In7.Cu")
		(net 522)
	)
	(segment
		(start 198.53693 106.57553)
		(end 198.536932 106.575531)
		(width 0.1)
		(layer "In7.Cu")
		(net 522)
	)
	(segment
		(start 200.021852 108.060452)
		(end 200.021854 108.060453)
		(width 0.1)
		(layer "In7.Cu")
		(net 522)
	)
	(segment
		(start 197.73 102.39)
		(end 197.73 103.06)
		(width 0.1)
		(layer "In7.Cu")
		(net 522)
	)
	(segment
		(start 200.057384 108.519897)
		(end 200.269339 108.307939)
		(width 0.1)
		(layer "In7.Cu")
		(net 522)
	)
	(segment
		(start 201.291252 98.828748)
		(end 197.73 102.39)
		(width 0.1)
		(layer "In7.Cu")
		(net 522)
	)
	(segment
		(start 198.536932 106.575531)
		(end 198.324974 106.787486)
		(width 0.1)
		(layer "In7.Cu")
		(net 522)
	)
	(segment
		(start 198.077488 106.540001)
		(end 198.289443 106.328043)
		(width 0.1)
		(layer "In7.Cu")
		(net 522)
	)
	(segment
		(start 199.52688 107.565479)
		(end 199.314922 107.777434)
		(width 0.1)
		(layer "In7.Cu")
		(net 522)
	)
	(segment
		(start 197.028203 103.585)
		(end 197.555 103.585)
		(width 0.1)
		(layer "In7.Cu")
		(net 522)
	)
	(segment
		(start 201.011802 109.050401)
		(end 200.799844 109.262356)
		(width 0.1)
		(layer "In7.Cu")
		(net 522)
	)
	(segment
		(start 199.067436 107.529949)
		(end 199.279391 107.317991)
		(width 0.1)
		(layer "In7.Cu")
		(net 522)
	)
	(segment
		(start 201.02 109.73)
		(end 201.02 110.72)
		(width 0.1)
		(layer "In7.Cu")
		(net 522)
	)
	(segment
		(start 200.021854 108.060453)
		(end 199.809896 108.272408)
		(width 0.1)
		(layer "In7.Cu")
		(net 522)
	)
	(segment
		(start 199.526878 107.565478)
		(end 199.52688 107.565479)
		(width 0.1)
		(layer "In7.Cu")
		(net 522)
	)
	(segment
		(start 200.552358 109.014871)
		(end 200.764313 108.802913)
		(width 0.1)
		(layer "In7.Cu")
		(net 522)
	)
	(segment
		(start 197.73 105.86)
		(end 197.73 106.44)
		(width 0.1)
		(layer "In7.Cu")
		(net 522)
	)
	(segment
		(start 201.0118 109.0504)
		(end 201.011802 109.050401)
		(width 0.1)
		(layer "In7.Cu")
		(net 522)
	)
	(segment
		(start 197.555 103.935)
		(end 197.028203 103.935)
		(width 0.1)
		(layer "In7.Cu")
		(net 522)
	)
	(segment
		(start 198.572462 107.034975)
		(end 198.784417 106.823017)
		(width 0.1)
		(layer "In7.Cu")
		(net 522)
	)
	(segment
		(start 197.555 104.635)
		(end 197.028203 104.635)
		(width 0.1)
		(layer "In7.Cu")
		(net 522)
	)
	(segment
		(start 199.562409 108.024921)
		(end 199.56241 108.024923)
		(width 0.1)
		(layer "In7.Cu")
		(net 522)
	)
	(segment
		(start 198.077487 106.539999)
		(end 198.077488 106.540001)
		(width 0.1)
		(layer "In7.Cu")
		(net 522)
	)
	(segment
		(start 197.555 103.235)
		(end 197.028203 103.235)
		(width 0.1)
		(layer "In7.Cu")
		(net 522)
	)
	(segment
		(start 201.02 110.72)
		(end 203.775 113.475)
		(width 0.1)
		(layer "In7.Cu")
		(net 522)
	)
	(segment
		(start 203.775 117.775)
		(end 204 118)
		(width 0.1)
		(layer "In7.Cu")
		(net 522)
	)
	(segment
		(start 197.73 106.44)
		(end 197.83 106.54)
		(width 0.1)
		(layer "In7.Cu")
		(net 522)
	)
	(segment
		(start 200.516828 108.555427)
		(end 200.30487 108.767382)
		(width 0.1)
		(layer "In7.Cu")
		(net 522)
	)
	(segment
		(start 197.028203 104.985)
		(end 197.555 104.985)
		(width 0.1)
		(layer "In7.Cu")
		(net 522)
	)
	(segment
		(start 200.552357 109.014869)
		(end 200.552358 109.014871)
		(width 0.1)
		(layer "In7.Cu")
		(net 522)
	)
	(arc
		(start 199.314922 107.777434)
		(mid 199.263666 107.901178)
		(end 199.314922 108.024922)
		(width 0.1)
		(layer "In7.Cu")
		(net 522)
	)
	(arc
		(start 198.784417 106.823017)
		(mid 198.908161 106.771761)
		(end 199.031905 106.823017)
		(width 0.1)
		(layer "In7.Cu")
		(net 522)
	)
	(arc
		(start 198.819948 107.529948)
		(mid 198.943692 107.581204)
		(end 199.067435 107.529947)
		(width 0.1)
		(layer "In7.Cu")
		(net 522)
	)
	(arc
		(start 200.764313 108.802913)
		(mid 200.888057 108.751657)
		(end 201.011801 108.802913)
		(width 0.1)
		(layer "In7.Cu")
		(net 522)
	)
	(arc
		(start 196.853203 103.41)
		(mid 196.904459 103.533744)
		(end 197.028203 103.585)
		(width 0.1)
		(layer "In7.Cu")
		(net 522)
	)
	(arc
		(start 200.30487 109.01487)
		(mid 200.428614 109.066126)
		(end 200.552357 109.014869)
		(width 0.1)
		(layer "In7.Cu")
		(net 522)
	)
	(arc
		(start 200.516827 108.307939)
		(mid 200.568083 108.431683)
		(end 200.516826 108.555426)
		(width 0.1)
		(layer "In7.Cu")
		(net 522)
	)
	(arc
		(start 200.30487 108.767382)
		(mid 200.253614 108.891126)
		(end 200.30487 109.01487)
		(width 0.1)
		(layer "In7.Cu")
		(net 522)
	)
	(arc
		(start 199.809896 108.272408)
		(mid 199.75864 108.396152)
		(end 199.809896 108.519896)
		(width 0.1)
		(layer "In7.Cu")
		(net 522)
	)
	(arc
		(start 201.011801 108.802913)
		(mid 201.063057 108.926657)
		(end 201.0118 109.0504)
		(width 0.1)
		(layer "In7.Cu")
		(net 522)
	)
	(arc
		(start 198.536931 106.328043)
		(mid 198.588187 106.451787)
		(end 198.53693 106.57553)
		(width 0.1)
		(layer "In7.Cu")
		(net 522)
	)
	(arc
		(start 197.028203 103.235)
		(mid 196.904459 103.286256)
		(end 196.853203 103.41)
		(width 0.1)
		(layer "In7.Cu")
		(net 522)
	)
	(arc
		(start 197.83 106.54)
		(mid 197.953744 106.591256)
		(end 198.077487 106.539999)
		(width 0.1)
		(layer "In7.Cu")
		(net 522)
	)
	(arc
		(start 197.73 105.16)
		(mid 197.678744 105.283744)
		(end 197.555 105.335)
		(width 0.1)
		(layer "In7.Cu")
		(net 522)
	)
	(arc
		(start 197.028203 103.935)
		(mid 196.904459 103.986256)
		(end 196.853203 104.11)
		(width 0.1)
		(layer "In7.Cu")
		(net 522)
	)
	(arc
		(start 197.555 104.985)
		(mid 197.678744 105.036256)
		(end 197.73 105.16)
		(width 0.1)
		(layer "In7.Cu")
		(net 522)
	)
	(arc
		(start 196.853203 104.11)
		(mid 196.904459 104.233744)
		(end 197.028203 104.285)
		(width 0.1)
		(layer "In7.Cu")
		(net 522)
	)
	(arc
		(start 200.021853 107.812965)
		(mid 200.073109 107.936709)
		(end 200.021852 108.060452)
		(width 0.1)
		(layer "In7.Cu")
		(net 522)
	)
	(arc
		(start 197.73 104.46)
		(mid 197.678744 104.583744)
		(end 197.555 104.635)
		(width 0.1)
		(layer "In7.Cu")
		(net 522)
	)
	(arc
		(start 197.555 103.585)
		(mid 197.678744 103.636256)
		(end 197.73 103.76)
		(width 0.1)
		(layer "In7.Cu")
		(net 522)
	)
	(arc
		(start 199.279391 107.317991)
		(mid 199.403135 107.266735)
		(end 199.526879 107.317991)
		(width 0.1)
		(layer "In7.Cu")
		(net 522)
	)
	(arc
		(start 200.799844 109.262356)
		(mid 200.748588 109.3861)
		(end 200.799844 109.509844)
		(width 0.1)
		(layer "In7.Cu")
		(net 522)
	)
	(arc
		(start 197.73 103.76)
		(mid 197.678744 103.883744)
		(end 197.555 103.935)
		(width 0.1)
		(layer "In7.Cu")
		(net 522)
	)
	(arc
		(start 197.028203 105.335)
		(mid 196.904459 105.386256)
		(end 196.853203 105.51)
		(width 0.1)
		(layer "In7.Cu")
		(net 522)
	)
	(arc
		(start 199.774365 107.812965)
		(mid 199.898109 107.761709)
		(end 200.021853 107.812965)
		(width 0.1)
		(layer "In7.Cu")
		(net 522)
	)
	(arc
		(start 197.028203 104.635)
		(mid 196.904459 104.686256)
		(end 196.853203 104.81)
		(width 0.1)
		(layer "In7.Cu")
		(net 522)
	)
	(arc
		(start 196.853203 105.51)
		(mid 196.904459 105.633744)
		(end 197.028203 105.685)
		(width 0.1)
		(layer "In7.Cu")
		(net 522)
	)
	(arc
		(start 197.73 103.06)
		(mid 197.678744 103.183744)
		(end 197.555 103.235)
		(width 0.1)
		(layer "In7.Cu")
		(net 522)
	)
	(arc
		(start 196.853203 104.81)
		(mid 196.904459 104.933744)
		(end 197.028203 104.985)
		(width 0.1)
		(layer "In7.Cu")
		(net 522)
	)
	(arc
		(start 198.819948 107.28246)
		(mid 198.768692 107.406204)
		(end 198.819948 107.529948)
		(width 0.1)
		(layer "In7.Cu")
		(net 522)
	)
	(arc
		(start 200.269339 108.307939)
		(mid 200.393083 108.256683)
		(end 200.516827 108.307939)
		(width 0.1)
		(layer "In7.Cu")
		(net 522)
	)
	(arc
		(start 198.289443 106.328043)
		(mid 198.413187 106.276787)
		(end 198.536931 106.328043)
		(width 0.1)
		(layer "In7.Cu")
		(net 522)
	)
	(arc
		(start 199.809896 108.519896)
		(mid 199.93364 108.571152)
		(end 200.057383 108.519895)
		(width 0.1)
		(layer "In7.Cu")
		(net 522)
	)
	(arc
		(start 198.324974 106.787486)
		(mid 198.273718 106.91123)
		(end 198.324974 107.034974)
		(width 0.1)
		(layer "In7.Cu")
		(net 522)
	)
	(arc
		(start 199.526879 107.317991)
		(mid 199.578135 107.441735)
		(end 199.526878 107.565478)
		(width 0.1)
		(layer "In7.Cu")
		(net 522)
	)
	(arc
		(start 198.324974 107.034974)
		(mid 198.448718 107.08623)
		(end 198.572461 107.034973)
		(width 0.1)
		(layer "In7.Cu")
		(net 522)
	)
	(arc
		(start 197.555 105.685)
		(mid 197.678744 105.736256)
		(end 197.73 105.86)
		(width 0.1)
		(layer "In7.Cu")
		(net 522)
	)
	(arc
		(start 199.031905 106.823017)
		(mid 199.083161 106.946761)
		(end 199.031904 107.070504)
		(width 0.1)
		(layer "In7.Cu")
		(net 522)
	)
	(arc
		(start 199.314922 108.024922)
		(mid 199.438666 108.076178)
		(end 199.562409 108.024921)
		(width 0.1)
		(layer "In7.Cu")
		(net 522)
	)
	(arc
		(start 197.555 104.285)
		(mid 197.678744 104.336256)
		(end 197.73 104.46)
		(width 0.1)
		(layer "In7.Cu")
		(net 522)
	)
	(segment
		(start 202.5 118.5)
		(end 203 118)
		(width 0.256)
		(layer "F.Cu")
		(net 523)
	)
	(segment
		(start 198.7 97.741252)
		(end 198.7 97.277149)
		(width 0.182)
		(layer "F.Cu")
		(net 523)
	)
	(segment
		(start 198.291252 98.15)
		(end 198.7 97.741252)
		(width 0.182)
		(layer "F.Cu")
		(net 523)
	)
	(via
		(at 198.291252 98.15)
		(size 0.45)
		(drill 0.2)
		(layers "F.Cu" "B.Cu")
		(net 523)
	)
	(via
		(at 203 118)
		(size 0.45)
		(drill 0.2)
		(layers "F.Cu" "B.Cu")
		(net 523)
	)
	(segment
		(start 197.991252 98.765)
		(end 197.991252 98.45)
		(width 0.184)
		(layer "B.Cu")
		(net 523)
	)
	(segment
		(start 197.991252 98.45)
		(end 198.291252 98.15)
		(width 0.184)
		(layer "B.Cu")
		(net 523)
	)
	(segment
		(start 195.23 103.71)
		(end 195.68 103.71)
		(width 0.1)
		(layer "In7.Cu")
		(net 523)
	)
	(segment
		(start 195.68 106.51)
		(end 195.23 106.51)
		(width 0.1)
		(layer "In7.Cu")
		(net 523)
	)
	(segment
		(start 196.730603 99.710653)
		(end 196.730603 99.710652)
		(width 0.1)
		(layer "In7.Cu")
		(net 523)
	)
	(segment
		(start 196.730603 99.710652)
		(end 196.730602 99.71065)
		(width 0.1)
		(layer "In7.Cu")
		(net 523)
	)
	(segment
		(start 202.42 117.42)
		(end 202.42 113.72)
		(width 0.1)
		(layer "In7.Cu")
		(net 523)
	)
	(segment
		(start 197.225579 98.968186)
		(end 197.048064 98.790671)
		(width 0.1)
		(layer "In7.Cu")
		(net 523)
	)
	(segment
		(start 196.235626 99.95814)
		(end 196.235627 99.958138)
		(width 0.1)
		(layer "In7.Cu")
		(net 523)
	)
	(segment
		(start 196.305599 99.533137)
		(end 196.483115 99.710653)
		(width 0.1)
		(layer "In7.Cu")
		(net 523)
	)
	(segment
		(start 196.235627 99.958138)
		(end 196.058112 99.780623)
		(width 0.1)
		(layer "In7.Cu")
		(net 523)
	)
	(segment
		(start 195.88 100.561252)
		(end 196.235626 100.205626)
		(width 0.1)
		(layer "In7.Cu")
		(net 523)
	)
	(segment
		(start 202.42 113.72)
		(end 195.88 107.18)
		(width 0.1)
		(layer "In7.Cu")
		(net 523)
	)
	(segment
		(start 195.68 102.45)
		(end 195.23 102.45)
		(width 0.1)
		(layer "In7.Cu")
		(net 523)
	)
	(segment
		(start 195.88 103.51)
		(end 195.88 103.46)
		(width 0.1)
		(layer "In7.Cu")
		(net 523)
	)
	(segment
		(start 197.720555 98.7207)
		(end 198.291252 98.15)
		(width 0.1)
		(layer "In7.Cu")
		(net 523)
	)
	(segment
		(start 197.225579 99.215676)
		(end 197.225578 99.215674)
		(width 0.1)
		(layer "In7.Cu")
		(net 523)
	)
	(segment
		(start 195.23 102.05)
		(end 195.68 102.05)
		(width 0.1)
		(layer "In7.Cu")
		(net 523)
	)
	(segment
		(start 196.553088 99.038159)
		(end 196.553087 99.038161)
		(width 0.1)
		(layer "In7.Cu")
		(net 523)
	)
	(segment
		(start 195.68 104.11)
		(end 195.23 104.11)
		(width 0.1)
		(layer "In7.Cu")
		(net 523)
	)
	(segment
		(start 197.225578 98.968188)
		(end 197.225579 98.968186)
		(width 0.1)
		(layer "In7.Cu")
		(net 523)
	)
	(segment
		(start 195.88 101)
		(end 195.88 100.561252)
		(width 0.1)
		(layer "In7.Cu")
		(net 523)
	)
	(segment
		(start 203 118)
		(end 202.42 117.42)
		(width 0.1)
		(layer "In7.Cu")
		(net 523)
	)
	(segment
		(start 195.88 101.05)
		(end 195.88 101)
		(width 0.1)
		(layer "In7.Cu")
		(net 523)
	)
	(segment
		(start 196.730603 99.463162)
		(end 196.553088 99.285647)
		(width 0.1)
		(layer "In7.Cu")
		(net 523)
	)
	(segment
		(start 196.730602 99.463164)
		(end 196.730603 99.463162)
		(width 0.1)
		(layer "In7.Cu")
		(net 523)
	)
	(segment
		(start 197.225579 99.215677)
		(end 197.225579 99.215676)
		(width 0.1)
		(layer "In7.Cu")
		(net 523)
	)
	(segment
		(start 195.68 104.91)
		(end 195.23 104.91)
		(width 0.1)
		(layer "In7.Cu")
		(net 523)
	)
	(segment
		(start 195.23 104.51)
		(end 195.68 104.51)
		(width 0.1)
		(layer "In7.Cu")
		(net 523)
	)
	(segment
		(start 195.88 103.46)
		(end 195.88 102.65)
		(width 0.1)
		(layer "In7.Cu")
		(net 523)
	)
	(segment
		(start 195.23 105.31)
		(end 195.68 105.31)
		(width 0.1)
		(layer "In7.Cu")
		(net 523)
	)
	(segment
		(start 196.058112 99.533135)
		(end 196.058111 99.533137)
		(width 0.1)
		(layer "In7.Cu")
		(net 523)
	)
	(segment
		(start 197.295551 98.543185)
		(end 197.473067 98.720701)
		(width 0.1)
		(layer "In7.Cu")
		(net 523)
	)
	(segment
		(start 195.23 106.11)
		(end 195.68 106.11)
		(width 0.1)
		(layer "In7.Cu")
		(net 523)
	)
	(segment
		(start 195.68 101.65)
		(end 195.23 101.65)
		(width 0.1)
		(layer "In7.Cu")
		(net 523)
	)
	(segment
		(start 195.68 105.71)
		(end 195.23 105.71)
		(width 0.1)
		(layer "In7.Cu")
		(net 523)
	)
	(segment
		(start 195.88 107.18)
		(end 195.88 106.71)
		(width 0.1)
		(layer "In7.Cu")
		(net 523)
	)
	(segment
		(start 195.23 101.25)
		(end 195.68 101.25)
		(width 0.1)
		(layer "In7.Cu")
		(net 523)
	)
	(segment
		(start 197.048064 98.543183)
		(end 197.048063 98.543185)
		(width 0.1)
		(layer "In7.Cu")
		(net 523)
	)
	(segment
		(start 197.720555 98.720701)
		(end 197.720555 98.7207)
		(width 0.1)
		(layer "In7.Cu")
		(net 523)
	)
	(segment
		(start 196.800575 99.038161)
		(end 196.978091 99.215677)
		(width 0.1)
		(layer "In7.Cu")
		(net 523)
	)
	(arc
		(start 195.88 105.11)
		(mid 195.821421 104.968579)
		(end 195.68 104.91)
		(width 0.1)
		(layer "In7.Cu")
		(net 523)
	)
	(arc
		(start 195.68 105.31)
		(mid 195.821421 105.251421)
		(end 195.88 105.11)
		(width 0.1)
		(layer "In7.Cu")
		(net 523)
	)
	(arc
		(start 195.68 106.11)
		(mid 195.821421 106.051421)
		(end 195.88 105.91)
		(width 0.1)
		(layer "In7.Cu")
		(net 523)
	)
	(arc
		(start 195.88 102.65)
		(mid 195.821421 102.508579)
		(end 195.68 102.45)
		(width 0.1)
		(layer "In7.Cu")
		(net 523)
	)
	(arc
		(start 196.058112 99.780623)
		(mid 196.006856 99.656879)
		(end 196.058112 99.533135)
		(width 0.1)
		(layer "In7.Cu")
		(net 523)
	)
	(arc
		(start 196.553088 99.285647)
		(mid 196.501832 99.161903)
		(end 196.553088 99.038159)
		(width 0.1)
		(layer "In7.Cu")
		(net 523)
	)
	(arc
		(start 195.88 106.71)
		(mid 195.821421 106.568579)
		(end 195.68 106.51)
		(width 0.1)
		(layer "In7.Cu")
		(net 523)
	)
	(arc
		(start 195.68 102.05)
		(mid 195.821421 101.991421)
		(end 195.88 101.85)
		(width 0.1)
		(layer "In7.Cu")
		(net 523)
	)
	(arc
		(start 197.473067 98.720701)
		(mid 197.596811 98.771957)
		(end 197.720555 98.720701)
		(width 0.1)
		(layer "In7.Cu")
		(net 523)
	)
	(arc
		(start 195.23 104.91)
		(mid 195.088579 104.851421)
		(end 195.03 104.71)
		(width 0.1)
		(layer "In7.Cu")
		(net 523)
	)
	(arc
		(start 197.225578 99.215674)
		(mid 197.276835 99.09193)
		(end 197.225578 98.968188)
		(width 0.1)
		(layer "In7.Cu")
		(net 523)
	)
	(arc
		(start 195.03 103.91)
		(mid 195.088579 103.768579)
		(end 195.23 103.71)
		(width 0.1)
		(layer "In7.Cu")
		(net 523)
	)
	(arc
		(start 195.23 101.65)
		(mid 195.088579 101.591421)
		(end 195.03 101.45)
		(width 0.1)
		(layer "In7.Cu")
		(net 523)
	)
	(arc
		(start 197.048063 98.543185)
		(mid 197.171807 98.491929)
		(end 197.295551 98.543185)
		(width 0.1)
		(layer "In7.Cu")
		(net 523)
	)
	(arc
		(start 195.23 104.11)
		(mid 195.088579 104.051421)
		(end 195.03 103.91)
		(width 0.1)
		(layer "In7.Cu")
		(net 523)
	)
	(arc
		(start 195.88 105.91)
		(mid 195.821421 105.768579)
		(end 195.68 105.71)
		(width 0.1)
		(layer "In7.Cu")
		(net 523)
	)
	(arc
		(start 195.68 104.51)
		(mid 195.821421 104.451421)
		(end 195.88 104.31)
		(width 0.1)
		(layer "In7.Cu")
		(net 523)
	)
	(arc
		(start 197.048064 98.790671)
		(mid 196.996808 98.666927)
		(end 197.048064 98.543183)
		(width 0.1)
		(layer "In7.Cu")
		(net 523)
	)
	(arc
		(start 195.68 103.71)
		(mid 195.821421 103.651421)
		(end 195.88 103.51)
		(width 0.1)
		(layer "In7.Cu")
		(net 523)
	)
	(arc
		(start 195.03 101.45)
		(mid 195.088579 101.308579)
		(end 195.23 101.25)
		(width 0.1)
		(layer "In7.Cu")
		(net 523)
	)
	(arc
		(start 195.03 104.71)
		(mid 195.088579 104.568579)
		(end 195.23 104.51)
		(width 0.1)
		(layer "In7.Cu")
		(net 523)
	)
	(arc
		(start 196.235626 100.205626)
		(mid 196.286883 100.081882)
		(end 196.235626 99.95814)
		(width 0.1)
		(layer "In7.Cu")
		(net 523)
	)
	(arc
		(start 195.03 105.51)
		(mid 195.088579 105.368579)
		(end 195.23 105.31)
		(width 0.1)
		(layer "In7.Cu")
		(net 523)
	)
	(arc
		(start 195.23 102.45)
		(mid 195.088579 102.391421)
		(end 195.03 102.25)
		(width 0.1)
		(layer "In7.Cu")
		(net 523)
	)
	(arc
		(start 196.058111 99.533137)
		(mid 196.181855 99.481881)
		(end 196.305599 99.533137)
		(width 0.1)
		(layer "In7.Cu")
		(net 523)
	)
	(arc
		(start 196.978091 99.215677)
		(mid 197.101835 99.266933)
		(end 197.225579 99.215677)
		(width 0.1)
		(layer "In7.Cu")
		(net 523)
	)
	(arc
		(start 195.88 101.85)
		(mid 195.821421 101.708579)
		(end 195.68 101.65)
		(width 0.1)
		(layer "In7.Cu")
		(net 523)
	)
	(arc
		(start 195.03 102.25)
		(mid 195.088579 102.108579)
		(end 195.23 102.05)
		(width 0.1)
		(layer "In7.Cu")
		(net 523)
	)
	(arc
		(start 196.730602 99.71065)
		(mid 196.781859 99.586906)
		(end 196.730602 99.463164)
		(width 0.1)
		(layer "In7.Cu")
		(net 523)
	)
	(arc
		(start 195.23 105.71)
		(mid 195.088579 105.651421)
		(end 195.03 105.51)
		(width 0.1)
		(layer "In7.Cu")
		(net 523)
	)
	(arc
		(start 195.68 101.25)
		(mid 195.821421 101.191421)
		(end 195.88 101.05)
		(width 0.1)
		(layer "In7.Cu")
		(net 523)
	)
	(arc
		(start 195.23 106.51)
		(mid 195.088579 106.451421)
		(end 195.03 106.31)
		(width 0.1)
		(layer "In7.Cu")
		(net 523)
	)
	(arc
		(start 196.483115 99.710653)
		(mid 196.606859 99.761909)
		(end 196.730603 99.710653)
		(width 0.1)
		(layer "In7.Cu")
		(net 523)
	)
	(arc
		(start 196.553087 99.038161)
		(mid 196.676831 98.986905)
		(end 196.800575 99.038161)
		(width 0.1)
		(layer "In7.Cu")
		(net 523)
	)
	(arc
		(start 195.88 104.31)
		(mid 195.821421 104.168579)
		(end 195.68 104.11)
		(width 0.1)
		(layer "In7.Cu")
		(net 523)
	)
	(arc
		(start 195.03 106.31)
		(mid 195.088579 106.168579)
		(end 195.23 106.11)
		(width 0.1)
		(layer "In7.Cu")
		(net 523)
	)
	(segment
		(start 243.3455 103.9805)
		(end 243.665 104.3)
		(width 0.153)
		(layer "F.Cu")
		(net 524)
	)
	(segment
		(start 203.6 117.1)
		(end 203.816422 117.1)
		(width 0.1)
		(layer "F.Cu")
		(net 524)
	)
	(segment
		(start 204.1805 111.5745)
		(end 204.1805 111.399766)
		(width 0.153)
		(layer "F.Cu")
		(net 524)
	)
	(segment
		(start 203.5 117.5)
		(end 203.5 117.2)
		(width 0.1)
		(layer "F.Cu")
		(net 524)
	)
	(segment
		(start 203.5 117.2)
		(end 203.6 117.1)
		(width 0.1)
		(layer "F.Cu")
		(net 524)
	)
	(segment
		(start 204.1 115.175)
		(end 204.1 116.816422)
		(width 0.1)
		(layer "F.Cu")
		(net 524)
	)
	(segment
		(start 204.367387 111.801)
		(end 204.357 111.801)
		(width 0.153)
		(layer "F.Cu")
		(net 524)
	)
	(segment
		(start 203.816422 117.1)
		(end 204.1 116.816422)
		(width 0.1)
		(layer "F.Cu")
		(net 524)
	)
	(segment
		(start 204.1805 111.6245)
		(end 204.1805 111.5745)
		(width 0.153)
		(layer "F.Cu")
		(net 524)
	)
	(segment
		(start 204.1 115.175)
		(end 204.1805 115.0945)
		(width 0.1)
		(layer "F.Cu")
		(net 524)
	)
	(segment
		(start 204.1805 115.0945)
		(end 204.1805 112.3305)
		(width 0.153)
		(layer "F.Cu")
		(net 524)
	)
	(segment
		(start 204.1805 111.399766)
		(end 211.599766 103.9805)
		(width 0.153)
		(layer "F.Cu")
		(net 524)
	)
	(segment
		(start 204.357 112.154)
		(end 204.367387 112.154)
		(width 0.153)
		(layer "F.Cu")
		(net 524)
	)
	(segment
		(start 211.599766 103.9805)
		(end 243.3455 103.9805)
		(width 0.153)
		(layer "F.Cu")
		(net 524)
	)
	(arc
		(start 204.367387 112.154)
		(mid 204.492191 112.102304)
		(end 204.543887 111.9775)
		(width 0.153)
		(layer "F.Cu")
		(net 524)
	)
	(arc
		(start 204.1805 112.3305)
		(mid 204.232196 112.205696)
		(end 204.357 112.154)
		(width 0.153)
		(layer "F.Cu")
		(net 524)
	)
	(arc
		(start 204.543887 111.9775)
		(mid 204.492191 111.852696)
		(end 204.367387 111.801)
		(width 0.153)
		(layer "F.Cu")
		(net 524)
	)
	(arc
		(start 204.357 111.801)
		(mid 204.232196 111.749304)
		(end 204.1805 111.6245)
		(width 0.153)
		(layer "F.Cu")
		(net 524)
	)
	(segment
		(start 243.665 103.3)
		(end 243.3455 103.6195)
		(width 0.153)
		(layer "F.Cu")
		(net 525)
	)
	(segment
		(start 243.3455 103.6195)
		(end 211.450234 103.6195)
		(width 0.153)
		(layer "F.Cu")
		(net 525)
	)
	(segment
		(start 203.9 116.73358)
		(end 203.733578 116.9)
		(width 0.1)
		(layer "F.Cu")
		(net 525)
	)
	(segment
		(start 203.9 115.175)
		(end 203.9 116.73358)
		(width 0.1)
		(layer "F.Cu")
		(net 525)
	)
	(segment
		(start 203.8195 115.0945)
		(end 203.9 115.175)
		(width 0.1)
		(layer "F.Cu")
		(net 525)
	)
	(segment
		(start 203.8195 111.250234)
		(end 203.8195 115.0945)
		(width 0.153)
		(layer "F.Cu")
		(net 525)
	)
	(segment
		(start 203.6 116.9)
		(end 203.5 116.8)
		(width 0.1)
		(layer "F.Cu")
		(net 525)
	)
	(segment
		(start 203.733578 116.9)
		(end 203.6 116.9)
		(width 0.1)
		(layer "F.Cu")
		(net 525)
	)
	(segment
		(start 211.450234 103.6195)
		(end 203.8195 111.250234)
		(width 0.153)
		(layer "F.Cu")
		(net 525)
	)
	(segment
		(start 203.5 116.8)
		(end 203.5 116.5)
		(width 0.1)
		(layer "F.Cu")
		(net 525)
	)
	(segment
		(start 205.1 116.81642)
		(end 204.81642 117.1)
		(width 0.1)
		(layer "F.Cu")
		(net 526)
	)
	(segment
		(start 233.886 105.7805)
		(end 233.886 104.94389)
		(width 0.153)
		(layer "F.Cu")
		(net 526)
	)
	(segment
		(start 205.098 115.177)
		(end 205.1 115.179)
		(width 0.1)
		(layer "F.Cu")
		(net 526)
	)
	(segment
		(start 232.775 104.94389)
		(end 232.775 105.225)
		(width 0.153)
		(layer "F.Cu")
		(net 526)
	)
	(segment
		(start 205.1805 115.0945)
		(end 205.098 115.177)
		(width 0.1)
		(layer "F.Cu")
		(net 526)
	)
	(segment
		(start 232.775 105.225)
		(end 232.775 106.15611)
		(width 0.153)
		(layer "F.Cu")
		(net 526)
	)
	(segment
		(start 234.275 104.94389)
		(end 234.275 105.4195)
		(width 0.153)
		(layer "F.Cu")
		(net 526)
	)
	(segment
		(start 205.1805 115.0945)
		(end 205.1805 112.549766)
		(width 0.153)
		(layer "F.Cu")
		(net 526)
	)
	(segment
		(start 233.886 106.15611)
		(end 233.886 105.7805)
		(width 0.153)
		(layer "F.Cu")
		(net 526)
	)
	(segment
		(start 237.881618 105.7805)
		(end 241.3455 105.7805)
		(width 0.153)
		(layer "F.Cu")
		(net 526)
	)
	(segment
		(start 205.1 115.179)
		(end 205.1 116.81642)
		(width 0.1)
		(layer "F.Cu")
		(net 526)
	)
	(segment
		(start 234.275 105.4195)
		(end 234.275 106.15611)
		(width 0.153)
		(layer "F.Cu")
		(net 526)
	)
	(segment
		(start 211.949766 105.7805)
		(end 231.8305 105.7805)
		(width 0.153)
		(layer "F.Cu")
		(net 526)
	)
	(segment
		(start 235.386 106.15611)
		(end 235.386 105.975)
		(width 0.153)
		(layer "F.Cu")
		(net 526)
	)
	(segment
		(start 204.81642 117.1)
		(end 204.6 117.1)
		(width 0.1)
		(layer "F.Cu")
		(net 526)
	)
	(segment
		(start 204.5 117.2)
		(end 204.5 117.5)
		(width 0.1)
		(layer "F.Cu")
		(net 526)
	)
	(segment
		(start 205.1805 112.549766)
		(end 211.949766 105.7805)
		(width 0.153)
		(layer "F.Cu")
		(net 526)
	)
	(segment
		(start 235.5805 105.7805)
		(end 237.881618 105.7805)
		(width 0.153)
		(layer "F.Cu")
		(net 526)
	)
	(segment
		(start 232.386 105.225)
		(end 232.386 104.94389)
		(width 0.153)
		(layer "F.Cu")
		(net 526)
	)
	(segment
		(start 204.6 117.1)
		(end 204.5 117.2)
		(width 0.1)
		(layer "F.Cu")
		(net 526)
	)
	(segment
		(start 241.3455 105.7805)
		(end 241.665 106.1)
		(width 0.153)
		(layer "F.Cu")
		(net 526)
	)
	(arc
		(start 231.8305 105.7805)
		(mid 232.223298 105.617798)
		(end 232.386 105.225)
		(width 0.153)
		(layer "F.Cu")
		(net 526)
	)
	(arc
		(start 232.386 104.94389)
		(mid 232.442968 104.806358)
		(end 232.5805 104.74939)
		(width 0.153)
		(layer "F.Cu")
		(net 526)
	)
	(arc
		(start 234.0805 104.74939)
		(mid 234.218032 104.806358)
		(end 234.275 104.94389)
		(width 0.153)
		(layer "F.Cu")
		(net 526)
	)
	(arc
		(start 235.386 105.975)
		(mid 235.442968 105.837468)
		(end 235.5805 105.7805)
		(width 0.153)
		(layer "F.Cu")
		(net 526)
	)
	(arc
		(start 232.775 106.15611)
		(mid 232.937702 106.548908)
		(end 233.3305 106.71161)
		(width 0.153)
		(layer "F.Cu")
		(net 526)
	)
	(arc
		(start 233.886 104.94389)
		(mid 233.942968 104.806358)
		(end 234.0805 104.74939)
		(width 0.153)
		(layer "F.Cu")
		(net 526)
	)
	(arc
		(start 234.8305 106.71161)
		(mid 235.223298 106.548908)
		(end 235.386 106.15611)
		(width 0.153)
		(layer "F.Cu")
		(net 526)
	)
	(arc
		(start 234.275 106.15611)
		(mid 234.437702 106.548908)
		(end 234.8305 106.71161)
		(width 0.153)
		(layer "F.Cu")
		(net 526)
	)
	(arc
		(start 233.3305 106.71161)
		(mid 233.723298 106.548908)
		(end 233.886 106.15611)
		(width 0.153)
		(layer "F.Cu")
		(net 526)
	)
	(arc
		(start 232.5805 104.74939)
		(mid 232.718032 104.806358)
		(end 232.775 104.94389)
		(width 0.153)
		(layer "F.Cu")
		(net 526)
	)
	(segment
		(start 211.800234 105.4195)
		(end 231.8305 105.4195)
		(width 0.153)
		(layer "F.Cu")
		(net 527)
	)
	(segment
		(start 234.636 105.4195)
		(end 234.636 106.15611)
		(width 0.153)
		(layer "F.Cu")
		(net 527)
	)
	(segment
		(start 204.4695 114.6195)
		(end 204.4695 114.5695)
		(width 0.153)
		(layer "F.Cu")
		(net 527)
	)
	(segment
		(start 204.5 116.8)
		(end 204.5 116.5)
		(width 0.1)
		(layer "F.Cu")
		(net 527)
	)
	(segment
		(start 204.6 116.9)
		(end 204.5 116.8)
		(width 0.1)
		(layer "F.Cu")
		(net 527)
	)
	(segment
		(start 205.658766 111.560971)
		(end 205.658765 111.56097)
		(width 0.153)
		(layer "F.Cu")
		(net 527)
	)
	(segment
		(start 233.136 105.225)
		(end 233.136 106.15611)
		(width 0.153)
		(layer "F.Cu")
		(net 527)
	)
	(segment
		(start 237.881618 105.4195)
		(end 241.3455 105.4195)
		(width 0.153)
		(layer "F.Cu")
		(net 527)
	)
	(segment
		(start 204.9 115.334314)
		(end 204.9 116.733578)
		(width 0.1)
		(layer "F.Cu")
		(net 527)
	)
	(segment
		(start 204.8195 112.400234)
		(end 205.022367 112.197367)
		(width 0.153)
		(layer "F.Cu")
		(net 527)
	)
	(segment
		(start 233.136 104.94389)
		(end 233.136 105.225)
		(width 0.153)
		(layer "F.Cu")
		(net 527)
	)
	(segment
		(start 204.8195 112.5695)
		(end 204.8195 112.400234)
		(width 0.153)
		(layer "F.Cu")
		(net 527)
	)
	(segment
		(start 204.898 115.332314)
		(end 204.9 115.334314)
		(width 0.1)
		(layer "F.Cu")
		(net 527)
	)
	(segment
		(start 204.8195 115.0945)
		(end 204.8195 114.9695)
		(width 0.153)
		(layer "F.Cu")
		(net 527)
	)
	(segment
		(start 205.333167 111.55357)
		(end 205.340568 111.560971)
		(width 0.153)
		(layer "F.Cu")
		(net 527)
	)
	(segment
		(start 204.8195 115.0945)
		(end 204.898 115.173)
		(width 0.1)
		(layer "F.Cu")
		(net 527)
	)
	(segment
		(start 204.8195 112.6195)
		(end 204.8195 112.5695)
		(width 0.153)
		(layer "F.Cu")
		(net 527)
	)
	(segment
		(start 204.8195 113.4195)
		(end 204.8195 113.3695)
		(width 0.153)
		(layer "F.Cu")
		(net 527)
	)
	(segment
		(start 233.525 105.7805)
		(end 233.525 104.94389)
		(width 0.153)
		(layer "F.Cu")
		(net 527)
	)
	(segment
		(start 205.333167 111.553571)
		(end 205.333167 111.55357)
		(width 0.153)
		(layer "F.Cu")
		(net 527)
	)
	(segment
		(start 205.658765 111.56097)
		(end 211.800234 105.4195)
		(width 0.153)
		(layer "F.Cu")
		(net 527)
	)
	(segment
		(start 235.025 106.15611)
		(end 235.025 105.975)
		(width 0.153)
		(layer "F.Cu")
		(net 527)
	)
	(segment
		(start 204.8195 114.2195)
		(end 204.8195 114.1695)
		(width 0.153)
		(layer "F.Cu")
		(net 527)
	)
	(segment
		(start 204.733578 116.9)
		(end 204.6 116.9)
		(width 0.1)
		(layer "F.Cu")
		(net 527)
	)
	(segment
		(start 235.5805 105.4195)
		(end 237.881618 105.4195)
		(width 0.153)
		(layer "F.Cu")
		(net 527)
	)
	(segment
		(start 241.3455 105.4195)
		(end 241.665 105.1)
		(width 0.153)
		(layer "F.Cu")
		(net 527)
	)
	(segment
		(start 204.9 116.733578)
		(end 204.733578 116.9)
		(width 0.1)
		(layer "F.Cu")
		(net 527)
	)
	(segment
		(start 204.898 115.173)
		(end 204.898 115.332314)
		(width 0.1)
		(layer "F.Cu")
		(net 527)
	)
	(segment
		(start 232.025 105.225)
		(end 232.025 104.94389)
		(width 0.153)
		(layer "F.Cu")
		(net 527)
	)
	(segment
		(start 234.636 104.94389)
		(end 234.636 105.4195)
		(width 0.153)
		(layer "F.Cu")
		(net 527)
	)
	(segment
		(start 205.022367 111.879169)
		(end 205.014967 111.871769)
		(width 0.153)
		(layer "F.Cu")
		(net 527)
	)
	(segment
		(start 204.4695 113.0195)
		(end 204.4695 112.9695)
		(width 0.153)
		(layer "F.Cu")
		(net 527)
	)
	(segment
		(start 233.525 106.15611)
		(end 233.525 105.7805)
		(width 0.153)
		(layer "F.Cu")
		(net 527)
	)
	(segment
		(start 204.4695 113.8195)
		(end 204.4695 113.7695)
		(width 0.153)
		(layer "F.Cu")
		(net 527)
	)
	(arc
		(start 233.3305 106.35061)
		(mid 233.468032 106.293642)
		(end 233.525 106.15611)
		(width 0.153)
		(layer "F.Cu")
		(net 527)
	)
	(arc
		(start 204.4695 113.7695)
		(mid 204.520756 113.645756)
		(end 204.6445 113.5945)
		(width 0.153)
		(layer "F.Cu")
		(net 527)
	)
	(arc
		(start 204.4695 114.5695)
		(mid 204.520756 114.445756)
		(end 204.6445 114.3945)
		(width 0.153)
		(layer "F.Cu")
		(net 527)
	)
	(arc
		(start 205.014967 111.553571)
		(mid 205.174068 111.487669)
		(end 205.333167 111.553571)
		(width 0.153)
		(layer "F.Cu")
		(net 527)
	)
	(arc
		(start 234.636 106.15611)
		(mid 234.692968 106.293642)
		(end 234.8305 106.35061)
		(width 0.153)
		(layer "F.Cu")
		(net 527)
	)
	(arc
		(start 204.4695 112.9695)
		(mid 204.520756 112.845756)
		(end 204.6445 112.7945)
		(width 0.153)
		(layer "F.Cu")
		(net 527)
	)
	(arc
		(start 231.8305 105.4195)
		(mid 231.968032 105.362532)
		(end 232.025 105.225)
		(width 0.153)
		(layer "F.Cu")
		(net 527)
	)
	(arc
		(start 204.6445 113.9945)
		(mid 204.520756 113.943244)
		(end 204.4695 113.8195)
		(width 0.153)
		(layer "F.Cu")
		(net 527)
	)
	(arc
		(start 205.022367 112.197367)
		(mid 205.088268 112.038268)
		(end 205.022367 111.879169)
		(width 0.153)
		(layer "F.Cu")
		(net 527)
	)
	(arc
		(start 204.8195 113.3695)
		(mid 204.768244 113.245756)
		(end 204.6445 113.1945)
		(width 0.153)
		(layer "F.Cu")
		(net 527)
	)
	(arc
		(start 232.025 104.94389)
		(mid 232.187702 104.551092)
		(end 232.5805 104.38839)
		(width 0.153)
		(layer "F.Cu")
		(net 527)
	)
	(arc
		(start 204.8195 114.1695)
		(mid 204.768244 114.045756)
		(end 204.6445 113.9945)
		(width 0.153)
		(layer "F.Cu")
		(net 527)
	)
	(arc
		(start 204.6445 114.3945)
		(mid 204.768244 114.343244)
		(end 204.8195 114.2195)
		(width 0.153)
		(layer "F.Cu")
		(net 527)
	)
	(arc
		(start 234.0805 104.38839)
		(mid 234.473298 104.551092)
		(end 234.636 104.94389)
		(width 0.153)
		(layer "F.Cu")
		(net 527)
	)
	(arc
		(start 233.525 104.94389)
		(mid 233.687702 104.551092)
		(end 234.0805 104.38839)
		(width 0.153)
		(layer "F.Cu")
		(net 527)
	)
	(arc
		(start 204.6445 113.5945)
		(mid 204.768244 113.543244)
		(end 204.8195 113.4195)
		(width 0.153)
		(layer "F.Cu")
		(net 527)
	)
	(arc
		(start 204.6445 113.1945)
		(mid 204.520756 113.143244)
		(end 204.4695 113.0195)
		(width 0.153)
		(layer "F.Cu")
		(net 527)
	)
	(arc
		(start 204.8195 114.9695)
		(mid 204.768244 114.845756)
		(end 204.6445 114.7945)
		(width 0.153)
		(layer "F.Cu")
		(net 527)
	)
	(arc
		(start 204.6445 112.7945)
		(mid 204.768244 112.743244)
		(end 204.8195 112.6195)
		(width 0.153)
		(layer "F.Cu")
		(net 527)
	)
	(arc
		(start 233.136 106.15611)
		(mid 233.192968 106.293642)
		(end 233.3305 106.35061)
		(width 0.153)
		(layer "F.Cu")
		(net 527)
	)
	(arc
		(start 232.5805 104.38839)
		(mid 232.973298 104.551092)
		(end 233.136 104.94389)
		(width 0.153)
		(layer "F.Cu")
		(net 527)
	)
	(arc
		(start 204.6445 114.7945)
		(mid 204.520756 114.743244)
		(end 204.4695 114.6195)
		(width 0.153)
		(layer "F.Cu")
		(net 527)
	)
	(arc
		(start 205.340568 111.560971)
		(mid 205.499667 111.626872)
		(end 205.658766 111.560971)
		(width 0.153)
		(layer "F.Cu")
		(net 527)
	)
	(arc
		(start 234.8305 106.35061)
		(mid 234.968032 106.293642)
		(end 235.025 106.15611)
		(width 0.153)
		(layer "F.Cu")
		(net 527)
	)
	(arc
		(start 205.014967 111.871769)
		(mid 204.949066 111.71267)
		(end 205.014967 111.553571)
		(width 0.153)
		(layer "F.Cu")
		(net 527)
	)
	(arc
		(start 235.025 105.975)
		(mid 235.187702 105.582202)
		(end 235.5805 105.4195)
		(width 0.153)
		(layer "F.Cu")
		(net 527)
	)
	(segment
		(start 230.7305 107.4805)
		(end 232.012648 107.4805)
		(width 0.153)
		(layer "F.Cu")
		(net 528)
	)
	(segment
		(start 205.816422 118.1)
		(end 206.1 117.816422)
		(width 0.1)
		(layer "F.Cu")
		(net 528)
	)
	(segment
		(start 227.311 107.890294)
		(end 227.311 107.4805)
		(width 0.153)
		(layer "F.Cu")
		(net 528)
	)
	(segment
		(start 227.75 107.1195)
		(end 227.75 107.890294)
		(width 0.153)
		(layer "F.Cu")
		(net 528)
	)
	(segment
		(start 206.1805 115.0945)
		(end 206.1805 113.699766)
		(width 0.153)
		(layer "F.Cu")
		(net 528)
	)
	(segment
		(start 225.711 107.4805)
		(end 225.711 106.709706)
		(width 0.153)
		(layer "F.Cu")
		(net 528)
	)
	(segment
		(start 206.857316 113.308789)
		(end 206.855816 113.307289)
		(width 0.153)
		(layer "F.Cu")
		(net 528)
	)
	(segment
		(start 225.711 107.890294)
		(end 225.711 107.4805)
		(width 0.153)
		(layer "F.Cu")
		(net 528)
	)
	(segment
		(start 207.138661 113.024447)
		(end 207.14016 113.025946)
		(width 0.153)
		(layer "F.Cu")
		(net 528)
	)
	(segment
		(start 207.421503 112.45876)
		(end 207.776753 112.103513)
		(width 0.153)
		(layer "F.Cu")
		(net 528)
	)
	(segment
		(start 224.55 106.709706)
		(end 224.55 106.9)
		(width 0.153)
		(layer "F.Cu")
		(net 528)
	)
	(segment
		(start 226.15 107.1195)
		(end 226.15 107.890294)
		(width 0.153)
		(layer "F.Cu")
		(net 528)
	)
	(segment
		(start 206.1 115.175)
		(end 206.1805 115.0945)
		(width 0.1)
		(layer "F.Cu")
		(net 528)
	)
	(segment
		(start 212.399766 107.4805)
		(end 223.5305 107.4805)
		(width 0.153)
		(layer "F.Cu")
		(net 528)
	)
	(segment
		(start 205.6 118.1)
		(end 205.816422 118.1)
		(width 0.1)
		(layer "F.Cu")
		(net 528)
	)
	(segment
		(start 206.857317 113.591631)
		(end 206.857316 113.591632)
		(width 0.153)
		(layer "F.Cu")
		(net 528)
	)
	(segment
		(start 229.35 106.709706)
		(end 229.35 107.1195)
		(width 0.153)
		(layer "F.Cu")
		(net 528)
	)
	(segment
		(start 230.511 107.890294)
		(end 230.511 107.7)
		(width 0.153)
		(layer "F.Cu")
		(net 528)
	)
	(segment
		(start 243.3455 107.4805)
		(end 243.665 107.8)
		(width 0.153)
		(layer "F.Cu")
		(net 528)
	)
	(segment
		(start 207.776753 112.103513)
		(end 212.399766 107.4805)
		(width 0.153)
		(layer "F.Cu")
		(net 528)
	)
	(segment
		(start 205.5 118.2)
		(end 205.6 118.1)
		(width 0.1)
		(layer "F.Cu")
		(net 528)
	)
	(segment
		(start 206.1 117.816422)
		(end 206.1 115.175)
		(width 0.1)
		(layer "F.Cu")
		(net 528)
	)
	(segment
		(start 206.1805 113.699766)
		(end 206.290133 113.590133)
		(width 0.153)
		(layer "F.Cu")
		(net 528)
	)
	(segment
		(start 227.311 107.4805)
		(end 227.311 106.709706)
		(width 0.153)
		(layer "F.Cu")
		(net 528)
	)
	(segment
		(start 206.855816 113.024447)
		(end 206.855819 113.024447)
		(width 0.153)
		(layer "F.Cu")
		(net 528)
	)
	(segment
		(start 228.911 107.4805)
		(end 228.911 106.709706)
		(width 0.153)
		(layer "F.Cu")
		(net 528)
	)
	(segment
		(start 206.572975 113.590133)
		(end 206.574474 113.591632)
		(width 0.153)
		(layer "F.Cu")
		(net 528)
	)
	(segment
		(start 207.423003 113.025945)
		(end 207.423002 113.025946)
		(width 0.153)
		(layer "F.Cu")
		(net 528)
	)
	(segment
		(start 232.012648 107.4805)
		(end 243.3455 107.4805)
		(width 0.153)
		(layer "F.Cu")
		(net 528)
	)
	(segment
		(start 224.55 106.9)
		(end 224.55 107.890294)
		(width 0.153)
		(layer "F.Cu")
		(net 528)
	)
	(segment
		(start 228.911 107.890294)
		(end 228.911 107.4805)
		(width 0.153)
		(layer "F.Cu")
		(net 528)
	)
	(segment
		(start 227.75 106.709706)
		(end 227.75 107.1195)
		(width 0.153)
		(layer "F.Cu")
		(net 528)
	)
	(segment
		(start 226.15 106.709706)
		(end 226.15 107.1195)
		(width 0.153)
		(layer "F.Cu")
		(net 528)
	)
	(segment
		(start 205.5 118.5)
		(end 205.5 118.2)
		(width 0.1)
		(layer "F.Cu")
		(net 528)
	)
	(segment
		(start 207.423002 112.743103)
		(end 207.421502 112.741603)
		(width 0.153)
		(layer "F.Cu")
		(net 528)
	)
	(segment
		(start 224.111 106.9)
		(end 224.111 106.709706)
		(width 0.153)
		(layer "F.Cu")
		(net 528)
	)
	(segment
		(start 207.423002 112.743102)
		(end 207.423002 112.743103)
		(width 0.153)
		(layer "F.Cu")
		(net 528)
	)
	(segment
		(start 206.857316 113.308788)
		(end 206.857316 113.308789)
		(width 0.153)
		(layer "F.Cu")
		(net 528)
	)
	(segment
		(start 229.35 107.1195)
		(end 229.35 107.890294)
		(width 0.153)
		(layer "F.Cu")
		(net 528)
	)
	(segment
		(start 206.855817 113.024446)
		(end 206.855816 113.024447)
		(width 0.153)
		(layer "F.Cu")
		(net 528)
	)
	(arc
		(start 227.75 107.890294)
		(mid 227.920025 108.300769)
		(end 228.3305 108.470794)
		(width 0.153)
		(layer "F.Cu")
		(net 528)
	)
	(arc
		(start 206.290133 113.590133)
		(mid 206.431554 113.531555)
		(end 206.572975 113.590133)
		(width 0.153)
		(layer "F.Cu")
		(net 528)
	)
	(arc
		(start 226.7305 108.470794)
		(mid 227.140975 108.300769)
		(end 227.311 107.890294)
		(width 0.153)
		(layer "F.Cu")
		(net 528)
	)
	(arc
		(start 207.14016 113.025946)
		(mid 207.281582 113.084524)
		(end 207.423003 113.025945)
		(width 0.153)
		(layer "F.Cu")
		(net 528)
	)
	(arc
		(start 207.423002 113.025946)
		(mid 207.481581 112.884524)
		(end 207.423002 112.743102)
		(width 0.153)
		(layer "F.Cu")
		(net 528)
	)
	(arc
		(start 224.3305 106.490206)
		(mid 224.48571 106.554496)
		(end 224.55 106.709706)
		(width 0.153)
		(layer "F.Cu")
		(net 528)
	)
	(arc
		(start 225.1305 108.470794)
		(mid 225.540975 108.300769)
		(end 225.711 107.890294)
		(width 0.153)
		(layer "F.Cu")
		(net 528)
	)
	(arc
		(start 229.1305 106.490206)
		(mid 229.28571 106.554496)
		(end 229.35 106.709706)
		(width 0.153)
		(layer "F.Cu")
		(net 528)
	)
	(arc
		(start 206.855819 113.024447)
		(mid 206.99724 112.965869)
		(end 207.138661 113.024447)
		(width 0.153)
		(layer "F.Cu")
		(net 528)
	)
	(arc
		(start 225.9305 106.490206)
		(mid 226.08571 106.554496)
		(end 226.15 106.709706)
		(width 0.153)
		(layer "F.Cu")
		(net 528)
	)
	(arc
		(start 229.9305 108.470794)
		(mid 230.340975 108.300769)
		(end 230.511 107.890294)
		(width 0.153)
		(layer "F.Cu")
		(net 528)
	)
	(arc
		(start 225.711 106.709706)
		(mid 225.77529 106.554496)
		(end 225.9305 106.490206)
		(width 0.153)
		(layer "F.Cu")
		(net 528)
	)
	(arc
		(start 206.574474 113.591632)
		(mid 206.715896 113.65021)
		(end 206.857317 113.591631)
		(width 0.153)
		(layer "F.Cu")
		(net 528)
	)
	(arc
		(start 223.5305 107.4805)
		(mid 223.940975 107.310475)
		(end 224.111 106.9)
		(width 0.153)
		(layer "F.Cu")
		(net 528)
	)
	(arc
		(start 224.55 107.890294)
		(mid 224.720025 108.300769)
		(end 225.1305 108.470794)
		(width 0.153)
		(layer "F.Cu")
		(net 528)
	)
	(arc
		(start 206.857316 113.591632)
		(mid 206.915895 113.45021)
		(end 206.857316 113.308788)
		(width 0.153)
		(layer "F.Cu")
		(net 528)
	)
	(arc
		(start 224.111 106.709706)
		(mid 224.17529 106.554496)
		(end 224.3305 106.490206)
		(width 0.153)
		(layer "F.Cu")
		(net 528)
	)
	(arc
		(start 228.911 106.709706)
		(mid 228.97529 106.554496)
		(end 229.1305 106.490206)
		(width 0.153)
		(layer "F.Cu")
		(net 528)
	)
	(arc
		(start 207.421502 112.741603)
		(mid 207.362924 112.600181)
		(end 207.421503 112.45876)
		(width 0.153)
		(layer "F.Cu")
		(net 528)
	)
	(arc
		(start 206.855816 113.307289)
		(mid 206.797238 113.165867)
		(end 206.855817 113.024446)
		(width 0.153)
		(layer "F.Cu")
		(net 528)
	)
	(arc
		(start 228.3305 108.470794)
		(mid 228.740975 108.300769)
		(end 228.911 107.890294)
		(width 0.153)
		(layer "F.Cu")
		(net 528)
	)
	(arc
		(start 227.5305 106.490206)
		(mid 227.68571 106.554496)
		(end 227.75 106.709706)
		(width 0.153)
		(layer "F.Cu")
		(net 528)
	)
	(arc
		(start 227.311 106.709706)
		(mid 227.37529 106.554496)
		(end 227.5305 106.490206)
		(width 0.153)
		(layer "F.Cu")
		(net 528)
	)
	(arc
		(start 226.15 107.890294)
		(mid 226.320025 108.300769)
		(end 226.7305 108.470794)
		(width 0.153)
		(layer "F.Cu")
		(net 528)
	)
	(arc
		(start 229.35 107.890294)
		(mid 229.520025 108.300769)
		(end 229.9305 108.470794)
		(width 0.153)
		(layer "F.Cu")
		(net 528)
	)
	(arc
		(start 230.511 107.7)
		(mid 230.57529 107.54479)
		(end 230.7305 107.4805)
		(width 0.153)
		(layer "F.Cu")
		(net 528)
	)
	(segment
		(start 226.511 107.1195)
		(end 226.511 107.890294)
		(width 0.153)
		(layer "F.Cu")
		(net 529)
	)
	(segment
		(start 212.250234 107.1195)
		(end 223.5305 107.1195)
		(width 0.153)
		(layer "F.Cu")
		(net 529)
	)
	(segment
		(start 223.75 106.9)
		(end 223.75 106.709706)
		(width 0.153)
		(layer "F.Cu")
		(net 529)
	)
	(segment
		(start 226.511 106.709706)
		(end 226.511 107.1195)
		(width 0.153)
		(layer "F.Cu")
		(net 529)
	)
	(segment
		(start 226.95 107.890294)
		(end 226.95 107.4805)
		(width 0.153)
		(layer "F.Cu")
		(net 529)
	)
	(segment
		(start 205.5 117.5)
		(end 205.5 117.8)
		(width 0.1)
		(layer "F.Cu")
		(net 529)
	)
	(segment
		(start 229.711 106.709706)
		(end 229.711 107.1195)
		(width 0.153)
		(layer "F.Cu")
		(net 529)
	)
	(segment
		(start 205.8195 113.550234)
		(end 212.250234 107.1195)
		(width 0.153)
		(layer "F.Cu")
		(net 529)
	)
	(segment
		(start 226.95 107.4805)
		(end 226.95 106.709706)
		(width 0.153)
		(layer "F.Cu")
		(net 529)
	)
	(segment
		(start 224.911 106.709706)
		(end 224.911 106.9)
		(width 0.153)
		(layer "F.Cu")
		(net 529)
	)
	(segment
		(start 205.6 117.9)
		(end 205.733578 117.9)
		(width 0.1)
		(layer "F.Cu")
		(net 529)
	)
	(segment
		(start 229.711 107.1195)
		(end 229.711 107.890294)
		(width 0.153)
		(layer "F.Cu")
		(net 529)
	)
	(segment
		(start 225.35 107.890294)
		(end 225.35 107.4805)
		(width 0.153)
		(layer "F.Cu")
		(net 529)
	)
	(segment
		(start 225.35 107.4805)
		(end 225.35 106.709706)
		(width 0.153)
		(layer "F.Cu")
		(net 529)
	)
	(segment
		(start 228.111 106.709706)
		(end 228.111 107.1195)
		(width 0.153)
		(layer "F.Cu")
		(net 529)
	)
	(segment
		(start 205.5 117.8)
		(end 205.6 117.9)
		(width 0.1)
		(layer "F.Cu")
		(net 529)
	)
	(segment
		(start 230.7305 107.1195)
		(end 232.012648 107.1195)
		(width 0.153)
		(layer "F.Cu")
		(net 529)
	)
	(segment
		(start 205.9 115.175)
		(end 205.8195 115.0945)
		(width 0.1)
		(layer "F.Cu")
		(net 529)
	)
	(segment
		(start 232.012648 107.1195)
		(end 243.3455 107.1195)
		(width 0.153)
		(layer "F.Cu")
		(net 529)
	)
	(segment
		(start 224.911 106.9)
		(end 224.911 107.890294)
		(width 0.153)
		(layer "F.Cu")
		(net 529)
	)
	(segment
		(start 228.55 107.890294)
		(end 228.55 107.4805)
		(width 0.153)
		(layer "F.Cu")
		(net 529)
	)
	(segment
		(start 205.8195 115.0945)
		(end 205.8195 113.550234)
		(width 0.153)
		(layer "F.Cu")
		(net 529)
	)
	(segment
		(start 205.733578 117.9)
		(end 205.9 117.733578)
		(width 0.1)
		(layer "F.Cu")
		(net 529)
	)
	(segment
		(start 228.55 107.4805)
		(end 228.55 106.709706)
		(width 0.153)
		(layer "F.Cu")
		(net 529)
	)
	(segment
		(start 205.9 117.733578)
		(end 205.9 115.175)
		(width 0.1)
		(layer "F.Cu")
		(net 529)
	)
	(segment
		(start 230.15 107.890294)
		(end 230.15 107.7)
		(width 0.153)
		(layer "F.Cu")
		(net 529)
	)
	(segment
		(start 243.3455 107.1195)
		(end 243.665 106.8)
		(width 0.153)
		(layer "F.Cu")
		(net 529)
	)
	(segment
		(start 228.111 107.1195)
		(end 228.111 107.890294)
		(width 0.153)
		(layer "F.Cu")
		(net 529)
	)
	(arc
		(start 225.9305 106.129206)
		(mid 226.340975 106.299231)
		(end 226.511 106.709706)
		(width 0.153)
		(layer "F.Cu")
		(net 529)
	)
	(arc
		(start 229.711 107.890294)
		(mid 229.77529 108.045504)
		(end 229.9305 108.109794)
		(width 0.153)
		(layer "F.Cu")
		(net 529)
	)
	(arc
		(start 224.3305 106.129206)
		(mid 224.740975 106.299231)
		(end 224.911 106.709706)
		(width 0.153)
		(layer "F.Cu")
		(net 529)
	)
	(arc
		(start 226.511 107.890294)
		(mid 226.57529 108.045504)
		(end 226.7305 108.109794)
		(width 0.153)
		(layer "F.Cu")
		(net 529)
	)
	(arc
		(start 225.1305 108.109794)
		(mid 225.28571 108.045504)
		(end 225.35 107.890294)
		(width 0.153)
		(layer "F.Cu")
		(net 529)
	)
	(arc
		(start 226.7305 108.109794)
		(mid 226.88571 108.045504)
		(end 226.95 107.890294)
		(width 0.153)
		(layer "F.Cu")
		(net 529)
	)
	(arc
		(start 228.3305 108.109794)
		(mid 228.48571 108.045504)
		(end 228.55 107.890294)
		(width 0.153)
		(layer "F.Cu")
		(net 529)
	)
	(arc
		(start 228.111 107.890294)
		(mid 228.17529 108.045504)
		(end 228.3305 108.109794)
		(width 0.153)
		(layer "F.Cu")
		(net 529)
	)
	(arc
		(start 223.5305 107.1195)
		(mid 223.68571 107.05521)
		(end 223.75 106.9)
		(width 0.153)
		(layer "F.Cu")
		(net 529)
	)
	(arc
		(start 229.9305 108.109794)
		(mid 230.08571 108.045504)
		(end 230.15 107.890294)
		(width 0.153)
		(layer "F.Cu")
		(net 529)
	)
	(arc
		(start 225.35 106.709706)
		(mid 225.520025 106.299231)
		(end 225.9305 106.129206)
		(width 0.153)
		(layer "F.Cu")
		(net 529)
	)
	(arc
		(start 224.911 107.890294)
		(mid 224.97529 108.045504)
		(end 225.1305 108.109794)
		(width 0.153)
		(layer "F.Cu")
		(net 529)
	)
	(arc
		(start 226.95 106.709706)
		(mid 227.120025 106.299231)
		(end 227.5305 106.129206)
		(width 0.153)
		(layer "F.Cu")
		(net 529)
	)
	(arc
		(start 229.1305 106.129206)
		(mid 229.540975 106.299231)
		(end 229.711 106.709706)
		(width 0.153)
		(layer "F.Cu")
		(net 529)
	)
	(arc
		(start 228.55 106.709706)
		(mid 228.720025 106.299231)
		(end 229.1305 106.129206)
		(width 0.153)
		(layer "F.Cu")
		(net 529)
	)
	(arc
		(start 227.5305 106.129206)
		(mid 227.940975 106.299231)
		(end 228.111 106.709706)
		(width 0.153)
		(layer "F.Cu")
		(net 529)
	)
	(arc
		(start 223.75 106.709706)
		(mid 223.920025 106.299231)
		(end 224.3305 106.129206)
		(width 0.153)
		(layer "F.Cu")
		(net 529)
	)
	(arc
		(start 230.15 107.7)
		(mid 230.320025 107.289525)
		(end 230.7305 107.1195)
		(width 0.153)
		(layer "F.Cu")
		(net 529)
	)
	(segment
		(start 214.964 108.400976)
		(end 214.964 108.625)
		(width 0.153)
		(layer "F.Cu")
		(net 530)
	)
	(segment
		(start 217.575 109.699024)
		(end 217.575 109.1805)
		(width 0.153)
		(layer "F.Cu")
		(net 530)
	)
	(segment
		(start 241.3455 109.1805)
		(end 241.665 109.5)
		(width 0.153)
		(layer "F.Cu")
		(net 530)
	)
	(segment
		(start 217.964 108.400976)
		(end 217.964 108.8195)
		(width 0.153)
		(layer "F.Cu")
		(net 530)
	)
	(segment
		(start 216.464 108.400976)
		(end 216.464 108.8195)
		(width 0.153)
		(layer "F.Cu")
		(net 530)
	)
	(segment
		(start 209.277426 113.329633)
		(end 209.20116 113.253367)
		(width 0.153)
		(layer "F.Cu")
		(net 530)
	)
	(segment
		(start 208.776897 113.677633)
		(end 208.853162 113.753898)
		(width 0.153)
		(layer "F.Cu")
		(net 530)
	)
	(segment
		(start 206.5 116.5)
		(end 206.5 116.2)
		(width 0.1)
		(layer "F.Cu")
		(net 530)
	)
	(segment
		(start 219.464 108.400976)
		(end 219.464 108.8195)
		(width 0.153)
		(layer "F.Cu")
		(net 530)
	)
	(segment
		(start 207.1805 115.0945)
		(end 207.1805 114.849766)
		(width 0.153)
		(layer "F.Cu")
		(net 530)
	)
	(segment
		(start 206.6 116.1)
		(end 206.816422 116.1)
		(width 0.1)
		(layer "F.Cu")
		(net 530)
	)
	(segment
		(start 216.464 108.8195)
		(end 216.464 109.699024)
		(width 0.153)
		(layer "F.Cu")
		(net 530)
	)
	(segment
		(start 221.849999 109.1805)
		(end 241.3455 109.1805)
		(width 0.153)
		(layer "F.Cu")
		(net 530)
	)
	(segment
		(start 219.075 109.1805)
		(end 219.075 108.400976)
		(width 0.153)
		(layer "F.Cu")
		(net 530)
	)
	(segment
		(start 207.1 115.175)
		(end 207.1805 115.0945)
		(width 0.1)
		(layer "F.Cu")
		(net 530)
	)
	(segment
		(start 220.575 109.699024)
		(end 220.575 109.375)
		(width 0.153)
		(layer "F.Cu")
		(net 530)
	)
	(segment
		(start 206.5 116.2)
		(end 206.6 116.1)
		(width 0.1)
		(layer "F.Cu")
		(net 530)
	)
	(segment
		(start 207.1805 114.849766)
		(end 208.352633 113.677633)
		(width 0.153)
		(layer "F.Cu")
		(net 530)
	)
	(segment
		(start 220.7695 109.1805)
		(end 221.849999 109.1805)
		(width 0.153)
		(layer "F.Cu")
		(net 530)
	)
	(segment
		(start 216.075 109.699024)
		(end 216.075 109.1805)
		(width 0.153)
		(layer "F.Cu")
		(net 530)
	)
	(segment
		(start 207.1 115.816422)
		(end 207.1 115.175)
		(width 0.1)
		(layer "F.Cu")
		(net 530)
	)
	(segment
		(start 214.964 108.625)
		(end 214.964 109.699024)
		(width 0.153)
		(layer "F.Cu")
		(net 530)
	)
	(segment
		(start 209.201161 112.829104)
		(end 212.849766 109.1805)
		(width 0.153)
		(layer "F.Cu")
		(net 530)
	)
	(segment
		(start 209.20116 112.829103)
		(end 209.201161 112.829104)
		(width 0.153)
		(layer "F.Cu")
		(net 530)
	)
	(segment
		(start 214.575 108.625)
		(end 214.575 108.400976)
		(width 0.153)
		(layer "F.Cu")
		(net 530)
	)
	(segment
		(start 217.575 109.1805)
		(end 217.575 108.400976)
		(width 0.153)
		(layer "F.Cu")
		(net 530)
	)
	(segment
		(start 217.964 108.8195)
		(end 217.964 109.699024)
		(width 0.153)
		(layer "F.Cu")
		(net 530)
	)
	(segment
		(start 216.075 109.1805)
		(end 216.075 108.400976)
		(width 0.153)
		(layer "F.Cu")
		(net 530)
	)
	(segment
		(start 219.464 108.8195)
		(end 219.464 109.699024)
		(width 0.153)
		(layer "F.Cu")
		(net 530)
	)
	(segment
		(start 219.075 109.699024)
		(end 219.075 109.1805)
		(width 0.153)
		(layer "F.Cu")
		(net 530)
	)
	(segment
		(start 212.849766 109.1805)
		(end 214.0195 109.1805)
		(width 0.153)
		(layer "F.Cu")
		(net 530)
	)
	(segment
		(start 209.277426 113.329632)
		(end 209.277426 113.329633)
		(width 0.153)
		(layer "F.Cu")
		(net 530)
	)
	(segment
		(start 206.816422 116.1)
		(end 207.1 115.816422)
		(width 0.1)
		(layer "F.Cu")
		(net 530)
	)
	(arc
		(start 214.575 108.400976)
		(mid 214.631968 108.263444)
		(end 214.7695 108.206476)
		(width 0.153)
		(layer "F.Cu")
		(net 530)
	)
	(arc
		(start 217.7695 108.206476)
		(mid 217.907032 108.263444)
		(end 217.964 108.400976)
		(width 0.153)
		(layer "F.Cu")
		(net 530)
	)
	(arc
		(start 216.075 108.400976)
		(mid 216.131968 108.263444)
		(end 216.2695 108.206476)
		(width 0.153)
		(layer "F.Cu")
		(net 530)
	)
	(arc
		(start 208.352633 113.677633)
		(mid 208.564765 113.589765)
		(end 208.776897 113.677633)
		(width 0.153)
		(layer "F.Cu")
		(net 530)
	)
	(arc
		(start 208.853162 113.753898)
		(mid 209.065294 113.841766)
		(end 209.277426 113.753898)
		(width 0.153)
		(layer "F.Cu")
		(net 530)
	)
	(arc
		(start 215.5195 110.254524)
		(mid 215.912298 110.091822)
		(end 216.075 109.699024)
		(width 0.153)
		(layer "F.Cu")
		(net 530)
	)
	(arc
		(start 220.575 109.375)
		(mid 220.631968 109.237468)
		(end 220.7695 109.1805)
		(width 0.153)
		(layer "F.Cu")
		(net 530)
	)
	(arc
		(start 219.464 109.699024)
		(mid 219.626702 110.091822)
		(end 220.0195 110.254524)
		(width 0.153)
		(layer "F.Cu")
		(net 530)
	)
	(arc
		(start 217.0195 110.254524)
		(mid 217.412298 110.091822)
		(end 217.575 109.699024)
		(width 0.153)
		(layer "F.Cu")
		(net 530)
	)
	(arc
		(start 214.964 109.699024)
		(mid 215.126702 110.091822)
		(end 215.5195 110.254524)
		(width 0.153)
		(layer "F.Cu")
		(net 530)
	)
	(arc
		(start 209.277426 113.753898)
		(mid 209.365294 113.541765)
		(end 209.277426 113.329632)
		(width 0.153)
		(layer "F.Cu")
		(net 530)
	)
	(arc
		(start 220.0195 110.254524)
		(mid 220.412298 110.091822)
		(end 220.575 109.699024)
		(width 0.153)
		(layer "F.Cu")
		(net 530)
	)
	(arc
		(start 219.075 108.400976)
		(mid 219.131968 108.263444)
		(end 219.2695 108.206476)
		(width 0.153)
		(layer "F.Cu")
		(net 530)
	)
	(arc
		(start 209.20116 113.253367)
		(mid 209.113292 113.041235)
		(end 209.20116 112.829103)
		(width 0.153)
		(layer "F.Cu")
		(net 530)
	)
	(arc
		(start 219.2695 108.206476)
		(mid 219.407032 108.263444)
		(end 219.464 108.400976)
		(width 0.153)
		(layer "F.Cu")
		(net 530)
	)
	(arc
		(start 216.2695 108.206476)
		(mid 216.407032 108.263444)
		(end 216.464 108.400976)
		(width 0.153)
		(layer "F.Cu")
		(net 530)
	)
	(arc
		(start 214.0195 109.1805)
		(mid 214.412298 109.017798)
		(end 214.575 108.625)
		(width 0.153)
		(layer "F.Cu")
		(net 530)
	)
	(arc
		(start 214.7695 108.206476)
		(mid 214.907032 108.263444)
		(end 214.964 108.400976)
		(width 0.153)
		(layer "F.Cu")
		(net 530)
	)
	(arc
		(start 216.464 109.699024)
		(mid 216.626702 110.091822)
		(end 217.0195 110.254524)
		(width 0.153)
		(layer "F.Cu")
		(net 530)
	)
	(arc
		(start 217.964 109.699024)
		(mid 218.126702 110.091822)
		(end 218.5195 110.254524)
		(width 0.153)
		(layer "F.Cu")
		(net 530)
	)
	(arc
		(start 218.5195 110.254524)
		(mid 218.912298 110.091822)
		(end 219.075 109.699024)
		(width 0.153)
		(layer "F.Cu")
		(net 530)
	)
	(arc
		(start 217.575 108.400976)
		(mid 217.631968 108.263444)
		(end 217.7695 108.206476)
		(width 0.153)
		(layer "F.Cu")
		(net 530)
	)
	(segment
		(start 188.5 139.5)
		(end 188 140)
		(width 0.256)
		(layer "F.Cu")
		(net 531)
	)
	(segment
		(start 166.8 144)
		(end 166.4 143.6)
		(width 0.256)
		(layer "F.Cu")
		(net 531)
	)
	(via
		(at 166.4 143.6)
		(size 0.45)
		(drill 0.2)
		(layers "F.Cu" "B.Cu")
		(net 531)
	)
	(via
		(at 188 140)
		(size 0.45)
		(drill 0.2)
		(layers "F.Cu" "B.Cu")
		(net 531)
	)
	(segment
		(start 166.199999 144.528411)
		(end 166.199999 144.699999)
		(width 0.201)
		(layer "B.Cu")
		(net 531)
	)
	(segment
		(start 166.4 143.6)
		(end 166.4 144.23)
		(width 0.256)
		(layer "B.Cu")
		(net 531)
	)
	(segment
		(start 166.4 144.32841)
		(end 166.199999 144.528411)
		(width 0.201)
		(layer "B.Cu")
		(net 531)
	)
	(segment
		(start 166.4 144.23)
		(end 166.4 144.32841)
		(width 0.201)
		(layer "B.Cu")
		(net 531)
	)
	(segment
		(start 178.125 136.541805)
		(end 178.125 135.879097)
		(width 0.157)
		(layer "In7.Cu")
		(net 531)
	)
	(segment
		(start 176.595902 136.641805)
		(end 176.654098 136.641805)
		(width 0.157)
		(layer "In7.Cu")
		(net 531)
	)
	(segment
		(start 166.4 143.6)
		(end 166 143.2)
		(width 0.157)
		(layer "In7.Cu")
		(net 531)
	)
	(segment
		(start 175.370902 136.591805)
		(end 175.479098 136.591805)
		(width 0.157)
		(layer "In7.Cu")
		(net 531)
	)
	(segment
		(start 173.925 135.879097)
		(end 173.925 136.345903)
		(width 0.157)
		(layer "In7.Cu")
		(net 531)
	)
	(segment
		(start 165.5 139.7)
		(end 169.1 136.1)
		(width 0.157)
		(layer "In7.Cu")
		(net 531)
	)
	(segment
		(start 173.545902 135.658195)
		(end 173.704098 135.658195)
		(width 0.157)
		(layer "In7.Cu")
		(net 531)
	)
	(segment
		(start 179.625 136.1)
		(end 180.144343 136.1)
		(width 0.157)
		(layer "In7.Cu")
		(net 531)
	)
	(segment
		(start 166 143.2)
		(end 166 142.975)
		(width 0.157)
		(layer "In7.Cu")
		(net 531)
	)
	(segment
		(start 177.145902 135.658195)
		(end 177.304098 135.658195)
		(width 0.157)
		(layer "In7.Cu")
		(net 531)
	)
	(segment
		(start 165.5 142.025)
		(end 165.5 139.7)
		(width 0.157)
		(layer "In7.Cu")
		(net 531)
	)
	(segment
		(start 176.325 135.879097)
		(end 176.325 136.370903)
		(width 0.157)
		(layer "In7.Cu")
		(net 531)
	)
	(segment
		(start 166 142.975)
		(end 166 142.625)
		(width 0.15)
		(layer "In7.Cu")
		(net 531)
	)
	(segment
		(start 173.325 136.370903)
		(end 173.325 135.879097)
		(width 0.157)
		(layer "In7.Cu")
		(net 531)
	)
	(segment
		(start 169.1 136.1)
		(end 170.075 136.1)
		(width 0.157)
		(layer "In7.Cu")
		(net 531)
	)
	(segment
		(start 170.920902 136.1)
		(end 170.925 136.1)
		(width 0.157)
		(layer "In7.Cu")
		(net 531)
	)
	(segment
		(start 178.345902 135.658195)
		(end 178.504098 135.658195)
		(width 0.157)
		(layer "In7.Cu")
		(net 531)
	)
	(segment
		(start 187.5 139.5)
		(end 188 140)
		(width 0.157)
		(layer "In7.Cu")
		(net 531)
	)
	(segment
		(start 166 142.525)
		(end 165.5 142.025)
		(width 0.157)
		(layer "In7.Cu")
		(net 531)
	)
	(segment
		(start 174.170902 136.591805)
		(end 174.279098 136.591805)
		(width 0.157)
		(layer "In7.Cu")
		(net 531)
	)
	(segment
		(start 177.525 135.879097)
		(end 177.525 136.541805)
		(width 0.157)
		(layer "In7.Cu")
		(net 531)
	)
	(segment
		(start 174.745902 135.658195)
		(end 174.904098 135.658195)
		(width 0.157)
		(layer "In7.Cu")
		(net 531)
	)
	(segment
		(start 171.145902 135.658195)
		(end 171.304098 135.658195)
		(width 0.157)
		(layer "In7.Cu")
		(net 531)
	)
	(segment
		(start 166 142.625)
		(end 166 142.525)
		(width 0.157)
		(layer "In7.Cu")
		(net 531)
	)
	(segment
		(start 175.945902 135.658195)
		(end 176.104098 135.658195)
		(width 0.157)
		(layer "In7.Cu")
		(net 531)
	)
	(segment
		(start 186.3 139.025)
		(end 186.775 139.5)
		(width 0.157)
		(layer "In7.Cu")
		(net 531)
	)
	(segment
		(start 178.725 135.879097)
		(end 178.725 136.541805)
		(width 0.157)
		(layer "In7.Cu")
		(net 531)
	)
	(segment
		(start 179.325 136.541805)
		(end 179.325 136.4)
		(width 0.157)
		(layer "In7.Cu")
		(net 531)
	)
	(segment
		(start 175.725 136.345903)
		(end 175.725 135.879097)
		(width 0.157)
		(layer "In7.Cu")
		(net 531)
	)
	(segment
		(start 186.775 139.5)
		(end 187.5 139.5)
		(width 0.157)
		(layer "In7.Cu")
		(net 531)
	)
	(segment
		(start 172.125 136.345903)
		(end 172.125 135.879097)
		(width 0.157)
		(layer "In7.Cu")
		(net 531)
	)
	(segment
		(start 176.925 136.370903)
		(end 176.925 135.879097)
		(width 0.157)
		(layer "In7.Cu")
		(net 531)
	)
	(segment
		(start 183.069343 139.025)
		(end 186.3 139.025)
		(width 0.157)
		(layer "In7.Cu")
		(net 531)
	)
	(segment
		(start 171.525 135.879097)
		(end 171.525 136.345903)
		(width 0.157)
		(layer "In7.Cu")
		(net 531)
	)
	(segment
		(start 170.925 136.1)
		(end 170.925 135.879097)
		(width 0.157)
		(layer "In7.Cu")
		(net 531)
	)
	(segment
		(start 170.320902 136.345902)
		(end 170.320902 136.345903)
		(width 0.157)
		(layer "In7.Cu")
		(net 531)
	)
	(segment
		(start 172.725 135.879097)
		(end 172.725 136.370903)
		(width 0.157)
		(layer "In7.Cu")
		(net 531)
	)
	(segment
		(start 170.920902 136.345903)
		(end 170.920902 136.345902)
		(width 0.157)
		(layer "In7.Cu")
		(net 531)
	)
	(segment
		(start 171.770902 136.591805)
		(end 171.879098 136.591805)
		(width 0.157)
		(layer "In7.Cu")
		(net 531)
	)
	(segment
		(start 172.995902 136.641805)
		(end 173.054098 136.641805)
		(width 0.157)
		(layer "In7.Cu")
		(net 531)
	)
	(segment
		(start 180.144343 136.1)
		(end 183.069343 139.025)
		(width 0.157)
		(layer "In7.Cu")
		(net 531)
	)
	(segment
		(start 172.345902 135.658195)
		(end 172.504098 135.658195)
		(width 0.157)
		(layer "In7.Cu")
		(net 531)
	)
	(segment
		(start 170.920902 136.345902)
		(end 170.920902 136.1)
		(width 0.157)
		(layer "In7.Cu")
		(net 531)
	)
	(segment
		(start 175.125 135.879097)
		(end 175.125 136.345903)
		(width 0.157)
		(layer "In7.Cu")
		(net 531)
	)
	(segment
		(start 170.566804 136.591805)
		(end 170.675 136.591805)
		(width 0.157)
		(layer "In7.Cu")
		(net 531)
	)
	(segment
		(start 174.525 136.345903)
		(end 174.525 135.879097)
		(width 0.157)
		(layer "In7.Cu")
		(net 531)
	)
	(arc
		(start 174.279098 136.591805)
		(mid 174.452977 136.519782)
		(end 174.525 136.345903)
		(width 0.157)
		(layer "In7.Cu")
		(net 531)
	)
	(arc
		(start 173.325 135.879097)
		(mid 173.389701 135.722896)
		(end 173.545902 135.658195)
		(width 0.157)
		(layer "In7.Cu")
		(net 531)
	)
	(arc
		(start 171.879098 136.591805)
		(mid 172.052977 136.519782)
		(end 172.125 136.345903)
		(width 0.157)
		(layer "In7.Cu")
		(net 531)
	)
	(arc
		(start 170.675 136.591805)
		(mid 170.848879 136.519782)
		(end 170.920902 136.345903)
		(width 0.157)
		(layer "In7.Cu")
		(net 531)
	)
	(arc
		(start 178.725 136.541805)
		(mid 178.812868 136.753937)
		(end 179.025 136.841805)
		(width 0.157)
		(layer "In7.Cu")
		(net 531)
	)
	(arc
		(start 174.904098 135.658195)
		(mid 175.060299 135.722896)
		(end 175.125 135.879097)
		(width 0.157)
		(layer "In7.Cu")
		(net 531)
	)
	(arc
		(start 173.704098 135.658195)
		(mid 173.860299 135.722896)
		(end 173.925 135.879097)
		(width 0.157)
		(layer "In7.Cu")
		(net 531)
	)
	(arc
		(start 170.320902 136.345903)
		(mid 170.392925 136.519782)
		(end 170.566804 136.591805)
		(width 0.157)
		(layer "In7.Cu")
		(net 531)
	)
	(arc
		(start 175.725 135.879097)
		(mid 175.789701 135.722896)
		(end 175.945902 135.658195)
		(width 0.157)
		(layer "In7.Cu")
		(net 531)
	)
	(arc
		(start 172.125 135.879097)
		(mid 172.189701 135.722896)
		(end 172.345902 135.658195)
		(width 0.157)
		(layer "In7.Cu")
		(net 531)
	)
	(arc
		(start 175.125 136.345903)
		(mid 175.197023 136.519782)
		(end 175.370902 136.591805)
		(width 0.157)
		(layer "In7.Cu")
		(net 531)
	)
	(arc
		(start 172.504098 135.658195)
		(mid 172.660299 135.722896)
		(end 172.725 135.879097)
		(width 0.157)
		(layer "In7.Cu")
		(net 531)
	)
	(arc
		(start 177.825 136.841805)
		(mid 178.037132 136.753937)
		(end 178.125 136.541805)
		(width 0.157)
		(layer "In7.Cu")
		(net 531)
	)
	(arc
		(start 177.304098 135.658195)
		(mid 177.460299 135.722896)
		(end 177.525 135.879097)
		(width 0.157)
		(layer "In7.Cu")
		(net 531)
	)
	(arc
		(start 179.025 136.841805)
		(mid 179.237132 136.753937)
		(end 179.325 136.541805)
		(width 0.157)
		(layer "In7.Cu")
		(net 531)
	)
	(arc
		(start 173.054098 136.641805)
		(mid 173.245655 136.56246)
		(end 173.325 136.370903)
		(width 0.157)
		(layer "In7.Cu")
		(net 531)
	)
	(arc
		(start 174.525 135.879097)
		(mid 174.589701 135.722896)
		(end 174.745902 135.658195)
		(width 0.157)
		(layer "In7.Cu")
		(net 531)
	)
	(arc
		(start 171.304098 135.658195)
		(mid 171.460299 135.722896)
		(end 171.525 135.879097)
		(width 0.157)
		(layer "In7.Cu")
		(net 531)
	)
	(arc
		(start 176.325 136.370903)
		(mid 176.404345 136.56246)
		(end 176.595902 136.641805)
		(width 0.157)
		(layer "In7.Cu")
		(net 531)
	)
	(arc
		(start 178.504098 135.658195)
		(mid 178.660299 135.722896)
		(end 178.725 135.879097)
		(width 0.157)
		(layer "In7.Cu")
		(net 531)
	)
	(arc
		(start 172.725 136.370903)
		(mid 172.804345 136.56246)
		(end 172.995902 136.641805)
		(width 0.157)
		(layer "In7.Cu")
		(net 531)
	)
	(arc
		(start 175.479098 136.591805)
		(mid 175.652977 136.519782)
		(end 175.725 136.345903)
		(width 0.157)
		(layer "In7.Cu")
		(net 531)
	)
	(arc
		(start 170.075 136.1)
		(mid 170.248879 136.172023)
		(end 170.320902 136.345902)
		(width 0.157)
		(layer "In7.Cu")
		(net 531)
	)
	(arc
		(start 176.925 135.879097)
		(mid 176.989701 135.722896)
		(end 177.145902 135.658195)
		(width 0.157)
		(layer "In7.Cu")
		(net 531)
	)
	(arc
		(start 177.525 136.541805)
		(mid 177.612868 136.753937)
		(end 177.825 136.841805)
		(width 0.157)
		(layer "In7.Cu")
		(net 531)
	)
	(arc
		(start 176.654098 136.641805)
		(mid 176.845655 136.56246)
		(end 176.925 136.370903)
		(width 0.157)
		(layer "In7.Cu")
		(net 531)
	)
	(arc
		(start 176.104098 135.658195)
		(mid 176.260299 135.722896)
		(end 176.325 135.879097)
		(width 0.157)
		(layer "In7.Cu")
		(net 531)
	)
	(arc
		(start 179.325 136.4)
		(mid 179.412868 136.187868)
		(end 179.625 136.1)
		(width 0.157)
		(layer "In7.Cu")
		(net 531)
	)
	(arc
		(start 173.925 136.345903)
		(mid 173.997023 136.519782)
		(end 174.170902 136.591805)
		(width 0.157)
		(layer "In7.Cu")
		(net 531)
	)
	(arc
		(start 170.925 135.879097)
		(mid 170.989701 135.722896)
		(end 171.145902 135.658195)
		(width 0.157)
		(layer "In7.Cu")
		(net 531)
	)
	(arc
		(start 171.525 136.345903)
		(mid 171.597023 136.519782)
		(end 171.770902 136.591805)
		(width 0.157)
		(layer "In7.Cu")
		(net 531)
	)
	(arc
		(start 178.125 135.879097)
		(mid 178.189701 135.722896)
		(end 178.345902 135.658195)
		(width 0.157)
		(layer "In7.Cu")
		(net 531)
	)
	(segment
		(start 165.6 147.6)
		(end 166 147.2)
		(width 0.256)
		(layer "F.Cu")
		(net 532)
	)
	(segment
		(start 186.988799 142.011201)
		(end 186.977398 142.011201)
		(width 0.256)
		(layer "F.Cu")
		(net 532)
	)
	(segment
		(start 187.5 141.5)
		(end 186.988799 142.011201)
		(width 0.256)
		(layer "F.Cu")
		(net 532)
	)
	(via
		(at 165.6 147.6)
		(size 0.45)
		(drill 0.2)
		(layers "F.Cu" "B.Cu")
		(net 532)
	)
	(via
		(at 186.977398 142.011201)
		(size 0.45)
		(drill 0.2)
		(layers "F.Cu" "B.Cu")
		(net 532)
	)
	(segment
		(start 165.6 147.175)
		(end 165.6 147.6)
		(width 0.256)
		(layer "B.Cu")
		(net 532)
	)
	(segment
		(start 165.799999 146.975001)
		(end 165.6 147.175)
		(width 0.256)
		(layer "B.Cu")
		(net 532)
	)
	(segment
		(start 165.799999 146.499999)
		(end 165.799999 146.975001)
		(width 0.256)
		(layer "B.Cu")
		(net 532)
	)
	(segment
		(start 165.6 146.775)
		(end 165.6 147.6)
		(width 0.157)
		(layer "In7.Cu")
		(net 532)
	)
	(segment
		(start 188.5 142.775)
		(end 188.5 145.225)
		(width 0.157)
		(layer "In7.Cu")
		(net 532)
	)
	(segment
		(start 182.275 146.134688)
		(end 182.275 144.865312)
		(width 0.157)
		(layer "In7.Cu")
		(net 532)
	)
	(segment
		(start 178 145.5)
		(end 177.6 145.1)
		(width 0.157)
		(layer "In7.Cu")
		(net 532)
	)
	(segment
		(start 180.625 144.865312)
		(end 180.625 146.134688)
		(width 0.157)
		(layer "In7.Cu")
		(net 532)
	)
	(segment
		(start 188.5 145.225)
		(end 188.225 145.5)
		(width 0.157)
		(layer "In7.Cu")
		(net 532)
	)
	(segment
		(start 181.175 146.134688)
		(end 181.175 144.865312)
		(width 0.157)
		(layer "In7.Cu")
		(net 532)
	)
	(segment
		(start 167.275 145.1)
		(end 165.6 146.775)
		(width 0.157)
		(layer "In7.Cu")
		(net 532)
	)
	(segment
		(start 180.075 146.134688)
		(end 180.075 144.865312)
		(width 0.157)
		(layer "In7.Cu")
		(net 532)
	)
	(segment
		(start 182.825 145.775)
		(end 182.825 146.134688)
		(width 0.157)
		(layer "In7.Cu")
		(net 532)
	)
	(segment
		(start 179.25 145.5)
		(end 178 145.5)
		(width 0.157)
		(layer "In7.Cu")
		(net 532)
	)
	(segment
		(start 188.225 142.5)
		(end 188.5 142.775)
		(width 0.157)
		(layer "In7.Cu")
		(net 532)
	)
	(segment
		(start 187.466197 142.5)
		(end 188.225 142.5)
		(width 0.157)
		(layer "In7.Cu")
		(net 532)
	)
	(segment
		(start 181.725 144.865312)
		(end 181.725 146.134688)
		(width 0.157)
		(layer "In7.Cu")
		(net 532)
	)
	(segment
		(start 188.225 145.5)
		(end 183.1 145.5)
		(width 0.157)
		(layer "In7.Cu")
		(net 532)
	)
	(segment
		(start 179.525 144.865312)
		(end 179.525 145.225)
		(width 0.157)
		(layer "In7.Cu")
		(net 532)
	)
	(segment
		(start 177.6 145.1)
		(end 167.275 145.1)
		(width 0.157)
		(layer "In7.Cu")
		(net 532)
	)
	(segment
		(start 186.977398 142.011201)
		(end 187.466197 142.5)
		(width 0.157)
		(layer "In7.Cu")
		(net 532)
	)
	(arc
		(start 182 144.590312)
		(mid 181.805546 144.670858)
		(end 181.725 144.865312)
		(width 0.157)
		(layer "In7.Cu")
		(net 532)
	)
	(arc
		(start 180.9 144.590312)
		(mid 180.705546 144.670858)
		(end 180.625 144.865312)
		(width 0.157)
		(layer "In7.Cu")
		(net 532)
	)
	(arc
		(start 182.55 146.409688)
		(mid 182.355546 146.329142)
		(end 182.275 146.134688)
		(width 0.157)
		(layer "In7.Cu")
		(net 532)
	)
	(arc
		(start 181.725 146.134688)
		(mid 181.644454 146.329142)
		(end 181.45 146.409688)
		(width 0.157)
		(layer "In7.Cu")
		(net 532)
	)
	(arc
		(start 181.175 144.865312)
		(mid 181.094454 144.670858)
		(end 180.9 144.590312)
		(width 0.157)
		(layer "In7.Cu")
		(net 532)
	)
	(arc
		(start 180.35 146.409688)
		(mid 180.155546 146.329142)
		(end 180.075 146.134688)
		(width 0.157)
		(layer "In7.Cu")
		(net 532)
	)
	(arc
		(start 182.275 144.865312)
		(mid 182.194454 144.670858)
		(end 182 144.590312)
		(width 0.157)
		(layer "In7.Cu")
		(net 532)
	)
	(arc
		(start 179.8 144.590312)
		(mid 179.605546 144.670858)
		(end 179.525 144.865312)
		(width 0.157)
		(layer "In7.Cu")
		(net 532)
	)
	(arc
		(start 181.45 146.409688)
		(mid 181.255546 146.329142)
		(end 181.175 146.134688)
		(width 0.157)
		(layer "In7.Cu")
		(net 532)
	)
	(arc
		(start 179.525 145.225)
		(mid 179.444454 145.419454)
		(end 179.25 145.5)
		(width 0.157)
		(layer "In7.Cu")
		(net 532)
	)
	(arc
		(start 182.825 146.134688)
		(mid 182.744454 146.329142)
		(end 182.55 146.409688)
		(width 0.157)
		(layer "In7.Cu")
		(net 532)
	)
	(arc
		(start 183.1 145.5)
		(mid 182.905546 145.580546)
		(end 182.825 145.775)
		(width 0.157)
		(layer "In7.Cu")
		(net 532)
	)
	(arc
		(start 180.075 144.865312)
		(mid 179.994454 144.670858)
		(end 179.8 144.590312)
		(width 0.157)
		(layer "In7.Cu")
		(net 532)
	)
	(arc
		(start 180.625 146.134688)
		(mid 180.544454 146.329142)
		(end 180.35 146.409688)
		(width 0.157)
		(layer "In7.Cu")
		(net 532)
	)
	(segment
		(start 165.6 143.6)
		(end 166 144)
		(width 0.256)
		(layer "F.Cu")
		(net 533)
	)
	(segment
		(start 188.5 141.5)
		(end 188.025879 141.974121)
		(width 0.256)
		(layer "F.Cu")
		(net 533)
	)
	(segment
		(start 188.025879 141.974121)
		(end 188.025879 142.014974)
		(width 0.256)
		(layer "F.Cu")
		(net 533)
	)
	(via
		(at 188.025879 142.014974)
		(size 0.45)
		(drill 0.2)
		(layers "F.Cu" "B.Cu")
		(net 533)
	)
	(via
		(at 165.6 143.6)
		(size 0.45)
		(drill 0.2)
		(layers "F.Cu" "B.Cu")
		(net 533)
	)
	(segment
		(start 165.399999 144.360381)
		(end 165.6 144.16038)
		(width 0.256)
		(layer "B.Cu")
		(net 533)
	)
	(segment
		(start 165.399999 144.699999)
		(end 165.399999 144.360381)
		(width 0.256)
		(layer "B.Cu")
		(net 533)
	)
	(segment
		(start 165.6 144.16038)
		(end 165.6 143.6)
		(width 0.256)
		(layer "B.Cu")
		(net 533)
	)
	(segment
		(start 165.882353 140.993139)
		(end 165.882355 140.993138)
		(width 0.157)
		(layer "In5.Cu")
		(net 533)
	)
	(segment
		(start 172.609 140.045)
		(end 172.609 140.195)
		(width 0.157)
		(layer "In5.Cu")
		(net 533)
	)
	(segment
		(start 179.438 140.395)
		(end 178.809 140.395)
		(width 0.157)
		(layer "In5.Cu")
		(net 533)
	)
	(segment
		(start 166.256862 141.367646)
		(end 165.882353 140.993139)
		(width 0.157)
		(layer "In5.Cu")
		(net 533)
	)
	(segment
		(start 165.974017 141.933333)
		(end 165.974018 141.933332)
		(width 0.157)
		(layer "In5.Cu")
		(net 533)
	)
	(segment
		(start 165.691175 141.933333)
		(end 165.645342 141.8875)
		(width 0.157)
		(layer "In5.Cu")
		(net 533)
	)
	(segment
		(start 165.6 143.6)
		(end 165.2 143.2)
		(width 0.157)
		(layer "In5.Cu")
		(net 533)
	)
	(segment
		(start 168.209 140.195)
		(end 168.209 140.045)
		(width 0.157)
		(layer "In5.Cu")
		(net 533)
	)
	(segment
		(start 166.493871 141.038969)
		(end 166.539705 141.084803)
		(width 0.157)
		(layer "In5.Cu")
		(net 533)
	)
	(segment
		(start 175.009 140.045)
		(end 175.009 140.195)
		(width 0.157)
		(layer "In5.Cu")
		(net 533)
	)
	(segment
		(start 173.009 140.195)
		(end 173.009 140.045)
		(width 0.157)
		(layer "In5.Cu")
		(net 533)
	)
	(segment
		(start 187.500905 141.49)
		(end 180.533 141.49)
		(width 0.157)
		(layer "In5.Cu")
		(net 533)
	)
	(segment
		(start 165.2 143.2)
		(end 165.2 142.95)
		(width 0.157)
		(layer "In5.Cu")
		(net 533)
	)
	(segment
		(start 175.809 140.045)
		(end 175.809 140.195)
		(width 0.157)
		(layer "In5.Cu")
		(net 533)
	)
	(segment
		(start 171.409 140.195)
		(end 171.409 140.045)
		(width 0.157)
		(layer "In5.Cu")
		(net 533)
	)
	(segment
		(start 178.209 140.045)
		(end 178.209 140.195)
		(width 0.157)
		(layer "In5.Cu")
		(net 533)
	)
	(segment
		(start 166.539705 141.367646)
		(end 166.539704 141.367646)
		(width 0.157)
		(layer "In5.Cu")
		(net 533)
	)
	(segment
		(start 169.409 140.045)
		(end 169.409 140.195)
		(width 0.157)
		(layer "In5.Cu")
		(net 533)
	)
	(segment
		(start 165.59951 141.275982)
		(end 165.974017 141.65049)
		(width 0.157)
		(layer "In5.Cu")
		(net 533)
	)
	(segment
		(start 177.809 140.195)
		(end 177.809 140.045)
		(width 0.157)
		(layer "In5.Cu")
		(net 533)
	)
	(segment
		(start 178.609 140.195)
		(end 178.609 140.045)
		(width 0.157)
		(layer "In5.Cu")
		(net 533)
	)
	(segment
		(start 165.974017 141.65049)
		(end 165.974017 141.650489)
		(width 0.157)
		(layer "In5.Cu")
		(net 533)
	)
	(segment
		(start 174.209 140.045)
		(end 174.209 140.195)
		(width 0.157)
		(layer "In5.Cu")
		(net 533)
	)
	(segment
		(start 165.3625 141.8875)
		(end 165.2 142.05)
		(width 0.157)
		(layer "In5.Cu")
		(net 533)
	)
	(segment
		(start 175.409 140.195)
		(end 175.409 140.045)
		(width 0.157)
		(layer "In5.Cu")
		(net 533)
	)
	(segment
		(start 176.609 140.045)
		(end 176.609 140.195)
		(width 0.157)
		(layer "In5.Cu")
		(net 533)
	)
	(segment
		(start 165.2 142.95)
		(end 165.2 142.65)
		(width 0.15)
		(layer "In5.Cu")
		(net 533)
	)
	(segment
		(start 168.609 140.045)
		(end 168.609 140.195)
		(width 0.157)
		(layer "In5.Cu")
		(net 533)
	)
	(segment
		(start 166.539705 141.084803)
		(end 166.539705 141.084802)
		(width 0.157)
		(layer "In5.Cu")
		(net 533)
	)
	(segment
		(start 171.009 140.045)
		(end 171.009 140.195)
		(width 0.157)
		(layer "In5.Cu")
		(net 533)
	)
	(segment
		(start 188.025879 142.014974)
		(end 187.500905 141.49)
		(width 0.157)
		(layer "In5.Cu")
		(net 533)
	)
	(segment
		(start 172.209 140.195)
		(end 172.209 140.045)
		(width 0.157)
		(layer "In5.Cu")
		(net 533)
	)
	(segment
		(start 165.2 142.05)
		(end 165.2 142.65)
		(width 0.157)
		(layer "In5.Cu")
		(net 533)
	)
	(segment
		(start 174.609 140.195)
		(end 174.609 140.045)
		(width 0.157)
		(layer "In5.Cu")
		(net 533)
	)
	(segment
		(start 169.809 140.195)
		(end 169.809 140.045)
		(width 0.157)
		(layer "In5.Cu")
		(net 533)
	)
	(segment
		(start 170.609 140.195)
		(end 170.609 140.045)
		(width 0.157)
		(layer "In5.Cu")
		(net 533)
	)
	(segment
		(start 165.599511 140.993138)
		(end 165.59951 140.99314)
		(width 0.157)
		(layer "In5.Cu")
		(net 533)
	)
	(segment
		(start 176.209 140.195)
		(end 176.209 140.045)
		(width 0.157)
		(layer "In5.Cu")
		(net 533)
	)
	(segment
		(start 166.855 140.395)
		(end 166.493872 140.756126)
		(width 0.157)
		(layer "In5.Cu")
		(net 533)
	)
	(segment
		(start 180.533 141.49)
		(end 179.438 140.395)
		(width 0.157)
		(layer "In5.Cu")
		(net 533)
	)
	(segment
		(start 167.609 140.395)
		(end 166.855 140.395)
		(width 0.157)
		(layer "In5.Cu")
		(net 533)
	)
	(segment
		(start 169.009 140.195)
		(end 169.009 140.045)
		(width 0.157)
		(layer "In5.Cu")
		(net 533)
	)
	(segment
		(start 173.809 140.195)
		(end 173.809 140.045)
		(width 0.157)
		(layer "In5.Cu")
		(net 533)
	)
	(segment
		(start 177.409 140.045)
		(end 177.409 140.195)
		(width 0.157)
		(layer "In5.Cu")
		(net 533)
	)
	(segment
		(start 177.009 140.195)
		(end 177.009 140.045)
		(width 0.157)
		(layer "In5.Cu")
		(net 533)
	)
	(segment
		(start 167.809 140.045)
		(end 167.809 140.195)
		(width 0.157)
		(layer "In5.Cu")
		(net 533)
	)
	(segment
		(start 170.209 140.045)
		(end 170.209 140.195)
		(width 0.157)
		(layer "In5.Cu")
		(net 533)
	)
	(segment
		(start 171.809 140.045)
		(end 171.809 140.195)
		(width 0.157)
		(layer "In5.Cu")
		(net 533)
	)
	(segment
		(start 173.409 140.045)
		(end 173.409 140.195)
		(width 0.157)
		(layer "In5.Cu")
		(net 533)
	)
	(arc
		(start 178.009 140.395)
		(mid 177.867579 140.336421)
		(end 177.809 140.195)
		(width 0.157)
		(layer "In5.Cu")
		(net 533)
	)
	(arc
		(start 171.409 140.045)
		(mid 171.350421 139.903579)
		(end 171.209 139.845)
		(width 0.157)
		(layer "In5.Cu")
		(net 533)
	)
	(arc
		(start 171.809 140.195)
		(mid 171.750421 140.336421)
		(end 171.609 140.395)
		(width 0.157)
		(layer "In5.Cu")
		(net 533)
	)
	(arc
		(start 171.209 139.845)
		(mid 171.067579 139.903579)
		(end 171.009 140.045)
		(width 0.157)
		(layer "In5.Cu")
		(net 533)
	)
	(arc
		(start 172.409 140.395)
		(mid 172.267579 140.336421)
		(end 172.209 140.195)
		(width 0.157)
		(layer "In5.Cu")
		(net 533)
	)
	(arc
		(start 168.809 139.845)
		(mid 168.667579 139.903579)
		(end 168.609 140.045)
		(width 0.157)
		(layer "In5.Cu")
		(net 533)
	)
	(arc
		(start 178.609 140.045)
		(mid 178.550421 139.903579)
		(end 178.409 139.845)
		(width 0.157)
		(layer "In5.Cu")
		(net 533)
	)
	(arc
		(start 171.009 140.195)
		(mid 170.950421 140.336421)
		(end 170.809 140.395)
		(width 0.157)
		(layer "In5.Cu")
		(net 533)
	)
	(arc
		(start 165.882355 140.993138)
		(mid 165.740932 140.93456)
		(end 165.599511 140.993138)
		(width 0.157)
		(layer "In5.Cu")
		(net 533)
	)
	(arc
		(start 175.209 139.845)
		(mid 175.067579 139.903579)
		(end 175.009 140.045)
		(width 0.157)
		(layer "In5.Cu")
		(net 533)
	)
	(arc
		(start 175.609 140.395)
		(mid 175.467579 140.336421)
		(end 175.409 140.195)
		(width 0.157)
		(layer "In5.Cu")
		(net 533)
	)
	(arc
		(start 173.409 140.195)
		(mid 173.350421 140.336421)
		(end 173.209 140.395)
		(width 0.157)
		(layer "In5.Cu")
		(net 533)
	)
	(arc
		(start 177.409 140.195)
		(mid 177.350421 140.336421)
		(end 177.209 140.395)
		(width 0.157)
		(layer "In5.Cu")
		(net 533)
	)
	(arc
		(start 177.809 140.045)
		(mid 177.750421 139.903579)
		(end 177.609 139.845)
		(width 0.157)
		(layer "In5.Cu")
		(net 533)
	)
	(arc
		(start 174.409 139.845)
		(mid 174.267579 139.903579)
		(end 174.209 140.045)
		(width 0.157)
		(layer "In5.Cu")
		(net 533)
	)
	(arc
		(start 165.645342 141.8875)
		(mid 165.503921 141.828922)
		(end 165.3625 141.8875)
		(width 0.157)
		(layer "In5.Cu")
		(net 533)
	)
	(arc
		(start 178.409 139.845)
		(mid 178.267579 139.903579)
		(end 178.209 140.045)
		(width 0.157)
		(layer "In5.Cu")
		(net 533)
	)
	(arc
		(start 166.539704 141.367646)
		(mid 166.398283 141.426224)
		(end 166.256862 141.367646)
		(width 0.157)
		(layer "In5.Cu")
		(net 533)
	)
	(arc
		(start 177.009 140.045)
		(mid 176.950421 139.903579)
		(end 176.809 139.845)
		(width 0.157)
		(layer "In5.Cu")
		(net 533)
	)
	(arc
		(start 168.209 140.045)
		(mid 168.150421 139.903579)
		(end 168.009 139.845)
		(width 0.157)
		(layer "In5.Cu")
		(net 533)
	)
	(arc
		(start 169.009 140.045)
		(mid 168.950421 139.903579)
		(end 168.809 139.845)
		(width 0.157)
		(layer "In5.Cu")
		(net 533)
	)
	(arc
		(start 173.609 139.845)
		(mid 173.467579 139.903579)
		(end 173.409 140.045)
		(width 0.157)
		(layer "In5.Cu")
		(net 533)
	)
	(arc
		(start 176.609 140.195)
		(mid 176.550421 140.336421)
		(end 176.409 140.395)
		(width 0.157)
		(layer "In5.Cu")
		(net 533)
	)
	(arc
		(start 175.809 140.195)
		(mid 175.750421 140.336421)
		(end 175.609 140.395)
		(width 0.157)
		(layer "In5.Cu")
		(net 533)
	)
	(arc
		(start 166.493872 140.756126)
		(mid 166.435293 140.897547)
		(end 166.493871 141.038969)
		(width 0.157)
		(layer "In5.Cu")
		(net 533)
	)
	(arc
		(start 169.809 140.045)
		(mid 169.750421 139.903579)
		(end 169.609 139.845)
		(width 0.157)
		(layer "In5.Cu")
		(net 533)
	)
	(arc
		(start 174.809 140.395)
		(mid 174.667579 140.336421)
		(end 174.609 140.195)
		(width 0.157)
		(layer "In5.Cu")
		(net 533)
	)
	(arc
		(start 170.209 140.195)
		(mid 170.150421 140.336421)
		(end 170.009 140.395)
		(width 0.157)
		(layer "In5.Cu")
		(net 533)
	)
	(arc
		(start 173.809 140.045)
		(mid 173.750421 139.903579)
		(end 173.609 139.845)
		(width 0.157)
		(layer "In5.Cu")
		(net 533)
	)
	(arc
		(start 178.209 140.195)
		(mid 178.150421 140.336421)
		(end 178.009 140.395)
		(width 0.157)
		(layer "In5.Cu")
		(net 533)
	)
	(arc
		(start 169.209 140.395)
		(mid 169.067579 140.336421)
		(end 169.009 140.195)
		(width 0.157)
		(layer "In5.Cu")
		(net 533)
	)
	(arc
		(start 167.809 140.195)
		(mid 167.750421 140.336421)
		(end 167.609 140.395)
		(width 0.157)
		(layer "In5.Cu")
		(net 533)
	)
	(arc
		(start 172.209 140.045)
		(mid 172.150421 139.903579)
		(end 172.009 139.845)
		(width 0.157)
		(layer "In5.Cu")
		(net 533)
	)
	(arc
		(start 170.809 140.395)
		(mid 170.667579 140.336421)
		(end 170.609 140.195)
		(width 0.157)
		(layer "In5.Cu")
		(net 533)
	)
	(arc
		(start 177.209 140.395)
		(mid 177.067579 140.336421)
		(end 177.009 140.195)
		(width 0.157)
		(layer "In5.Cu")
		(net 533)
	)
	(arc
		(start 176.809 139.845)
		(mid 176.667579 139.903579)
		(end 176.609 140.045)
		(width 0.157)
		(layer "In5.Cu")
		(net 533)
	)
	(arc
		(start 177.609 139.845)
		(mid 177.467579 139.903579)
		(end 177.409 140.045)
		(width 0.157)
		(layer "In5.Cu")
		(net 533)
	)
	(arc
		(start 170.609 140.045)
		(mid 170.550421 139.903579)
		(end 170.409 139.845)
		(width 0.157)
		(layer "In5.Cu")
		(net 533)
	)
	(arc
		(start 165.974018 141.933332)
		(mid 165.832597 141.991911)
		(end 165.691175 141.933333)
		(width 0.157)
		(layer "In5.Cu")
		(net 533)
	)
	(arc
		(start 165.974017 141.650489)
		(mid 166.032596 141.791911)
		(end 165.974017 141.933333)
		(width 0.157)
		(layer "In5.Cu")
		(net 533)
	)
	(arc
		(start 172.009 139.845)
		(mid 171.867579 139.903579)
		(end 171.809 140.045)
		(width 0.157)
		(layer "In5.Cu")
		(net 533)
	)
	(arc
		(start 174.209 140.195)
		(mid 174.150421 140.336421)
		(end 174.009 140.395)
		(width 0.157)
		(layer "In5.Cu")
		(net 533)
	)
	(arc
		(start 170.009 140.395)
		(mid 169.867579 140.336421)
		(end 169.809 140.195)
		(width 0.157)
		(layer "In5.Cu")
		(net 533)
	)
	(arc
		(start 176.009 139.845)
		(mid 175.867579 139.903579)
		(end 175.809 140.045)
		(width 0.157)
		(layer "In5.Cu")
		(net 533)
	)
	(arc
		(start 171.609 140.395)
		(mid 171.467579 140.336421)
		(end 171.409 140.195)
		(width 0.157)
		(layer "In5.Cu")
		(net 533)
	)
	(arc
		(start 172.809 139.845)
		(mid 172.667579 139.903579)
		(end 172.609 140.045)
		(width 0.157)
		(layer "In5.Cu")
		(net 533)
	)
	(arc
		(start 173.209 140.395)
		(mid 173.067579 140.336421)
		(end 173.009 140.195)
		(width 0.157)
		(layer "In5.Cu")
		(net 533)
	)
	(arc
		(start 178.809 140.395)
		(mid 178.667579 140.336421)
		(end 178.609 140.195)
		(width 0.157)
		(layer "In5.Cu")
		(net 533)
	)
	(arc
		(start 165.59951 140.99314)
		(mid 165.540933 141.13456)
		(end 165.59951 141.275982)
		(width 0.157)
		(layer "In5.Cu")
		(net 533)
	)
	(arc
		(start 172.609 140.195)
		(mid 172.550421 140.336421)
		(end 172.409 140.395)
		(width 0.157)
		(layer "In5.Cu")
		(net 533)
	)
	(arc
		(start 173.009 140.045)
		(mid 172.950421 139.903579)
		(end 172.809 139.845)
		(width 0.157)
		(layer "In5.Cu")
		(net 533)
	)
	(arc
		(start 168.609 140.195)
		(mid 168.550421 140.336421)
		(end 168.409 140.395)
		(width 0.157)
		(layer "In5.Cu")
		(net 533)
	)
	(arc
		(start 169.609 139.845)
		(mid 169.467579 139.903579)
		(end 169.409 140.045)
		(width 0.157)
		(layer "In5.Cu")
		(net 533)
	)
	(arc
		(start 175.409 140.045)
		(mid 175.350421 139.903579)
		(end 175.209 139.845)
		(width 0.157)
		(layer "In5.Cu")
		(net 533)
	)
	(arc
		(start 176.409 140.395)
		(mid 176.267579 140.336421)
		(end 176.209 140.195)
		(width 0.157)
		(layer "In5.Cu")
		(net 533)
	)
	(arc
		(start 176.209 140.045)
		(mid 176.150421 139.903579)
		(end 176.009 139.845)
		(width 0.157)
		(layer "In5.Cu")
		(net 533)
	)
	(arc
		(start 168.009 139.845)
		(mid 167.867579 139.903579)
		(end 167.809 140.045)
		(width 0.157)
		(layer "In5.Cu")
		(net 533)
	)
	(arc
		(start 170.409 139.845)
		(mid 170.267579 139.903579)
		(end 170.209 140.045)
		(width 0.157)
		(layer "In5.Cu")
		(net 533)
	)
	(arc
		(start 166.539705 141.084802)
		(mid 166.598284 141.226224)
		(end 166.539705 141.367646)
		(width 0.157)
		(layer "In5.Cu")
		(net 533)
	)
	(arc
		(start 175.009 140.195)
		(mid 174.950421 140.336421)
		(end 174.809 140.395)
		(width 0.157)
		(layer "In5.Cu")
		(net 533)
	)
	(arc
		(start 174.009 140.395)
		(mid 173.867579 140.336421)
		(end 173.809 140.195)
		(width 0.157)
		(layer "In5.Cu")
		(net 533)
	)
	(arc
		(start 169.409 140.195)
		(mid 169.350421 140.336421)
		(end 169.209 140.395)
		(width 0.157)
		(layer "In5.Cu")
		(net 533)
	)
	(arc
		(start 174.609 140.045)
		(mid 174.550421 139.903579)
		(end 174.409 139.845)
		(width 0.157)
		(layer "In5.Cu")
		(net 533)
	)
	(arc
		(start 168.409 140.395)
		(mid 168.267579 140.336421)
		(end 168.209 140.195)
		(width 0.157)
		(layer "In5.Cu")
		(net 533)
	)
	(segment
		(start 185.5 140.5)
		(end 185 141)
		(width 0.256)
		(layer "F.Cu")
		(net 534)
	)
	(segment
		(start 166.4 142.8)
		(end 166.8 143.2)
		(width 0.256)
		(layer "F.Cu")
		(net 534)
	)
	(via
		(at 166.4 142.8)
		(size 0.45)
		(drill 0.2)
		(layers "F.Cu" "B.Cu")
		(net 534)
	)
	(via
		(at 185 141)
		(size 0.45)
		(drill 0.2)
		(layers "F.Cu" "B.Cu")
		(net 534)
	)
	(segment
		(start 166.4 140.35)
		(end 168.35 138.4)
		(width 0.256)
		(layer "B.Cu")
		(net 534)
	)
	(segment
		(start 180.575 142.725)
		(end 182.3 141)
		(width 0.256)
		(layer "B.Cu")
		(net 534)
	)
	(segment
		(start 166.399996 142.8)
		(end 165.999997 143.199999)
		(width 0.256)
		(layer "B.Cu")
		(net 534)
	)
	(segment
		(start 166 143.85)
		(end 166 143.350002)
		(width 0.15)
		(layer "B.Cu")
		(net 534)
	)
	(segment
		(start 178.3 147.6)
		(end 178.9 148.2)
		(width 0.256)
		(layer "B.Cu")
		(net 534)
	)
	(segment
		(start 178.9 148.2)
		(end 180.15 148.2)
		(width 0.256)
		(layer "B.Cu")
		(net 534)
	)
	(segment
		(start 165.799999 144.699999)
		(end 165.799999 144.463841)
		(width 0.256)
		(layer "B.Cu")
		(net 534)
	)
	(segment
		(start 182.3 141)
		(end 185 141)
		(width 0.256)
		(layer "B.Cu")
		(net 534)
	)
	(segment
		(start 166.8 142.4)
		(end 166.8 141.675)
		(width 0.256)
		(layer "B.Cu")
		(net 534)
	)
	(segment
		(start 179.431813 144.975)
		(end 181.118187 144.975)
		(width 0.256)
		(layer "B.Cu")
		(net 534)
	)
	(segment
		(start 180.15 148.2)
		(end 180.575 147.775)
		(width 0.256)
		(layer "B.Cu")
		(net 534)
	)
	(segment
		(start 166.4 142.8)
		(end 166.8 142.4)
		(width 0.256)
		(layer "B.Cu")
		(net 534)
	)
	(segment
		(start 178.3 140.95)
		(end 178.3 147.6)
		(width 0.256)
		(layer "B.Cu")
		(net 534)
	)
	(segment
		(start 180.575 143.225)
		(end 180.575 142.725)
		(width 0.256)
		(layer "B.Cu")
		(net 534)
	)
	(segment
		(start 179.431813 143.475)
		(end 180.325 143.475)
		(width 0.256)
		(layer "B.Cu")
		(net 534)
	)
	(segment
		(start 166.4 141.275)
		(end 166.4 140.35)
		(width 0.256)
		(layer "B.Cu")
		(net 534)
	)
	(segment
		(start 179.431813 144.475)
		(end 181.118187 144.475)
		(width 0.256)
		(layer "B.Cu")
		(net 534)
	)
	(segment
		(start 179.431813 145.975)
		(end 181.118187 145.975)
		(width 0.256)
		(layer "B.Cu")
		(net 534)
	)
	(segment
		(start 175.75 138.4)
		(end 178.3 140.95)
		(width 0.256)
		(layer "B.Cu")
		(net 534)
	)
	(segment
		(start 179.431813 146.475)
		(end 181.118187 146.475)
		(width 0.256)
		(layer "B.Cu")
		(net 534)
	)
	(segment
		(start 165.799999 144.463841)
		(end 166 144.26384)
		(width 0.256)
		(layer "B.Cu")
		(net 534)
	)
	(segment
		(start 179.431813 143.975)
		(end 181.118187 143.975)
		(width 0.256)
		(layer "B.Cu")
		(net 534)
	)
	(segment
		(start 166.8 141.675)
		(end 166.4 141.275)
		(width 0.256)
		(layer "B.Cu")
		(net 534)
	)
	(segment
		(start 179.431813 145.475)
		(end 181.118187 145.475)
		(width 0.256)
		(layer "B.Cu")
		(net 534)
	)
	(segment
		(start 166 143.350002)
		(end 165.999997 143.349999)
		(width 0.15)
		(layer "B.Cu")
		(net 534)
	)
	(segment
		(start 166 144.26384)
		(end 166 143.85)
		(width 0.256)
		(layer "B.Cu")
		(net 534)
	)
	(segment
		(start 165.999997 143.199999)
		(end 165.999997 143.349999)
		(width 0.256)
		(layer "B.Cu")
		(net 534)
	)
	(segment
		(start 168.35 138.4)
		(end 175.75 138.4)
		(width 0.256)
		(layer "B.Cu")
		(net 534)
	)
	(segment
		(start 180.575 147.775)
		(end 180.575 147.225)
		(width 0.256)
		(layer "B.Cu")
		(net 534)
	)
	(segment
		(start 180.325 146.975)
		(end 179.431813 146.975)
		(width 0.256)
		(layer "B.Cu")
		(net 534)
	)
	(arc
		(start 179.431813 143.975)
		(mid 179.255036 143.901777)
		(end 179.181813 143.725)
		(width 0.256)
		(layer "B.Cu")
		(net 534)
	)
	(arc
		(start 179.181813 143.725)
		(mid 179.255036 143.548223)
		(end 179.431813 143.475)
		(width 0.256)
		(layer "B.Cu")
		(net 534)
	)
	(arc
		(start 180.325 143.475)
		(mid 180.501777 143.401777)
		(end 180.575 143.225)
		(width 0.256)
		(layer "B.Cu")
		(net 534)
	)
	(arc
		(start 179.181813 146.725)
		(mid 179.255036 146.548223)
		(end 179.431813 146.475)
		(width 0.256)
		(layer "B.Cu")
		(net 534)
	)
	(arc
		(start 179.181813 145.725)
		(mid 179.255036 145.548223)
		(end 179.431813 145.475)
		(width 0.256)
		(layer "B.Cu")
		(net 534)
	)
	(arc
		(start 179.181813 144.725)
		(mid 179.255036 144.548223)
		(end 179.431813 144.475)
		(width 0.256)
		(layer "B.Cu")
		(net 534)
	)
	(arc
		(start 180.575 147.225)
		(mid 180.501777 147.048223)
		(end 180.325 146.975)
		(width 0.256)
		(layer "B.Cu")
		(net 534)
	)
	(arc
		(start 181.118187 145.475)
		(mid 181.294964 145.401777)
		(end 181.368187 145.225)
		(width 0.256)
		(layer "B.Cu")
		(net 534)
	)
	(arc
		(start 179.431813 145.975)
		(mid 179.255036 145.901777)
		(end 179.181813 145.725)
		(width 0.256)
		(layer "B.Cu")
		(net 534)
	)
	(arc
		(start 181.368187 144.225)
		(mid 181.294964 144.048223)
		(end 181.118187 143.975)
		(width 0.256)
		(layer "B.Cu")
		(net 534)
	)
	(arc
		(start 181.368187 146.225)
		(mid 181.294964 146.048223)
		(end 181.118187 145.975)
		(width 0.256)
		(layer "B.Cu")
		(net 534)
	)
	(arc
		(start 181.368187 145.225)
		(mid 181.294964 145.048223)
		(end 181.118187 144.975)
		(width 0.256)
		(layer "B.Cu")
		(net 534)
	)
	(arc
		(start 179.431813 144.975)
		(mid 179.255036 144.901777)
		(end 179.181813 144.725)
		(width 0.256)
		(layer "B.Cu")
		(net 534)
	)
	(arc
		(start 181.118187 146.475)
		(mid 181.294964 146.401777)
		(end 181.368187 146.225)
		(width 0.256)
		(layer "B.Cu")
		(net 534)
	)
	(arc
		(start 181.118187 144.475)
		(mid 181.294964 144.401777)
		(end 181.368187 144.225)
		(width 0.256)
		(layer "B.Cu")
		(net 534)
	)
	(arc
		(start 179.431813 146.975)
		(mid 179.255036 146.901777)
		(end 179.181813 146.725)
		(width 0.256)
		(layer "B.Cu")
		(net 534)
	)
	(segment
		(start 185.5 139.5)
		(end 185 140)
		(width 0.256)
		(layer "F.Cu")
		(net 535)
	)
	(segment
		(start 165.6 148.4)
		(end 166 148)
		(width 0.256)
		(layer "F.Cu")
		(net 535)
	)
	(via
		(at 185 140)
		(size 0.45)
		(drill 0.2)
		(layers "F.Cu" "B.Cu")
		(net 535)
	)
	(via
		(at 165.6 148.4)
		(size 0.45)
		(drill 0.2)
		(layers "F.Cu" "B.Cu")
		(net 535)
	)
	(segment
		(start 187.430511 147.975)
		(end 187.825 147.975)
		(width 0.256)
		(layer "B.Cu")
		(net 535)
	)
	(segment
		(start 165.2 147.025)
		(end 165.2 147.35)
		(width 0.256)
		(layer "B.Cu")
		(net 535)
	)
	(segment
		(start 186.5 139.75)
		(end 186.25 139.5)
		(width 0.256)
		(layer "B.Cu")
		(net 535)
	)
	(segment
		(start 186.25 139.5)
		(end 185.5 139.5)
		(width 0.256)
		(layer "B.Cu")
		(net 535)
	)
	(segment
		(start 188.1 147.3)
		(end 187.025 146.225)
		(width 0.256)
		(layer "B.Cu")
		(net 535)
	)
	(segment
		(start 187.825 150.725)
		(end 187.430511 150.725)
		(width 0.256)
		(layer "B.Cu")
		(net 535)
	)
	(segment
		(start 188.1 153.7)
		(end 188.1 153.2)
		(width 0.256)
		(layer "B.Cu")
		(net 535)
	)
	(segment
		(start 187.025 143.7)
		(end 186.5 143.175)
		(width 0.256)
		(layer "B.Cu")
		(net 535)
	)
	(segment
		(start 166.75 154.25)
		(end 187.55 154.25)
		(width 0.256)
		(layer "B.Cu")
		(net 535)
	)
	(segment
		(start 188.1 147.7)
		(end 188.1 147.3)
		(width 0.256)
		(layer "B.Cu")
		(net 535)
	)
	(segment
		(start 165.6 148.4)
		(end 165.55 148.45)
		(width 0.256)
		(layer "B.Cu")
		(net 535)
	)
	(segment
		(start 187.025 146.225)
		(end 187.025 143.7)
		(width 0.256)
		(layer "B.Cu")
		(net 535)
	)
	(segment
		(start 165.55 149.05)
		(end 166.2 149.7)
		(width 0.256)
		(layer "B.Cu")
		(net 535)
	)
	(segment
		(start 187.430511 152.375)
		(end 187.825 152.375)
		(width 0.256)
		(layer "B.Cu")
		(net 535)
	)
	(segment
		(start 187.430511 149.075)
		(end 187.825 149.075)
		(width 0.256)
		(layer "B.Cu")
		(net 535)
	)
	(segment
		(start 187.55 154.25)
		(end 188.1 153.7)
		(width 0.256)
		(layer "B.Cu")
		(net 535)
	)
	(segment
		(start 187.825 149.625)
		(end 187.430511 149.625)
		(width 0.256)
		(layer "B.Cu")
		(net 535)
	)
	(segment
		(start 165.200001 147.849997)
		(end 165.2 147.35)
		(width 0.15)
		(layer "B.Cu")
		(net 535)
	)
	(segment
		(start 165.6 148.399996)
		(end 165.200001 147.999997)
		(width 0.256)
		(layer "B.Cu")
		(net 535)
	)
	(segment
		(start 165.399999 146.825001)
		(end 165.25 146.975)
		(width 0.256)
		(layer "B.Cu")
		(net 535)
	)
	(segment
		(start 187.825 151.825)
		(end 187.430511 151.825)
		(width 0.256)
		(layer "B.Cu")
		(net 535)
	)
	(segment
		(start 166.2 153.7)
		(end 166.75 154.25)
		(width 0.256)
		(layer "B.Cu")
		(net 535)
	)
	(segment
		(start 165.399999 146.499999)
		(end 165.399999 146.825001)
		(width 0.256)
		(layer "B.Cu")
		(net 535)
	)
	(segment
		(start 165.25 146.975)
		(end 165.2 147.025)
		(width 0.256)
		(layer "B.Cu")
		(net 535)
	)
	(segment
		(start 187.825 148.525)
		(end 187.430511 148.525)
		(width 0.256)
		(layer "B.Cu")
		(net 535)
	)
	(segment
		(start 187.825 152.925)
		(end 187.430511 152.925)
		(width 0.256)
		(layer "B.Cu")
		(net 535)
	)
	(segment
		(start 186.5 143.175)
		(end 186.5 139.75)
		(width 0.256)
		(layer "B.Cu")
		(net 535)
	)
	(segment
		(start 185.5 139.5)
		(end 185 140)
		(width 0.256)
		(layer "B.Cu")
		(net 535)
	)
	(segment
		(start 187.430511 151.275)
		(end 187.825 151.275)
		(width 0.256)
		(layer "B.Cu")
		(net 535)
	)
	(segment
		(start 165.200001 147.999997)
		(end 165.200001 147.849997)
		(width 0.256)
		(layer "B.Cu")
		(net 535)
	)
	(segment
		(start 165.55 148.45)
		(end 165.55 149.05)
		(width 0.256)
		(layer "B.Cu")
		(net 535)
	)
	(segment
		(start 187.430511 150.175)
		(end 187.825 150.175)
		(width 0.256)
		(layer "B.Cu")
		(net 535)
	)
	(segment
		(start 166.2 149.7)
		(end 166.2 153.7)
		(width 0.256)
		(layer "B.Cu")
		(net 535)
	)
	(arc
		(start 187.155511 151.55)
		(mid 187.236057 151.355546)
		(end 187.430511 151.275)
		(width 0.256)
		(layer "B.Cu")
		(net 535)
	)
	(arc
		(start 187.430511 148.525)
		(mid 187.236057 148.444454)
		(end 187.155511 148.25)
		(width 0.256)
		(layer "B.Cu")
		(net 535)
	)
	(arc
		(start 188.1 151)
		(mid 188.019454 150.805546)
		(end 187.825 150.725)
		(width 0.256)
		(layer "B.Cu")
		(net 535)
	)
	(arc
		(start 187.825 149.075)
		(mid 188.019454 148.994454)
		(end 188.1 148.8)
		(width 0.256)
		(layer "B.Cu")
		(net 535)
	)
	(arc
		(start 187.155511 150.45)
		(mid 187.236057 150.255546)
		(end 187.430511 150.175)
		(width 0.256)
		(layer "B.Cu")
		(net 535)
	)
	(arc
		(start 188.1 149.9)
		(mid 188.019454 149.705546)
		(end 187.825 149.625)
		(width 0.256)
		(layer "B.Cu")
		(net 535)
	)
	(arc
		(start 187.825 151.275)
		(mid 188.019454 151.194454)
		(end 188.1 151)
		(width 0.256)
		(layer "B.Cu")
		(net 535)
	)
	(arc
		(start 187.155511 148.25)
		(mid 187.236057 148.055546)
		(end 187.430511 147.975)
		(width 0.256)
		(layer "B.Cu")
		(net 535)
	)
	(arc
		(start 187.430511 152.925)
		(mid 187.236057 152.844454)
		(end 187.155511 152.65)
		(width 0.256)
		(layer "B.Cu")
		(net 535)
	)
	(arc
		(start 187.155511 152.65)
		(mid 187.236057 152.455546)
		(end 187.430511 152.375)
		(width 0.256)
		(layer "B.Cu")
		(net 535)
	)
	(arc
		(start 187.430511 149.625)
		(mid 187.236057 149.544454)
		(end 187.155511 149.35)
		(width 0.256)
		(layer "B.Cu")
		(net 535)
	)
	(arc
		(start 188.1 153.2)
		(mid 188.019454 153.005546)
		(end 187.825 152.925)
		(width 0.256)
		(layer "B.Cu")
		(net 535)
	)
	(arc
		(start 187.825 147.975)
		(mid 188.019454 147.894454)
		(end 188.1 147.7)
		(width 0.256)
		(layer "B.Cu")
		(net 535)
	)
	(arc
		(start 187.155511 149.35)
		(mid 187.236057 149.155546)
		(end 187.430511 149.075)
		(width 0.256)
		(layer "B.Cu")
		(net 535)
	)
	(arc
		(start 187.825 152.375)
		(mid 188.019454 152.294454)
		(end 188.1 152.1)
		(width 0.256)
		(layer "B.Cu")
		(net 535)
	)
	(arc
		(start 187.825 150.175)
		(mid 188.019454 150.094454)
		(end 188.1 149.9)
		(width 0.256)
		(layer "B.Cu")
		(net 535)
	)
	(arc
		(start 188.1 152.1)
		(mid 188.019454 151.905546)
		(end 187.825 151.825)
		(width 0.256)
		(layer "B.Cu")
		(net 535)
	)
	(arc
		(start 188.1 148.8)
		(mid 188.019454 148.605546)
		(end 187.825 148.525)
		(width 0.256)
		(layer "B.Cu")
		(net 535)
	)
	(arc
		(start 187.430511 150.725)
		(mid 187.236057 150.644454)
		(end 187.155511 150.45)
		(width 0.256)
		(layer "B.Cu")
		(net 535)
	)
	(arc
		(start 187.430511 151.825)
		(mid 187.236057 151.744454)
		(end 187.155511 151.55)
		(width 0.256)
		(layer "B.Cu")
		(net 535)
	)
	(segment
		(start 165.6 142.8)
		(end 166 143.2)
		(width 0.256)
		(layer "F.Cu")
		(net 536)
	)
	(segment
		(start 186.5 140.5)
		(end 186 141)
		(width 0.256)
		(layer "F.Cu")
		(net 536)
	)
	(via
		(at 165.6 142.8)
		(size 0.45)
		(drill 0.2)
		(layers "F.Cu" "B.Cu")
		(net 536)
	)
	(via
		(at 186 141)
		(size 0.45)
		(drill 0.2)
		(layers "F.Cu" "B.Cu")
		(net 536)
	)
	(segment
		(start 177.01066 138.357107)
		(end 178.155318 137.212446)
		(width 0.256)
		(layer "B.Cu")
		(net 536)
	)
	(segment
		(start 177.717766 139.064213)
		(end 179.569531 137.212445)
		(width 0.256)
		(layer "B.Cu")
		(net 536)
	)
	(segment
		(start 177.010659 138.357105)
		(end 177.01066 138.357107)
		(width 0.256)
		(layer "B.Cu")
		(net 536)
	)
	(segment
		(start 180.63019 137.919552)
		(end 180.630191 137.919552)
		(width 0.256)
		(layer "B.Cu")
		(net 536)
	)
	(segment
		(start 177.364212 139.064213)
		(end 177.364211 139.064211)
		(width 0.256)
		(layer "B.Cu")
		(net 536)
	)
	(segment
		(start 179.131977 140.478423)
		(end 179.131978 140.478425)
		(width 0.256)
		(layer "B.Cu")
		(net 536)
	)
	(segment
		(start 178.508872 137.212446)
		(end 178.508872 137.212447)
		(width 0.256)
		(layer "B.Cu")
		(net 536)
	)
	(segment
		(start 177.165369 137.49529)
		(end 177.165369 137.495289)
		(width 0.256)
		(layer "B.Cu")
		(net 536)
	)
	(segment
		(start 177.165369 137.495289)
		(end 176.657106 138.003553)
		(width 0.256)
		(layer "B.Cu")
		(net 536)
	)
	(segment
		(start 177.717765 139.064211)
		(end 177.717766 139.064213)
		(width 0.256)
		(layer "B.Cu")
		(net 536)
	)
	(segment
		(start 181.337296 138.98021)
		(end 179.48553 140.831977)
		(width 0.256)
		(layer "B.Cu")
		(net 536)
	)
	(segment
		(start 180.63019 138.273105)
		(end 180.63019 138.273104)
		(width 0.256)
		(layer "B.Cu")
		(net 536)
	)
	(segment
		(start 177.364211 139.064211)
		(end 177.364212 139.064212)
		(width 0.256)
		(layer "B.Cu")
		(net 536)
	)
	(segment
		(start 175.75 137.45)
		(end 175.95 137.65)
		(width 0.256)
		(layer "B.Cu")
		(net 536)
	)
	(segment
		(start 178.424871 139.771317)
		(end 178.424872 139.771319)
		(width 0.256)
		(layer "B.Cu")
		(net 536)
	)
	(segment
		(start 181.337296 138.980211)
		(end 181.337296 138.98021)
		(width 0.256)
		(layer "B.Cu")
		(net 536)
	)
	(segment
		(start 165.599994 142.800002)
		(end 165.199995 143.200001)
		(width 0.256)
		(layer "B.Cu")
		(net 536)
	)
	(segment
		(start 178.778425 140.478424)
		(end 178.778423 140.478423)
		(width 0.256)
		(layer "B.Cu")
		(net 536)
	)
	(segment
		(start 179.923084 137.565999)
		(end 179.923084 137.565998)
		(width 0.256)
		(layer "B.Cu")
		(net 536)
	)
	(segment
		(start 178.424872 139.771319)
		(end 180.276637 137.919551)
		(width 0.256)
		(layer "B.Cu")
		(net 536)
	)
	(segment
		(start 179.485529 141.185529)
		(end 179.75 141.45)
		(width 0.256)
		(layer "B.Cu")
		(net 536)
	)
	(segment
		(start 179.485531 141.18553)
		(end 179.485529 141.185529)
		(width 0.256)
		(layer "B.Cu")
		(net 536)
	)
	(segment
		(start 176.657106 138.357107)
		(end 176.657105 138.357105)
		(width 0.256)
		(layer "B.Cu")
		(net 536)
	)
	(segment
		(start 176.303554 137.650001)
		(end 176.811816 137.141736)
		(width 0.256)
		(layer "B.Cu")
		(net 536)
	)
	(segment
		(start 165.199995 143.200001)
		(end 165.199995 143.350001)
		(width 0.256)
		(layer "B.Cu")
		(net 536)
	)
	(segment
		(start 180.63019 138.273104)
		(end 178.778424 140.124871)
		(width 0.256)
		(layer "B.Cu")
		(net 536)
	)
	(segment
		(start 165.2 144.05692)
		(end 164.799999 144.456921)
		(width 0.256)
		(layer "B.Cu")
		(net 536)
	)
	(segment
		(start 178.508871 137.566)
		(end 178.508871 137.565999)
		(width 0.256)
		(layer "B.Cu")
		(net 536)
	)
	(segment
		(start 178.071319 139.771318)
		(end 178.071317 139.771317)
		(width 0.256)
		(layer "B.Cu")
		(net 536)
	)
	(segment
		(start 179.131978 140.478425)
		(end 180.983743 138.626657)
		(width 0.256)
		(layer "B.Cu")
		(net 536)
	)
	(segment
		(start 179.923084 137.212446)
		(end 179.923085 137.212446)
		(width 0.256)
		(layer "B.Cu")
		(net 536)
	)
	(segment
		(start 180.85 141.45)
		(end 181.8 140.5)
		(width 0.256)
		(layer "B.Cu")
		(net 536)
	)
	(segment
		(start 181.337296 138.626658)
		(end 181.337297 138.626658)
		(width 0.256)
		(layer "B.Cu")
		(net 536)
	)
	(segment
		(start 165.2 143.350006)
		(end 165.199995 143.350001)
		(width 0.15)
		(layer "B.Cu")
		(net 536)
	)
	(segment
		(start 181.8 140.5)
		(end 185.5 140.5)
		(width 0.256)
		(layer "B.Cu")
		(net 536)
	)
	(segment
		(start 179.923084 137.565998)
		(end 178.071318 139.417765)
		(width 0.256)
		(layer "B.Cu")
		(net 536)
	)
	(segment
		(start 165.599998 140.100002)
		(end 168.25 137.45)
		(width 0.256)
		(layer "B.Cu")
		(net 536)
	)
	(segment
		(start 185.5 140.5)
		(end 186 141)
		(width 0.256)
		(layer "B.Cu")
		(net 536)
	)
	(segment
		(start 176.657105 138.357105)
		(end 176.657106 138.357106)
		(width 0.256)
		(layer "B.Cu")
		(net 536)
	)
	(segment
		(start 177.16537 137.141736)
		(end 177.16537 137.141737)
		(width 0.256)
		(layer "B.Cu")
		(net 536)
	)
	(segment
		(start 165.2 143.875)
		(end 165.2 144.05692)
		(width 0.256)
		(layer "B.Cu")
		(net 536)
	)
	(segment
		(start 178.508871 137.565999)
		(end 177.364212 138.710659)
		(width 0.256)
		(layer "B.Cu")
		(net 536)
	)
	(segment
		(start 178.071317 139.771317)
		(end 178.071318 139.771318)
		(width 0.256)
		(layer "B.Cu")
		(net 536)
	)
	(segment
		(start 168.25 137.45)
		(end 175.75 137.45)
		(width 0.256)
		(layer "B.Cu")
		(net 536)
	)
	(segment
		(start 165.599998 142.800002)
		(end 165.599998 140.100002)
		(width 0.256)
		(layer "B.Cu")
		(net 536)
	)
	(segment
		(start 176.303553 137.649999)
		(end 176.303554 137.650001)
		(width 0.256)
		(layer "B.Cu")
		(net 536)
	)
	(segment
		(start 165.2 143.875)
		(end 165.2 143.350006)
		(width 0.15)
		(layer "B.Cu")
		(net 536)
	)
	(segment
		(start 164.799999 144.456921)
		(end 164.799999 144.699999)
		(width 0.256)
		(layer "B.Cu")
		(net 536)
	)
	(segment
		(start 178.778423 140.478423)
		(end 178.778424 140.478424)
		(width 0.256)
		(layer "B.Cu")
		(net 536)
	)
	(segment
		(start 179.75 141.45)
		(end 180.85 141.45)
		(width 0.256)
		(layer "B.Cu")
		(net 536)
	)
	(arc
		(start 178.071318 139.771318)
		(mid 178.248095 139.844541)
		(end 178.424871 139.771317)
		(width 0.256)
		(layer "B.Cu")
		(net 536)
	)
	(arc
		(start 179.569531 137.212445)
		(mid 179.746308 137.139222)
		(end 179.923084 137.212446)
		(width 0.256)
		(layer "B.Cu")
		(net 536)
	)
	(arc
		(start 176.811816 137.141736)
		(mid 176.988593 137.068513)
		(end 177.16537 137.141736)
		(width 0.256)
		(layer "B.Cu")
		(net 536)
	)
	(arc
		(start 178.071318 139.417765)
		(mid 177.998095 139.594542)
		(end 178.071319 139.771318)
		(width 0.256)
		(layer "B.Cu")
		(net 536)
	)
	(arc
		(start 178.778424 140.478424)
		(mid 178.955201 140.551647)
		(end 179.131977 140.478423)
		(width 0.256)
		(layer "B.Cu")
		(net 536)
	)
	(arc
		(start 177.364212 138.710659)
		(mid 177.290989 138.887436)
		(end 177.364212 139.064213)
		(width 0.256)
		(layer "B.Cu")
		(net 536)
	)
	(arc
		(start 178.778424 140.124871)
		(mid 178.705201 140.301648)
		(end 178.778425 140.478424)
		(width 0.256)
		(layer "B.Cu")
		(net 536)
	)
	(arc
		(start 175.95 137.65)
		(mid 176.126777 137.723223)
		(end 176.303553 137.649999)
		(width 0.256)
		(layer "B.Cu")
		(net 536)
	)
	(arc
		(start 178.155318 137.212446)
		(mid 178.332095 137.139223)
		(end 178.508872 137.212446)
		(width 0.256)
		(layer "B.Cu")
		(net 536)
	)
	(arc
		(start 177.16537 137.141737)
		(mid 177.238593 137.318514)
		(end 177.165369 137.49529)
		(width 0.256)
		(layer "B.Cu")
		(net 536)
	)
	(arc
		(start 178.508872 137.212447)
		(mid 178.582095 137.389224)
		(end 178.508871 137.566)
		(width 0.256)
		(layer "B.Cu")
		(net 536)
	)
	(arc
		(start 179.923085 137.212446)
		(mid 179.996308 137.389223)
		(end 179.923084 137.565999)
		(width 0.256)
		(layer "B.Cu")
		(net 536)
	)
	(arc
		(start 179.48553 140.831977)
		(mid 179.412307 141.008754)
		(end 179.485531 141.18553)
		(width 0.256)
		(layer "B.Cu")
		(net 536)
	)
	(arc
		(start 180.630191 137.919552)
		(mid 180.703414 138.096329)
		(end 180.63019 138.273105)
		(width 0.256)
		(layer "B.Cu")
		(net 536)
	)
	(arc
		(start 176.657106 138.357106)
		(mid 176.833883 138.430329)
		(end 177.010659 138.357105)
		(width 0.256)
		(layer "B.Cu")
		(net 536)
	)
	(arc
		(start 181.337297 138.626658)
		(mid 181.41052 138.803435)
		(end 181.337296 138.980211)
		(width 0.256)
		(layer "B.Cu")
		(net 536)
	)
	(arc
		(start 176.657106 138.003553)
		(mid 176.583883 138.18033)
		(end 176.657106 138.357107)
		(width 0.256)
		(layer "B.Cu")
		(net 536)
	)
	(arc
		(start 180.276637 137.919551)
		(mid 180.453414 137.846328)
		(end 180.63019 137.919552)
		(width 0.256)
		(layer "B.Cu")
		(net 536)
	)
	(arc
		(start 180.983743 138.626657)
		(mid 181.16052 138.553434)
		(end 181.337296 138.626658)
		(width 0.256)
		(layer "B.Cu")
		(net 536)
	)
	(arc
		(start 177.364212 139.064212)
		(mid 177.540989 139.137435)
		(end 177.717765 139.064211)
		(width 0.256)
		(layer "B.Cu")
		(net 536)
	)
	(segment
		(start 187.5 140.5)
		(end 187 141)
		(width 0.256)
		(layer "F.Cu")
		(net 537)
	)
	(segment
		(start 164.8 148.4)
		(end 165.2 148)
		(width 0.256)
		(layer "F.Cu")
		(net 537)
	)
	(via
		(at 164.8 148.4)
		(size 0.45)
		(drill 0.2)
		(layers "F.Cu" "B.Cu")
		(net 537)
	)
	(via
		(at 187 141)
		(size 0.45)
		(drill 0.2)
		(layers "F.Cu" "B.Cu")
		(net 537)
	)
	(segment
		(start 164.399999 146.499999)
		(end 164.4 147.35)
		(width 0.256)
		(layer "B.Cu")
		(net 537)
	)
	(segment
		(start 187.651 143.499)
		(end 188.301 143.499)
		(width 0.256)
		(layer "B.Cu")
		(net 537)
	)
	(segment
		(start 164.4 147.85)
		(end 164.4 147.35)
		(width 0.15)
		(layer "B.Cu")
		(net 537)
	)
	(segment
		(start 164.8 150.9)
		(end 165.5 151.6)
		(width 0.256)
		(layer "B.Cu")
		(net 537)
	)
	(segment
		(start 165.5 151.6)
		(end 165.5 154.15)
		(width 0.256)
		(layer "B.Cu")
		(net 537)
	)
	(segment
		(start 189.55 148.575)
		(end 189.55 147.6)
		(width 0.256)
		(layer "B.Cu")
		(net 537)
	)
	(segment
		(start 187.5 145.55)
		(end 187.5 143.65)
		(width 0.256)
		(layer "B.Cu")
		(net 537)
	)
	(segment
		(start 164.8 148.4)
		(end 164.8 150.9)
		(width 0.256)
		(layer "B.Cu")
		(net 537)
	)
	(segment
		(start 189.55 147.6)
		(end 187.5 145.55)
		(width 0.256)
		(layer "B.Cu")
		(net 537)
	)
	(segment
		(start 187.525 140.475)
		(end 187 141)
		(width 0.256)
		(layer "B.Cu")
		(net 537)
	)
	(segment
		(start 187.5 143.65)
		(end 187.651 143.499)
		(width 0.256)
		(layer "B.Cu")
		(net 537)
	)
	(segment
		(start 188.5 143.3)
		(end 188.5 140.775)
		(width 0.256)
		(layer "B.Cu")
		(net 537)
	)
	(segment
		(start 189.275 149.4)
		(end 188.955963 149.4)
		(width 0.256)
		(layer "B.Cu")
		(net 537)
	)
	(segment
		(start 188.955963 148.85)
		(end 189.275 148.85)
		(width 0.256)
		(layer "B.Cu")
		(net 537)
	)
	(segment
		(start 188.35 155)
		(end 189.55 153.8)
		(width 0.256)
		(layer "B.Cu")
		(net 537)
	)
	(segment
		(start 164.4 148)
		(end 164.8 148.4)
		(width 0.256)
		(layer "B.Cu")
		(net 537)
	)
	(segment
		(start 165.5 154.15)
		(end 166.35 155)
		(width 0.256)
		(layer "B.Cu")
		(net 537)
	)
	(segment
		(start 188.5 140.775)
		(end 188.2 140.475)
		(width 0.256)
		(layer "B.Cu")
		(net 537)
	)
	(segment
		(start 164.4 148)
		(end 164.4 147.85)
		(width 0.256)
		(layer "B.Cu")
		(net 537)
	)
	(segment
		(start 188.955963 149.95)
		(end 189.275 149.95)
		(width 0.256)
		(layer "B.Cu")
		(net 537)
	)
	(segment
		(start 188.301 143.499)
		(end 188.5 143.3)
		(width 0.256)
		(layer "B.Cu")
		(net 537)
	)
	(segment
		(start 188.2 140.475)
		(end 187.525 140.475)
		(width 0.256)
		(layer "B.Cu")
		(net 537)
	)
	(segment
		(start 166.35 155)
		(end 188.35 155)
		(width 0.256)
		(layer "B.Cu")
		(net 537)
	)
	(segment
		(start 189.55 153.8)
		(end 189.55 150.775)
		(width 0.256)
		(layer "B.Cu")
		(net 537)
	)
	(segment
		(start 189.275 150.5)
		(end 188.955963 150.5)
		(width 0.256)
		(layer "B.Cu")
		(net 537)
	)
	(arc
		(start 189.55 150.775)
		(mid 189.469454 150.580546)
		(end 189.275 150.5)
		(width 0.256)
		(layer "B.Cu")
		(net 537)
	)
	(arc
		(start 188.680963 150.225)
		(mid 188.761509 150.030546)
		(end 188.955963 149.95)
		(width 0.256)
		(layer "B.Cu")
		(net 537)
	)
	(arc
		(start 188.955963 150.5)
		(mid 188.761509 150.419454)
		(end 188.680963 150.225)
		(width 0.256)
		(layer "B.Cu")
		(net 537)
	)
	(arc
		(start 188.680963 149.125)
		(mid 188.761509 148.930546)
		(end 188.955963 148.85)
		(width 0.256)
		(layer "B.Cu")
		(net 537)
	)
	(arc
		(start 189.275 148.85)
		(mid 189.469454 148.769454)
		(end 189.55 148.575)
		(width 0.256)
		(layer "B.Cu")
		(net 537)
	)
	(arc
		(start 189.275 149.95)
		(mid 189.469454 149.869454)
		(end 189.55 149.675)
		(width 0.256)
		(layer "B.Cu")
		(net 537)
	)
	(arc
		(start 188.955963 149.4)
		(mid 188.761509 149.319454)
		(end 188.680963 149.125)
		(width 0.256)
		(layer "B.Cu")
		(net 537)
	)
	(arc
		(start 189.55 149.675)
		(mid 189.469454 149.480546)
		(end 189.275 149.4)
		(width 0.256)
		(layer "B.Cu")
		(net 537)
	)
	(segment
		(start 164.8 142.8)
		(end 165.2 143.2)
		(width 0.256)
		(layer "F.Cu")
		(net 538)
	)
	(segment
		(start 191.5 137.5)
		(end 191 138)
		(width 0.256)
		(layer "F.Cu")
		(net 538)
	)
	(via
		(at 164.8 142.8)
		(size 0.45)
		(drill 0.2)
		(layers "F.Cu" "B.Cu")
		(net 538)
	)
	(via
		(at 191 138)
		(size 0.45)
		(drill 0.2)
		(layers "F.Cu" "B.Cu")
		(net 538)
	)
	(segment
		(start 171.225 135.368995)
		(end 171.225 136.731005)
		(width 0.256)
		(layer "B.Cu")
		(net 538)
	)
	(segment
		(start 173.025 136.731005)
		(end 173.025 135.368995)
		(width 0.256)
		(layer "B.Cu")
		(net 538)
	)
	(segment
		(start 175.425 136.731005)
		(end 175.425 135.368995)
		(width 0.256)
		(layer "B.Cu")
		(net 538)
	)
	(segment
		(start 171.825 136.731005)
		(end 171.825 135.368995)
		(width 0.256)
		(layer "B.Cu")
		(net 538)
	)
	(segment
		(start 173.625 135.368995)
		(end 173.625 136.731005)
		(width 0.256)
		(layer "B.Cu")
		(net 538)
	)
	(segment
		(start 164.399997 143.199999)
		(end 164.399997 143.349999)
		(width 0.256)
		(layer "B.Cu")
		(net 538)
	)
	(segment
		(start 174.825 135.368995)
		(end 174.825 136.731005)
		(width 0.256)
		(layer "B.Cu")
		(net 538)
	)
	(segment
		(start 164.4 143.350002)
		(end 164.399997 143.349999)
		(width 0.15)
		(layer "B.Cu")
		(net 538)
	)
	(segment
		(start 172.425 135.368995)
		(end 172.425 136.731005)
		(width 0.256)
		(layer "B.Cu")
		(net 538)
	)
	(segment
		(start 164.799996 142.8)
		(end 164.399997 143.199999)
		(width 0.256)
		(layer "B.Cu")
		(net 538)
	)
	(segment
		(start 187.197 138.547)
		(end 187.5 138.85)
		(width 0.256)
		(layer "B.Cu")
		(net 538)
	)
	(segment
		(start 168.65 136.05)
		(end 169.125 136.05)
		(width 0.256)
		(layer "B.Cu")
		(net 538)
	)
	(segment
		(start 183.53 136.55)
		(end 184.39 137.41)
		(width 0.256)
		(layer "B.Cu")
		(net 538)
	)
	(segment
		(start 177.6 136.55)
		(end 183.53 136.55)
		(width 0.256)
		(layer "B.Cu")
		(net 538)
	)
	(segment
		(start 174.225 136.731005)
		(end 174.225 135.368995)
		(width 0.256)
		(layer "B.Cu")
		(net 538)
	)
	(segment
		(start 163.999999 144.250001)
		(end 164.4 143.85)
		(width 0.256)
		(layer "B.Cu")
		(net 538)
	)
	(segment
		(start 169.425 135.75)
		(end 169.425 135.368995)
		(width 0.256)
		(layer "B.Cu")
		(net 538)
	)
	(segment
		(start 177.1 136.05)
		(end 177.6 136.55)
		(width 0.256)
		(layer "B.Cu")
		(net 538)
	)
	(segment
		(start 164.8 139.9)
		(end 168.65 136.05)
		(width 0.256)
		(layer "B.Cu")
		(net 538)
	)
	(segment
		(start 163.999999 144.699999)
		(end 163.999999 144.250001)
		(width 0.256)
		(layer "B.Cu")
		(net 538)
	)
	(segment
		(start 191.547 138.547)
		(end 191 138)
		(width 0.256)
		(layer "B.Cu")
		(net 538)
	)
	(segment
		(start 164.8 142.8)
		(end 164.8 139.9)
		(width 0.256)
		(layer "B.Cu")
		(net 538)
	)
	(segment
		(start 191.547 139.153)
		(end 191.547 138.547)
		(width 0.256)
		(layer "B.Cu")
		(net 538)
	)
	(segment
		(start 187.5 138.85)
		(end 187.5 139.2)
		(width 0.256)
		(layer "B.Cu")
		(net 538)
	)
	(segment
		(start 191.2 139.5)
		(end 191.547 139.153)
		(width 0.256)
		(layer "B.Cu")
		(net 538)
	)
	(segment
		(start 170.025 135.368995)
		(end 170.025 136.731005)
		(width 0.256)
		(layer "B.Cu")
		(net 538)
	)
	(segment
		(start 164.4 143.85)
		(end 164.4 143.350002)
		(width 0.15)
		(layer "B.Cu")
		(net 538)
	)
	(segment
		(start 187.8 139.5)
		(end 191.2 139.5)
		(width 0.256)
		(layer "B.Cu")
		(net 538)
	)
	(segment
		(start 176.025 135.368995)
		(end 176.025 135.75)
		(width 0.256)
		(layer "B.Cu")
		(net 538)
	)
	(segment
		(start 184.39 138.19)
		(end 184.747 138.547)
		(width 0.256)
		(layer "B.Cu")
		(net 538)
	)
	(segment
		(start 170.625 136.731005)
		(end 170.625 135.368995)
		(width 0.256)
		(layer "B.Cu")
		(net 538)
	)
	(segment
		(start 176.325 136.05)
		(end 177.1 136.05)
		(width 0.256)
		(layer "B.Cu")
		(net 538)
	)
	(segment
		(start 187.5 139.2)
		(end 187.8 139.5)
		(width 0.256)
		(layer "B.Cu")
		(net 538)
	)
	(segment
		(start 184.39 137.41)
		(end 184.39 138.19)
		(width 0.256)
		(layer "B.Cu")
		(net 538)
	)
	(segment
		(start 184.747 138.547)
		(end 187.197 138.547)
		(width 0.256)
		(layer "B.Cu")
		(net 538)
	)
	(arc
		(start 172.725 137.031005)
		(mid 172.937132 136.943137)
		(end 173.025 136.731005)
		(width 0.256)
		(layer "B.Cu")
		(net 538)
	)
	(arc
		(start 174.525 135.068995)
		(mid 174.737132 135.156863)
		(end 174.825 135.368995)
		(width 0.256)
		(layer "B.Cu")
		(net 538)
	)
	(arc
		(start 175.425 135.368995)
		(mid 175.512868 135.156863)
		(end 175.725 135.068995)
		(width 0.256)
		(layer "B.Cu")
		(net 538)
	)
	(arc
		(start 170.625 135.368995)
		(mid 170.712868 135.156863)
		(end 170.925 135.068995)
		(width 0.256)
		(layer "B.Cu")
		(net 538)
	)
	(arc
		(start 171.825 135.368995)
		(mid 171.912868 135.156863)
		(end 172.125 135.068995)
		(width 0.256)
		(layer "B.Cu")
		(net 538)
	)
	(arc
		(start 170.025 136.731005)
		(mid 170.112868 136.943137)
		(end 170.325 137.031005)
		(width 0.256)
		(layer "B.Cu")
		(net 538)
	)
	(arc
		(start 176.025 135.75)
		(mid 176.112868 135.962132)
		(end 176.325 136.05)
		(width 0.256)
		(layer "B.Cu")
		(net 538)
	)
	(arc
		(start 172.125 135.068995)
		(mid 172.337132 135.156863)
		(end 172.425 135.368995)
		(width 0.256)
		(layer "B.Cu")
		(net 538)
	)
	(arc
		(start 172.425 136.731005)
		(mid 172.512868 136.943137)
		(end 172.725 137.031005)
		(width 0.256)
		(layer "B.Cu")
		(net 538)
	)
	(arc
		(start 170.925 135.068995)
		(mid 171.137132 135.156863)
		(end 171.225 135.368995)
		(width 0.256)
		(layer "B.Cu")
		(net 538)
	)
	(arc
		(start 169.725 135.068995)
		(mid 169.937132 135.156863)
		(end 170.025 135.368995)
		(width 0.256)
		(layer "B.Cu")
		(net 538)
	)
	(arc
		(start 174.225 135.368995)
		(mid 174.312868 135.156863)
		(end 174.525 135.068995)
		(width 0.256)
		(layer "B.Cu")
		(net 538)
	)
	(arc
		(start 169.425 135.368995)
		(mid 169.512868 135.156863)
		(end 169.725 135.068995)
		(width 0.256)
		(layer "B.Cu")
		(net 538)
	)
	(arc
		(start 173.025 135.368995)
		(mid 173.112868 135.156863)
		(end 173.325 135.068995)
		(width 0.256)
		(layer "B.Cu")
		(net 538)
	)
	(arc
		(start 175.125 137.031005)
		(mid 175.337132 136.943137)
		(end 175.425 136.731005)
		(width 0.256)
		(layer "B.Cu")
		(net 538)
	)
	(arc
		(start 173.625 136.731005)
		(mid 173.712868 136.943137)
		(end 173.925 137.031005)
		(width 0.256)
		(layer "B.Cu")
		(net 538)
	)
	(arc
		(start 171.225 136.731005)
		(mid 171.312868 136.943137)
		(end 171.525 137.031005)
		(width 0.256)
		(layer "B.Cu")
		(net 538)
	)
	(arc
		(start 171.525 137.031005)
		(mid 171.737132 136.943137)
		(end 171.825 136.731005)
		(width 0.256)
		(layer "B.Cu")
		(net 538)
	)
	(arc
		(start 174.825 136.731005)
		(mid 174.912868 136.943137)
		(end 175.125 137.031005)
		(width 0.256)
		(layer "B.Cu")
		(net 538)
	)
	(arc
		(start 169.125 136.05)
		(mid 169.337132 135.962132)
		(end 169.425 135.75)
		(width 0.256)
		(layer "B.Cu")
		(net 538)
	)
	(arc
		(start 173.325 135.068995)
		(mid 173.537132 135.156863)
		(end 173.625 135.368995)
		(width 0.256)
		(layer "B.Cu")
		(net 538)
	)
	(arc
		(start 175.725 135.068995)
		(mid 175.937132 135.156863)
		(end 176.025 135.368995)
		(width 0.256)
		(layer "B.Cu")
		(net 538)
	)
	(arc
		(start 170.325 137.031005)
		(mid 170.537132 136.943137)
		(end 170.625 136.731005)
		(width 0.256)
		(layer "B.Cu")
		(net 538)
	)
	(arc
		(start 173.925 137.031005)
		(mid 174.137132 136.943137)
		(end 174.225 136.731005)
		(width 0.256)
		(layer "B.Cu")
		(net 538)
	)
	(segment
		(start 190.5 139.5)
		(end 190 140)
		(width 0.256)
		(layer "F.Cu")
		(net 539)
	)
	(segment
		(start 164 148.4)
		(end 164.4 148)
		(width 0.256)
		(layer "F.Cu")
		(net 539)
	)
	(via
		(at 164 148.4)
		(size 0.45)
		(drill 0.2)
		(layers "F.Cu" "B.Cu")
		(net 539)
	)
	(via
		(at 190 140)
		(size 0.45)
		(drill 0.2)
		(layers "F.Cu" "B.Cu")
		(net 539)
	)
	(segment
		(start 163.599999 146.499999)
		(end 163.546998 146.553)
		(width 0.256)
		(layer "B.Cu")
		(net 539)
	)
	(segment
		(start 163.8 151.1)
		(end 164.65 151.95)
		(width 0.256)
		(layer "B.Cu")
		(net 539)
	)
	(segment
		(start 166.05 155.8)
		(end 188.7 155.8)
		(width 0.256)
		(layer "B.Cu")
		(net 539)
	)
	(segment
		(start 190.193029 150.8)
		(end 190.3 150.8)
		(width 0.256)
		(layer "B.Cu")
		(net 539)
	)
	(segment
		(start 164.65 151.95)
		(end 164.65 154.4)
		(width 0.256)
		(layer "B.Cu")
		(net 539)
	)
	(segment
		(start 190.3 144.1)
		(end 189.5 143.3)
		(width 0.256)
		(layer "B.Cu")
		(net 539)
	)
	(segment
		(start 190.3 154.2)
		(end 190.3 152.3)
		(width 0.256)
		(layer "B.Cu")
		(net 539)
	)
	(segment
		(start 163.546998 147.946998)
		(end 164 148.4)
		(width 0.256)
		(layer "B.Cu")
		(net 539)
	)
	(segment
		(start 189.5 140.5)
		(end 190 140)
		(width 0.256)
		(layer "B.Cu")
		(net 539)
	)
	(segment
		(start 190.6 152)
		(end 190.863942 152)
		(width 0.256)
		(layer "B.Cu")
		(net 539)
	)
	(segment
		(start 163.8 148.6)
		(end 163.8 151.1)
		(width 0.256)
		(layer "B.Cu")
		(net 539)
	)
	(segment
		(start 190.086058 151.293029)
		(end 190.086058 150.906971)
		(width 0.256)
		(layer "B.Cu")
		(net 539)
	)
	(segment
		(start 190.3 150.8)
		(end 190.863942 150.8)
		(width 0.256)
		(layer "B.Cu")
		(net 539)
	)
	(segment
		(start 190.3 149.9)
		(end 190.3 144.1)
		(width 0.256)
		(layer "B.Cu")
		(net 539)
	)
	(segment
		(start 163.546998 146.553)
		(end 163.546998 147.946998)
		(width 0.256)
		(layer "B.Cu")
		(net 539)
	)
	(segment
		(start 190.193029 151.4)
		(end 190.863942 151.4)
		(width 0.256)
		(layer "B.Cu")
		(net 539)
	)
	(segment
		(start 164.65 154.4)
		(end 166.05 155.8)
		(width 0.256)
		(layer "B.Cu")
		(net 539)
	)
	(segment
		(start 189.5 143.3)
		(end 189.5 140.5)
		(width 0.256)
		(layer "B.Cu")
		(net 539)
	)
	(segment
		(start 164 148.4)
		(end 163.8 148.6)
		(width 0.256)
		(layer "B.Cu")
		(net 539)
	)
	(segment
		(start 188.7 155.8)
		(end 190.3 154.2)
		(width 0.256)
		(layer "B.Cu")
		(net 539)
	)
	(segment
		(start 190.863942 150.2)
		(end 190.6 150.2)
		(width 0.256)
		(layer "B.Cu")
		(net 539)
	)
	(arc
		(start 190.863942 152)
		(mid 191.076074 151.912132)
		(end 191.163942 151.7)
		(width 0.256)
		(layer "B.Cu")
		(net 539)
	)
	(arc
		(start 190.863942 150.8)
		(mid 191.076074 150.712132)
		(end 191.163942 150.5)
		(width 0.256)
		(layer "B.Cu")
		(net 539)
	)
	(arc
		(start 191.163942 150.5)
		(mid 191.076074 150.287868)
		(end 190.863942 150.2)
		(width 0.256)
		(layer "B.Cu")
		(net 539)
	)
	(arc
		(start 191.163942 151.7)
		(mid 191.076074 151.487868)
		(end 190.863942 151.4)
		(width 0.256)
		(layer "B.Cu")
		(net 539)
	)
	(arc
		(start 190.3 152.3)
		(mid 190.387868 152.087868)
		(end 190.6 152)
		(width 0.256)
		(layer "B.Cu")
		(net 539)
	)
	(arc
		(start 190.086058 150.906971)
		(mid 190.117389 150.831331)
		(end 190.193029 150.8)
		(width 0.256)
		(layer "B.Cu")
		(net 539)
	)
	(arc
		(start 190.193029 151.4)
		(mid 190.117389 151.368669)
		(end 190.086058 151.293029)
		(width 0.256)
		(layer "B.Cu")
		(net 539)
	)
	(arc
		(start 190.6 150.2)
		(mid 190.387868 150.112132)
		(end 190.3 149.9)
		(width 0.256)
		(layer "B.Cu")
		(net 539)
	)
	(segment
		(start 190.00665 138.99335)
		(end 190.00665 139.018512)
		(width 0.256)
		(layer "F.Cu")
		(net 540)
	)
	(segment
		(start 190.5 138.5)
		(end 190.00665 138.99335)
		(width 0.256)
		(layer "F.Cu")
		(net 540)
	)
	(segment
		(start 190.5 138.5)
		(end 190 139)
		(width 0.256)
		(layer "F.Cu")
		(net 540)
	)
	(segment
		(start 164.8 143.6)
		(end 165.2 144)
		(width 0.256)
		(layer "F.Cu")
		(net 540)
	)
	(via
		(at 164.8 143.6)
		(size 0.45)
		(drill 0.2)
		(layers "F.Cu" "B.Cu")
		(net 540)
	)
	(via
		(at 190.00665 139.018512)
		(size 0.45)
		(drill 0.2)
		(layers "F.Cu" "B.Cu")
		(net 540)
	)
	(segment
		(start 164.399999 144.353461)
		(end 164.8 143.95346)
		(width 0.256)
		(layer "B.Cu")
		(net 540)
	)
	(segment
		(start 164.8 143.95346)
		(end 164.8 143.6)
		(width 0.256)
		(layer "B.Cu")
		(net 540)
	)
	(segment
		(start 164.399999 144.699999)
		(end 164.399999 144.353461)
		(width 0.256)
		(layer "B.Cu")
		(net 540)
	)
	(segment
		(start 166.038918 136.025125)
		(end 166.038918 136.025126)
		(width 0.157)
		(layer "In7.Cu")
		(net 540)
	)
	(segment
		(start 164.4 138.8)
		(end 164.4 142.65)
		(width 0.157)
		(layer "In7.Cu")
		(net 540)
	)
	(segment
		(start 167.849999 135.350001)
		(end 167.084193 136.115804)
		(width 0.157)
		(layer "In7.Cu")
		(net 540)
	)
	(segment
		(start 167.084193 136.434002)
		(end 167.493074 136.842883)
		(width 0.157)
		(layer "In7.Cu")
		(net 540)
	)
	(segment
		(start 165.084319 136.979723)
		(end 166.220276 138.115681)
		(width 0.157)
		(layer "In7.Cu")
		(net 540)
	)
	(segment
		(start 167.493074 136.842883)
		(end 167.493074 136.842882)
		(width 0.157)
		(layer "In7.Cu")
		(net 540)
	)
	(segment
		(start 165.175 138.025)
		(end 164.4 138.8)
		(width 0.157)
		(layer "In7.Cu")
		(net 540)
	)
	(segment
		(start 166.538477 137.797481)
		(end 165.402519 136.661524)
		(width 0.157)
		(layer "In7.Cu")
		(net 540)
	)
	(segment
		(start 180.550001 135.350001)
		(end 167.849999 135.350001)
		(width 0.157)
		(layer "In7.Cu")
		(net 540)
	)
	(segment
		(start 189.488139 138.500001)
		(end 183.700001 138.500001)
		(width 0.157)
		(layer "In7.Cu")
		(net 540)
	)
	(segment
		(start 165.402519 136.661524)
		(end 165.402519 136.661525)
		(width 0.157)
		(layer "In7.Cu")
		(net 540)
	)
	(segment
		(start 165.720718 136.343324)
		(end 166.856675 137.479282)
		(width 0.157)
		(layer "In7.Cu")
		(net 540)
	)
	(segment
		(start 164.4 143.2)
		(end 164.4 142.95)
		(width 0.157)
		(layer "In7.Cu")
		(net 540)
	)
	(segment
		(start 190.00665 139.018512)
		(end 189.488139 138.500001)
		(width 0.157)
		(layer "In7.Cu")
		(net 540)
	)
	(segment
		(start 183.700001 138.500001)
		(end 180.550001 135.350001)
		(width 0.157)
		(layer "In7.Cu")
		(net 540)
	)
	(segment
		(start 165.902078 138.43388)
		(end 165.493198 138.025)
		(width 0.157)
		(layer "In7.Cu")
		(net 540)
	)
	(segment
		(start 166.220276 138.115681)
		(end 166.220276 138.11568)
		(width 0.157)
		(layer "In7.Cu")
		(net 540)
	)
	(segment
		(start 167.174876 137.161082)
		(end 166.038918 136.025125)
		(width 0.157)
		(layer "In7.Cu")
		(net 540)
	)
	(segment
		(start 164.4 142.95)
		(end 164.4 142.65)
		(width 0.15)
		(layer "In7.Cu")
		(net 540)
	)
	(segment
		(start 164.8 143.6)
		(end 164.4 143.2)
		(width 0.157)
		(layer "In7.Cu")
		(net 540)
	)
	(segment
		(start 166.856675 137.479282)
		(end 166.856675 137.479281)
		(width 0.157)
		(layer "In7.Cu")
		(net 540)
	)
	(arc
		(start 166.220276 138.43388)
		(mid 166.061177 138.499781)
		(end 165.902078 138.43388)
		(width 0.157)
		(layer "In7.Cu")
		(net 540)
	)
	(arc
		(start 165.720718 136.025126)
		(mid 165.654817 136.184225)
		(end 165.720718 136.343324)
		(width 0.157)
		(layer "In7.Cu")
		(net 540)
	)
	(arc
		(start 166.856675 137.797481)
		(mid 166.697576 137.863382)
		(end 166.538477 137.797481)
		(width 0.157)
		(layer "In7.Cu")
		(net 540)
	)
	(arc
		(start 167.493074 136.842882)
		(mid 167.558975 137.001982)
		(end 167.493074 137.161082)
		(width 0.157)
		(layer "In7.Cu")
		(net 540)
	)
	(arc
		(start 166.856675 137.479281)
		(mid 166.922576 137.638381)
		(end 166.856675 137.797481)
		(width 0.157)
		(layer "In7.Cu")
		(net 540)
	)
	(arc
		(start 167.493074 137.161082)
		(mid 167.333975 137.226983)
		(end 167.174876 137.161082)
		(width 0.157)
		(layer "In7.Cu")
		(net 540)
	)
	(arc
		(start 165.402519 136.661525)
		(mid 165.24342 136.595623)
		(end 165.084319 136.661525)
		(width 0.157)
		(layer "In7.Cu")
		(net 540)
	)
	(arc
		(start 165.493198 138.025)
		(mid 165.334099 137.959099)
		(end 165.175 138.025)
		(width 0.157)
		(layer "In7.Cu")
		(net 540)
	)
	(arc
		(start 167.084193 136.115804)
		(mid 167.018292 136.274903)
		(end 167.084193 136.434002)
		(width 0.157)
		(layer "In7.Cu")
		(net 540)
	)
	(arc
		(start 165.084319 136.661525)
		(mid 165.018418 136.820624)
		(end 165.084319 136.979723)
		(width 0.157)
		(layer "In7.Cu")
		(net 540)
	)
	(arc
		(start 166.038918 136.025126)
		(mid 165.879819 135.959224)
		(end 165.720718 136.025126)
		(width 0.157)
		(layer "In7.Cu")
		(net 540)
	)
	(arc
		(start 166.220276 138.11568)
		(mid 166.286177 138.27478)
		(end 166.220276 138.43388)
		(width 0.157)
		(layer "In7.Cu")
		(net 540)
	)
	(segment
		(start 188.5 137.5)
		(end 188 138)
		(width 0.256)
		(layer "F.Cu")
		(net 541)
	)
	(segment
		(start 168.4 147.2)
		(end 168 147.6)
		(width 0.256)
		(layer "F.Cu")
		(net 541)
	)
	(via
		(at 188 138)
		(size 0.45)
		(drill 0.2)
		(layers "F.Cu" "B.Cu")
		(net 541)
	)
	(via
		(at 168 147.6)
		(size 0.45)
		(drill 0.2)
		(layers "F.Cu" "B.Cu")
		(net 541)
	)
	(segment
		(start 167.599999 146.499999)
		(end 167.599999 146.949999)
		(width 0.256)
		(layer "B.Cu")
		(net 541)
	)
	(segment
		(start 167.599999 146.949999)
		(end 168 147.35)
		(width 0.256)
		(layer "B.Cu")
		(net 541)
	)
	(segment
		(start 168 147.35)
		(end 168 147.6)
		(width 0.256)
		(layer "B.Cu")
		(net 541)
	)
	(segment
		(start 192.25 138.5)
		(end 192.5 138.75)
		(width 0.157)
		(layer "In7.Cu")
		(net 541)
	)
	(segment
		(start 188.5 137.5)
		(end 190.25 137.5)
		(width 0.157)
		(layer "In7.Cu")
		(net 541)
	)
	(segment
		(start 190.5 138.3)
		(end 190.7 138.5)
		(width 0.157)
		(layer "In7.Cu")
		(net 541)
	)
	(segment
		(start 188 138)
		(end 188.5 137.5)
		(width 0.157)
		(layer "In7.Cu")
		(net 541)
	)
	(segment
		(start 180.05 151.55)
		(end 174.8 146.3)
		(width 0.157)
		(layer "In7.Cu")
		(net 541)
	)
	(segment
		(start 171.5 146.475)
		(end 171.5 146.484851)
		(width 0.157)
		(layer "In7.Cu")
		(net 541)
	)
	(segment
		(start 174.8 146.3)
		(end 171.675 146.3)
		(width 0.157)
		(layer "In7.Cu")
		(net 541)
	)
	(segment
		(start 192.5 138.75)
		(end 192.5 144.25)
		(width 0.157)
		(layer "In7.Cu")
		(net 541)
	)
	(segment
		(start 171.15 146.484851)
		(end 171.15 146.475)
		(width 0.157)
		(layer "In7.Cu")
		(net 541)
	)
	(segment
		(start 188.9 151.55)
		(end 180.05 151.55)
		(width 0.157)
		(layer "In7.Cu")
		(net 541)
	)
	(segment
		(start 193.05 147.4)
		(end 188.9 151.55)
		(width 0.157)
		(layer "In7.Cu")
		(net 541)
	)
	(segment
		(start 190.25 137.5)
		(end 190.5 137.75)
		(width 0.157)
		(layer "In7.Cu")
		(net 541)
	)
	(segment
		(start 190.5 137.75)
		(end 190.5 138.3)
		(width 0.157)
		(layer "In7.Cu")
		(net 541)
	)
	(segment
		(start 190.7 138.5)
		(end 192.25 138.5)
		(width 0.157)
		(layer "In7.Cu")
		(net 541)
	)
	(segment
		(start 193.05 144.8)
		(end 193.05 147.4)
		(width 0.157)
		(layer "In7.Cu")
		(net 541)
	)
	(segment
		(start 169.300001 146.3)
		(end 168 147.6)
		(width 0.157)
		(layer "In7.Cu")
		(net 541)
	)
	(segment
		(start 192.5 144.25)
		(end 193.05 144.8)
		(width 0.157)
		(layer "In7.Cu")
		(net 541)
	)
	(segment
		(start 170.975 146.3)
		(end 169.300001 146.3)
		(width 0.157)
		(layer "In7.Cu")
		(net 541)
	)
	(arc
		(start 171.325 146.659851)
		(mid 171.201256 146.608595)
		(end 171.15 146.484851)
		(width 0.157)
		(layer "In7.Cu")
		(net 541)
	)
	(arc
		(start 171.15 146.475)
		(mid 171.098744 146.351256)
		(end 170.975 146.3)
		(width 0.157)
		(layer "In7.Cu")
		(net 541)
	)
	(arc
		(start 171.5 146.484851)
		(mid 171.448744 146.608595)
		(end 171.325 146.659851)
		(width 0.157)
		(layer "In7.Cu")
		(net 541)
	)
	(arc
		(start 171.675 146.3)
		(mid 171.551256 146.351256)
		(end 171.5 146.475)
		(width 0.157)
		(layer "In7.Cu")
		(net 541)
	)
	(segment
		(start 189.5 137.5)
		(end 189 138)
		(width 0.256)
		(layer "F.Cu")
		(net 542)
	)
	(segment
		(start 164.8 147.6)
		(end 165.2 147.2)
		(width 0.256)
		(layer "F.Cu")
		(net 542)
	)
	(segment
		(start 189.5 137.5)
		(end 189 138)
		(width 0.256)
		(layer "F.Cu")
		(net 542)
	)
	(via
		(at 164.8 147.6)
		(size 0.45)
		(drill 0.2)
		(layers "F.Cu" "B.Cu")
		(net 542)
	)
	(via
		(at 189 138)
		(size 0.45)
		(drill 0.2)
		(layers "F.Cu" "B.Cu")
		(net 542)
	)
	(segment
		(start 164.799999 146.499999)
		(end 164.8 147.6)
		(width 0.256)
		(layer "B.Cu")
		(net 542)
	)
	(segment
		(start 169.028499 134.356731)
		(end 169.028499 134.871501)
		(width 0.157)
		(layer "In5.Cu")
		(net 542)
	)
	(segment
		(start 189.500001 136.450001)
		(end 189.500001 137.500001)
		(width 0.157)
		(layer "In5.Cu")
		(net 542)
	)
	(segment
		(start 163.650001 148.000001)
		(end 161.250001 145.600001)
		(width 0.157)
		(layer "In5.Cu")
		(net 542)
	)
	(segment
		(start 168.578499 135.836271)
		(end 168.578499 134.356731)
		(width 0.157)
		(layer "In5.Cu")
		(net 542)
	)
	(segment
		(start 163.811 148)
		(end 164.162 148)
		(width 0.15)
		(layer "In5.Cu")
		(net 542)
	)
	(segment
		(start 164.399999 148)
		(end 164.162 148)
		(width 0.157)
		(layer "In5.Cu")
		(net 542)
	)
	(segment
		(start 163.811 148)
		(end 163.650001 148.000001)
		(width 0.157)
		(layer "In5.Cu")
		(net 542)
	)
	(segment
		(start 169.253499 135.096501)
		(end 188.146501 135.096501)
		(width 0.157)
		(layer "In5.Cu")
		(net 542)
	)
	(segment
		(start 167.203501 135.096501)
		(end 167.903499 135.096501)
		(width 0.157)
		(layer "In5.Cu")
		(net 542)
	)
	(segment
		(start 164.8 147.6)
		(end 164.399999 148)
		(width 0.157)
		(layer "In5.Cu")
		(net 542)
	)
	(segment
		(start 189.5 137.5)
		(end 189 138)
		(width 0.157)
		(layer "In5.Cu")
		(net 542)
	)
	(segment
		(start 189.500001 137.500001)
		(end 189 138)
		(width 0.157)
		(layer "In5.Cu")
		(net 542)
	)
	(segment
		(start 161.250001 145.600001)
		(end 161.250001 141.050001)
		(width 0.157)
		(layer "In5.Cu")
		(net 542)
	)
	(segment
		(start 168.128499 135.321501)
		(end 168.128499 135.836271)
		(width 0.157)
		(layer "In5.Cu")
		(net 542)
	)
	(segment
		(start 161.250001 141.050001)
		(end 167.203501 135.096501)
		(width 0.157)
		(layer "In5.Cu")
		(net 542)
	)
	(segment
		(start 188.146501 135.096501)
		(end 189.500001 136.450001)
		(width 0.157)
		(layer "In5.Cu")
		(net 542)
	)
	(arc
		(start 168.353499 136.061271)
		(mid 168.512598 135.99537)
		(end 168.578499 135.836271)
		(width 0.157)
		(layer "In5.Cu")
		(net 542)
	)
	(arc
		(start 167.903499 135.096501)
		(mid 168.062598 135.162402)
		(end 168.128499 135.321501)
		(width 0.157)
		(layer "In5.Cu")
		(net 542)
	)
	(arc
		(start 169.028499 134.871501)
		(mid 169.0944 135.0306)
		(end 169.253499 135.096501)
		(width 0.157)
		(layer "In5.Cu")
		(net 542)
	)
	(arc
		(start 168.803499 134.131731)
		(mid 168.962598 134.197632)
		(end 169.028499 134.356731)
		(width 0.157)
		(layer "In5.Cu")
		(net 542)
	)
	(arc
		(start 168.128499 135.836271)
		(mid 168.1944 135.99537)
		(end 168.353499 136.061271)
		(width 0.157)
		(layer "In5.Cu")
		(net 542)
	)
	(arc
		(start 168.578499 134.356731)
		(mid 168.6444 134.197632)
		(end 168.803499 134.131731)
		(width 0.157)
		(layer "In5.Cu")
		(net 542)
	)
	(segment
		(start 166.4 147.6)
		(end 166.8 147.2)
		(width 0.256)
		(layer "F.Cu")
		(net 543)
	)
	(segment
		(start 185.5 137.5)
		(end 185 137)
		(width 0.256)
		(layer "F.Cu")
		(net 543)
	)
	(via
		(at 166.4 147.6)
		(size 0.45)
		(drill 0.2)
		(layers "F.Cu" "B.Cu")
		(net 543)
	)
	(via
		(at 185 137)
		(size 0.45)
		(drill 0.2)
		(layers "F.Cu" "B.Cu")
		(net 543)
	)
	(segment
		(start 166.599999 147.400501)
		(end 166.4005 147.6)
		(width 0.256)
		(layer "B.Cu")
		(net 543)
	)
	(segment
		(start 166.599999 146.499999)
		(end 166.599999 147.400501)
		(width 0.256)
		(layer "B.Cu")
		(net 543)
	)
	(segment
		(start 170.625 137.775)
		(end 170.625 137.338706)
		(width 0.157)
		(layer "In5.Cu")
		(net 543)
	)
	(segment
		(start 163.2 146.15)
		(end 164.95 146.15)
		(width 0.157)
		(layer "In5.Cu")
		(net 543)
	)
	(segment
		(start 167.925 138.611294)
		(end 167.925 137.338706)
		(width 0.157)
		(layer "In5.Cu")
		(net 543)
	)
	(segment
		(start 183.65 137)
		(end 182.65 138)
		(width 0.157)
		(layer "In5.Cu")
		(net 543)
	)
	(segment
		(start 169.275 137.338706)
		(end 169.275 138.611294)
		(width 0.157)
		(layer "In5.Cu")
		(net 543)
	)
	(segment
		(start 167.25 138)
		(end 166.3 138)
		(width 0.157)
		(layer "In5.Cu")
		(net 543)
	)
	(segment
		(start 167.475 137.338706)
		(end 167.475 137.775)
		(width 0.157)
		(layer "In5.Cu")
		(net 543)
	)
	(segment
		(start 185 137)
		(end 183.65 137)
		(width 0.157)
		(layer "In5.Cu")
		(net 543)
	)
	(segment
		(start 162.6 141.7)
		(end 162.6 145.55)
		(width 0.157)
		(layer "In5.Cu")
		(net 543)
	)
	(segment
		(start 169.725 138.611294)
		(end 169.725 137.338706)
		(width 0.157)
		(layer "In5.Cu")
		(net 543)
	)
	(segment
		(start 182.65 138)
		(end 170.85 138)
		(width 0.157)
		(layer "In5.Cu")
		(net 543)
	)
	(segment
		(start 170.175 137.338706)
		(end 170.175 138.611294)
		(width 0.157)
		(layer "In5.Cu")
		(net 543)
	)
	(segment
		(start 164.95 146.15)
		(end 166.4 147.6)
		(width 0.157)
		(layer "In5.Cu")
		(net 543)
	)
	(segment
		(start 168.825 138.611294)
		(end 168.825 137.338706)
		(width 0.157)
		(layer "In5.Cu")
		(net 543)
	)
	(segment
		(start 168.375 137.338706)
		(end 168.375 138.611294)
		(width 0.157)
		(layer "In5.Cu")
		(net 543)
	)
	(segment
		(start 162.6 145.55)
		(end 163.2 146.15)
		(width 0.157)
		(layer "In5.Cu")
		(net 543)
	)
	(segment
		(start 166.3 138)
		(end 162.6 141.7)
		(width 0.157)
		(layer "In5.Cu")
		(net 543)
	)
	(arc
		(start 167.7 137.113706)
		(mid 167.540901 137.179607)
		(end 167.475 137.338706)
		(width 0.157)
		(layer "In5.Cu")
		(net 543)
	)
	(arc
		(start 170.85 138)
		(mid 170.690901 137.934099)
		(end 170.625 137.775)
		(width 0.157)
		(layer "In5.Cu")
		(net 543)
	)
	(arc
		(start 169.5 137.113706)
		(mid 169.340901 137.179607)
		(end 169.275 137.338706)
		(width 0.157)
		(layer "In5.Cu")
		(net 543)
	)
	(arc
		(start 168.825 137.338706)
		(mid 168.759099 137.179607)
		(end 168.6 137.113706)
		(width 0.157)
		(layer "In5.Cu")
		(net 543)
	)
	(arc
		(start 170.4 137.113706)
		(mid 170.240901 137.179607)
		(end 170.175 137.338706)
		(width 0.157)
		(layer "In5.Cu")
		(net 543)
	)
	(arc
		(start 169.95 138.836294)
		(mid 169.790901 138.770393)
		(end 169.725 138.611294)
		(width 0.157)
		(layer "In5.Cu")
		(net 543)
	)
	(arc
		(start 168.15 138.836294)
		(mid 167.990901 138.770393)
		(end 167.925 138.611294)
		(width 0.157)
		(layer "In5.Cu")
		(net 543)
	)
	(arc
		(start 167.475 137.775)
		(mid 167.409099 137.934099)
		(end 167.25 138)
		(width 0.157)
		(layer "In5.Cu")
		(net 543)
	)
	(arc
		(start 169.275 138.611294)
		(mid 169.209099 138.770393)
		(end 169.05 138.836294)
		(width 0.157)
		(layer "In5.Cu")
		(net 543)
	)
	(arc
		(start 168.6 137.113706)
		(mid 168.440901 137.179607)
		(end 168.375 137.338706)
		(width 0.157)
		(layer "In5.Cu")
		(net 543)
	)
	(arc
		(start 170.175 138.611294)
		(mid 170.109099 138.770393)
		(end 169.95 138.836294)
		(width 0.157)
		(layer "In5.Cu")
		(net 543)
	)
	(arc
		(start 169.05 138.836294)
		(mid 168.890901 138.770393)
		(end 168.825 138.611294)
		(width 0.157)
		(layer "In5.Cu")
		(net 543)
	)
	(arc
		(start 170.625 137.338706)
		(mid 170.559099 137.179607)
		(end 170.4 137.113706)
		(width 0.157)
		(layer "In5.Cu")
		(net 543)
	)
	(arc
		(start 167.925 137.338706)
		(mid 167.859099 137.179607)
		(end 167.7 137.113706)
		(width 0.157)
		(layer "In5.Cu")
		(net 543)
	)
	(arc
		(start 168.375 138.611294)
		(mid 168.309099 138.770393)
		(end 168.15 138.836294)
		(width 0.157)
		(layer "In5.Cu")
		(net 543)
	)
	(arc
		(start 169.725 137.338706)
		(mid 169.659099 137.179607)
		(end 169.5 137.113706)
		(width 0.157)
		(layer "In5.Cu")
		(net 543)
	)
	(segment
		(start 186 137)
		(end 186.5 137.5)
		(width 0.256)
		(layer "F.Cu")
		(net 544)
	)
	(segment
		(start 164 143.6)
		(end 164.4 144)
		(width 0.256)
		(layer "F.Cu")
		(net 544)
	)
	(segment
		(start 186.5 137.5)
		(end 186 137)
		(width 0.177)
		(layer "F.Cu")
		(net 544)
	)
	(via
		(at 164 143.6)
		(size 0.45)
		(drill 0.2)
		(layers "F.Cu" "B.Cu")
		(net 544)
	)
	(via
		(at 186 137)
		(size 0.45)
		(drill 0.2)
		(layers "F.Cu" "B.Cu")
		(net 544)
	)
	(segment
		(start 163.85 138.05)
		(end 165.5 138.05)
		(width 0.256)
		(layer "B.Cu")
		(net 544)
	)
	(segment
		(start 165.5 138.55)
		(end 163.85 138.55)
		(width 0.256)
		(layer "B.Cu")
		(net 544)
	)
	(segment
		(start 183.900001 135.600001)
		(end 177.890001 135.600001)
		(width 0.256)
		(layer "B.Cu")
		(net 544)
	)
	(segment
		(start 163.6 140.3)
		(end 162.9 141)
		(width 0.256)
		(layer "B.Cu")
		(net 544)
	)
	(segment
		(start 165 134.4)
		(end 164.5 134.4)
		(width 0.256)
		(layer "B.Cu")
		(net 544)
	)
	(segment
		(start 162.9 141)
		(end 162.9 142.5)
		(width 0.256)
		(layer "B.Cu")
		(net 544)
	)
	(segment
		(start 177.890001 135.600001)
		(end 176.69 134.4)
		(width 0.256)
		(layer "B.Cu")
		(net 544)
	)
	(segment
		(start 163.6 135.3)
		(end 163.6 135.8)
		(width 0.256)
		(layer "B.Cu")
		(net 544)
	)
	(segment
		(start 164.5 134.4)
		(end 163.6 135.3)
		(width 0.256)
		(layer "B.Cu")
		(net 544)
	)
	(segment
		(start 163.6 139.8)
		(end 163.6 140.3)
		(width 0.256)
		(layer "B.Cu")
		(net 544)
	)
	(segment
		(start 163.85 139.05)
		(end 164.5 139.05)
		(width 0.256)
		(layer "B.Cu")
		(net 544)
	)
	(segment
		(start 167.5 136.55)
		(end 163.85 136.55)
		(width 0.256)
		(layer "B.Cu")
		(net 544)
	)
	(segment
		(start 166.5 137.55)
		(end 163.85 137.55)
		(width 0.256)
		(layer "B.Cu")
		(net 544)
	)
	(segment
		(start 163.599999 144.000001)
		(end 164 143.6)
		(width 0.256)
		(layer "B.Cu")
		(net 544)
	)
	(segment
		(start 185.500001 136.500001)
		(end 184.800001 136.500001)
		(width 0.256)
		(layer "B.Cu")
		(net 544)
	)
	(segment
		(start 186 137)
		(end 185.500001 136.500001)
		(width 0.256)
		(layer "B.Cu")
		(net 544)
	)
	(segment
		(start 165.3 135.100171)
		(end 165.3 134.7)
		(width 0.256)
		(layer "B.Cu")
		(net 544)
	)
	(segment
		(start 163.85 137.05)
		(end 166.5 137.05)
		(width 0.256)
		(layer "B.Cu")
		(net 544)
	)
	(segment
		(start 165.9 134.7)
		(end 165.9 135.100171)
		(width 0.256)
		(layer "B.Cu")
		(net 544)
	)
	(segment
		(start 184.800001 136.500001)
		(end 183.900001 135.600001)
		(width 0.256)
		(layer "B.Cu")
		(net 544)
	)
	(segment
		(start 164.5 139.55)
		(end 163.85 139.55)
		(width 0.256)
		(layer "B.Cu")
		(net 544)
	)
	(segment
		(start 162.9 142.5)
		(end 164 143.6)
		(width 0.256)
		(layer "B.Cu")
		(net 544)
	)
	(segment
		(start 163.85 136.05)
		(end 167.5 136.05)
		(width 0.256)
		(layer "B.Cu")
		(net 544)
	)
	(segment
		(start 163.599999 144.699999)
		(end 163.599999 144.000001)
		(width 0.256)
		(layer "B.Cu")
		(net 544)
	)
	(segment
		(start 176.69 134.4)
		(end 166.2 134.4)
		(width 0.256)
		(layer "B.Cu")
		(net 544)
	)
	(arc
		(start 164.5 139.05)
		(mid 164.676777 139.123223)
		(end 164.75 139.3)
		(width 0.256)
		(layer "B.Cu")
		(net 544)
	)
	(arc
		(start 165.6 135.400171)
		(mid 165.387868 135.312303)
		(end 165.3 135.100171)
		(width 0.256)
		(layer "B.Cu")
		(net 544)
	)
	(arc
		(start 163.6 138.8)
		(mid 163.673223 138.976777)
		(end 163.85 139.05)
		(width 0.256)
		(layer "B.Cu")
		(net 544)
	)
	(arc
		(start 163.85 138.55)
		(mid 163.673223 138.623223)
		(end 163.6 138.8)
		(width 0.256)
		(layer "B.Cu")
		(net 544)
	)
	(arc
		(start 163.85 136.55)
		(mid 163.673223 136.623223)
		(end 163.6 136.8)
		(width 0.256)
		(layer "B.Cu")
		(net 544)
	)
	(arc
		(start 166.75 137.3)
		(mid 166.676777 137.476777)
		(end 166.5 137.55)
		(width 0.256)
		(layer "B.Cu")
		(net 544)
	)
	(arc
		(start 165.9 135.100171)
		(mid 165.812132 135.312303)
		(end 165.6 135.400171)
		(width 0.256)
		(layer "B.Cu")
		(net 544)
	)
	(arc
		(start 164.75 139.3)
		(mid 164.676777 139.476777)
		(end 164.5 139.55)
		(width 0.256)
		(layer "B.Cu")
		(net 544)
	)
	(arc
		(start 163.6 136.8)
		(mid 163.673223 136.976777)
		(end 163.85 137.05)
		(width 0.256)
		(layer "B.Cu")
		(net 544)
	)
	(arc
		(start 165.3 134.7)
		(mid 165.212132 134.487868)
		(end 165 134.4)
		(width 0.256)
		(layer "B.Cu")
		(net 544)
	)
	(arc
		(start 165.5 138.05)
		(mid 165.676777 138.123223)
		(end 165.75 138.3)
		(width 0.256)
		(layer "B.Cu")
		(net 544)
	)
	(arc
		(start 165.75 138.3)
		(mid 165.676777 138.476777)
		(end 165.5 138.55)
		(width 0.256)
		(layer "B.Cu")
		(net 544)
	)
	(arc
		(start 166.2 134.4)
		(mid 165.987868 134.487868)
		(end 165.9 134.7)
		(width 0.256)
		(layer "B.Cu")
		(net 544)
	)
	(arc
		(start 163.6 135.8)
		(mid 163.673223 135.976777)
		(end 163.85 136.05)
		(width 0.256)
		(layer "B.Cu")
		(net 544)
	)
	(arc
		(start 167.5 136.05)
		(mid 167.676777 136.123223)
		(end 167.75 136.3)
		(width 0.256)
		(layer "B.Cu")
		(net 544)
	)
	(arc
		(start 163.85 137.55)
		(mid 163.673223 137.623223)
		(end 163.6 137.8)
		(width 0.256)
		(layer "B.Cu")
		(net 544)
	)
	(arc
		(start 166.5 137.05)
		(mid 166.676777 137.123223)
		(end 166.75 137.3)
		(width 0.256)
		(layer "B.Cu")
		(net 544)
	)
	(arc
		(start 167.75 136.3)
		(mid 167.676777 136.476777)
		(end 167.5 136.55)
		(width 0.256)
		(layer "B.Cu")
		(net 544)
	)
	(arc
		(start 163.85 139.55)
		(mid 163.673223 139.623223)
		(end 163.6 139.8)
		(width 0.256)
		(layer "B.Cu")
		(net 544)
	)
	(arc
		(start 163.6 137.8)
		(mid 163.673223 137.976777)
		(end 163.85 138.05)
		(width 0.256)
		(layer "B.Cu")
		(net 544)
	)
	(segment
		(start 187.5 138.5)
		(end 187 139)
		(width 0.256)
		(layer "F.Cu")
		(net 545)
	)
	(segment
		(start 164 147.6)
		(end 164.4 147.2)
		(width 0.256)
		(layer "F.Cu")
		(net 545)
	)
	(via
		(at 187 139)
		(size 0.45)
		(drill 0.2)
		(layers "F.Cu" "B.Cu")
		(net 545)
	)
	(via
		(at 164 147.6)
		(size 0.45)
		(drill 0.2)
		(layers "F.Cu" "B.Cu")
		(net 545)
	)
	(segment
		(start 163.999999 146.499999)
		(end 163.999998 147.600002)
		(width 0.256)
		(layer "B.Cu")
		(net 545)
	)
	(segment
		(start 187.5 137.5)
		(end 187.5 138.5)
		(width 0.157)
		(layer "In5.Cu")
		(net 545)
	)
	(segment
		(start 187 139)
		(end 187.5 138.5)
		(width 0.157)
		(layer "In5.Cu")
		(net 545)
	)
	(segment
		(start 181.325 137.145066)
		(end 181.325 135.854934)
		(width 0.157)
		(layer "In5.Cu")
		(net 545)
	)
	(segment
		(start 182.45 136.5)
		(end 186.5 136.5)
		(width 0.157)
		(layer "In5.Cu")
		(net 545)
	)
	(segment
		(start 182.225 137.145066)
		(end 182.225 136.725)
		(width 0.157)
		(layer "In5.Cu")
		(net 545)
	)
	(segment
		(start 180.875 135.854934)
		(end 180.875 137.145066)
		(width 0.157)
		(layer "In5.Cu")
		(net 545)
	)
	(segment
		(start 180.425 136.275)
		(end 180.425 135.854934)
		(width 0.157)
		(layer "In5.Cu")
		(net 545)
	)
	(segment
		(start 162 141.4)
		(end 166.9 136.5)
		(width 0.157)
		(layer "In5.Cu")
		(net 545)
	)
	(segment
		(start 162 145.6)
		(end 162 141.4)
		(width 0.157)
		(layer "In5.Cu")
		(net 545)
	)
	(segment
		(start 164 147.6)
		(end 162 145.6)
		(width 0.157)
		(layer "In5.Cu")
		(net 545)
	)
	(segment
		(start 166.9 136.5)
		(end 180.2 136.5)
		(width 0.157)
		(layer "In5.Cu")
		(net 545)
	)
	(segment
		(start 181.775 135.854934)
		(end 181.775 137.145066)
		(width 0.157)
		(layer "In5.Cu")
		(net 545)
	)
	(segment
		(start 186.5 136.5)
		(end 187.5 137.5)
		(width 0.157)
		(layer "In5.Cu")
		(net 545)
	)
	(arc
		(start 180.875 137.145066)
		(mid 180.940901 137.304165)
		(end 181.1 137.370066)
		(width 0.157)
		(layer "In5.Cu")
		(net 545)
	)
	(arc
		(start 181.325 135.854934)
		(mid 181.390901 135.695835)
		(end 181.55 135.629934)
		(width 0.157)
		(layer "In5.Cu")
		(net 545)
	)
	(arc
		(start 182.225 136.725)
		(mid 182.290901 136.565901)
		(end 182.45 136.5)
		(width 0.157)
		(layer "In5.Cu")
		(net 545)
	)
	(arc
		(start 180.425 135.854934)
		(mid 180.490901 135.695835)
		(end 180.65 135.629934)
		(width 0.157)
		(layer "In5.Cu")
		(net 545)
	)
	(arc
		(start 182 137.370066)
		(mid 182.159099 137.304165)
		(end 182.225 137.145066)
		(width 0.157)
		(layer "In5.Cu")
		(net 545)
	)
	(arc
		(start 181.775 137.145066)
		(mid 181.840901 137.304165)
		(end 182 137.370066)
		(width 0.157)
		(layer "In5.Cu")
		(net 545)
	)
	(arc
		(start 181.1 137.370066)
		(mid 181.259099 137.304165)
		(end 181.325 137.145066)
		(width 0.157)
		(layer "In5.Cu")
		(net 545)
	)
	(arc
		(start 180.65 135.629934)
		(mid 180.809099 135.695835)
		(end 180.875 135.854934)
		(width 0.157)
		(layer "In5.Cu")
		(net 545)
	)
	(arc
		(start 180.2 136.5)
		(mid 180.359099 136.434099)
		(end 180.425 136.275)
		(width 0.157)
		(layer "In5.Cu")
		(net 545)
	)
	(arc
		(start 181.55 135.629934)
		(mid 181.709099 135.695835)
		(end 181.775 135.854934)
		(width 0.157)
		(layer "In5.Cu")
		(net 545)
	)
	(segment
		(start 167.6 147.2)
		(end 167.2 147.6)
		(width 0.256)
		(layer "F.Cu")
		(net 546)
	)
	(segment
		(start 188.5 138.5)
		(end 188 139)
		(width 0.256)
		(layer "F.Cu")
		(net 546)
	)
	(via
		(at 167.2 147.6)
		(size 0.45)
		(drill 0.2)
		(layers "F.Cu" "B.Cu")
		(net 546)
	)
	(via
		(at 188 139)
		(size 0.45)
		(drill 0.2)
		(layers "F.Cu" "B.Cu")
		(net 546)
	)
	(segment
		(start 167.199999 146.499999)
		(end 167.2 147.6)
		(width 0.256)
		(layer "B.Cu")
		(net 546)
	)
	(segment
		(start 175.9 145.9)
		(end 180.03 150.03)
		(width 0.157)
		(layer "In7.Cu")
		(net 546)
	)
	(segment
		(start 191.2 139.5)
		(end 188.5 139.5)
		(width 0.157)
		(layer "In7.Cu")
		(net 546)
	)
	(segment
		(start 192 146.665)
		(end 192 144.7)
		(width 0.157)
		(layer "In7.Cu")
		(net 546)
	)
	(segment
		(start 192 144.7)
		(end 191.5 144.2)
		(width 0.157)
		(layer "In7.Cu")
		(net 546)
	)
	(segment
		(start 182.68 149.73)
		(end 182.68 149.414954)
		(width 0.157)
		(layer "In7.Cu")
		(net 546)
	)
	(segment
		(start 191.5 139.8)
		(end 191.2 139.5)
		(width 0.157)
		(layer "In7.Cu")
		(net 546)
	)
	(segment
		(start 183.58 150.03)
		(end 188.635 150.03)
		(width 0.157)
		(layer "In7.Cu")
		(net 546)
	)
	(segment
		(start 191.5 144.2)
		(end 191.5 139.8)
		(width 0.157)
		(layer "In7.Cu")
		(net 546)
	)
	(segment
		(start 188.635 150.03)
		(end 192 146.665)
		(width 0.157)
		(layer "In7.Cu")
		(net 546)
	)
	(segment
		(start 180.03 150.03)
		(end 182.38 150.03)
		(width 0.157)
		(layer "In7.Cu")
		(net 546)
	)
	(segment
		(start 167.2 147.6)
		(end 168.9 145.9)
		(width 0.157)
		(layer "In7.Cu")
		(net 546)
	)
	(segment
		(start 183.28 149.414954)
		(end 183.28 149.73)
		(width 0.157)
		(layer "In7.Cu")
		(net 546)
	)
	(segment
		(start 188.5 139.5)
		(end 188 139)
		(width 0.157)
		(layer "In7.Cu")
		(net 546)
	)
	(segment
		(start 168.9 145.9)
		(end 175.9 145.9)
		(width 0.157)
		(layer "In7.Cu")
		(net 546)
	)
	(arc
		(start 182.98 149.114954)
		(mid 183.192132 149.202822)
		(end 183.28 149.414954)
		(width 0.157)
		(layer "In7.Cu")
		(net 546)
	)
	(arc
		(start 182.68 149.414954)
		(mid 182.767868 149.202822)
		(end 182.98 149.114954)
		(width 0.157)
		(layer "In7.Cu")
		(net 546)
	)
	(arc
		(start 182.38 150.03)
		(mid 182.592132 149.942132)
		(end 182.68 149.73)
		(width 0.157)
		(layer "In7.Cu")
		(net 546)
	)
	(arc
		(start 183.28 149.73)
		(mid 183.367868 149.942132)
		(end 183.58 150.03)
		(width 0.157)
		(layer "In7.Cu")
		(net 546)
	)
	(segment
		(start 167.2 142.8)
		(end 167.6 143.2)
		(width 0.256)
		(layer "F.Cu")
		(net 547)
	)
	(segment
		(start 189.5 140.5)
		(end 189 141)
		(width 0.256)
		(layer "F.Cu")
		(net 547)
	)
	(via
		(at 189 141)
		(size 0.45)
		(drill 0.2)
		(layers "F.Cu" "B.Cu")
		(net 547)
	)
	(via
		(at 167.2 142.8)
		(size 0.45)
		(drill 0.2)
		(layers "F.Cu" "B.Cu")
		(net 547)
	)
	(segment
		(start 166.799997 143.199999)
		(end 166.799997 143.349999)
		(width 0.256)
		(layer "B.Cu")
		(net 547)
	)
	(segment
		(start 166.8 143.350002)
		(end 166.799997 143.349999)
		(width 0.15)
		(layer "B.Cu")
		(net 547)
	)
	(segment
		(start 166.599999 144.699999)
		(end 166.8 144.499998)
		(width 0.256)
		(layer "B.Cu")
		(net 547)
	)
	(segment
		(start 167.199996 142.8)
		(end 166.799997 143.199999)
		(width 0.256)
		(layer "B.Cu")
		(net 547)
	)
	(segment
		(start 166.8 144.499998)
		(end 166.8 143.85)
		(width 0.256)
		(layer "B.Cu")
		(net 547)
	)
	(segment
		(start 166.8 143.85)
		(end 166.8 143.350002)
		(width 0.15)
		(layer "B.Cu")
		(net 547)
	)
	(segment
		(start 174.325 138.547836)
		(end 174.325 139.075)
		(width 0.157)
		(layer "In7.Cu")
		(net 547)
	)
	(segment
		(start 188.5 140.5)
		(end 189 141)
		(width 0.157)
		(layer "In7.Cu")
		(net 547)
	)
	(segment
		(start 177.625 138.497836)
		(end 177.625 139.075)
		(width 0.157)
		(layer "In7.Cu")
		(net 547)
	)
	(segment
		(start 180.1 139.35)
		(end 180.15 139.35)
		(width 0.157)
		(layer "In7.Cu")
		(net 547)
	)
	(segment
		(start 169.8 139.35)
		(end 170.2 139.35)
		(width 0.157)
		(layer "In7.Cu")
		(net 547)
	)
	(segment
		(start 170.475 139.075)
		(end 170.475 138.497836)
		(width 0.157)
		(layer "In7.Cu")
		(net 547)
	)
	(segment
		(start 167.2 142.8)
		(end 167.125 142.725)
		(width 0.157)
		(layer "In7.Cu")
		(net 547)
	)
	(segment
		(start 173.775 139.075)
		(end 173.775 138.547836)
		(width 0.157)
		(layer "In7.Cu")
		(net 547)
	)
	(segment
		(start 178.725 138.497836)
		(end 178.725 139.075)
		(width 0.157)
		(layer "In7.Cu")
		(net 547)
	)
	(segment
		(start 179.275 139.075)
		(end 179.275 138.547836)
		(width 0.157)
		(layer "In7.Cu")
		(net 547)
	)
	(segment
		(start 176.525 138.497836)
		(end 176.525 139.075)
		(width 0.157)
		(layer "In7.Cu")
		(net 547)
	)
	(segment
		(start 175.975 139.075)
		(end 175.975 138.497836)
		(width 0.157)
		(layer "In7.Cu")
		(net 547)
	)
	(segment
		(start 181.625 140.5)
		(end 188.5 140.5)
		(width 0.157)
		(layer "In7.Cu")
		(net 547)
	)
	(segment
		(start 180.15 139.35)
		(end 180.475 139.35)
		(width 0.157)
		(layer "In7.Cu")
		(net 547)
	)
	(segment
		(start 171.025 138.497836)
		(end 171.025 139.075)
		(width 0.157)
		(layer "In7.Cu")
		(net 547)
	)
	(segment
		(start 179.825 138.547836)
		(end 179.825 139.075)
		(width 0.157)
		(layer "In7.Cu")
		(net 547)
	)
	(segment
		(start 167.125 142.025)
		(end 169.8 139.35)
		(width 0.157)
		(layer "In7.Cu")
		(net 547)
	)
	(segment
		(start 167.125 142.725)
		(end 167.125 142.025)
		(width 0.157)
		(layer "In7.Cu")
		(net 547)
	)
	(segment
		(start 180.475 139.35)
		(end 181.625 140.5)
		(width 0.157)
		(layer "In7.Cu")
		(net 547)
	)
	(segment
		(start 175.425 138.497836)
		(end 175.425 139.075)
		(width 0.157)
		(layer "In7.Cu")
		(net 547)
	)
	(segment
		(start 173.225 138.497836)
		(end 173.225 139.075)
		(width 0.157)
		(layer "In7.Cu")
		(net 547)
	)
	(segment
		(start 172.675 139.075)
		(end 172.675 138.497836)
		(width 0.157)
		(layer "In7.Cu")
		(net 547)
	)
	(segment
		(start 178.175 139.075)
		(end 178.175 138.497836)
		(width 0.157)
		(layer "In7.Cu")
		(net 547)
	)
	(segment
		(start 174.875 139.075)
		(end 174.875 138.497836)
		(width 0.157)
		(layer "In7.Cu")
		(net 547)
	)
	(segment
		(start 177.075 139.075)
		(end 177.075 138.497836)
		(width 0.157)
		(layer "In7.Cu")
		(net 547)
	)
	(segment
		(start 172.125 138.497836)
		(end 172.125 139.075)
		(width 0.157)
		(layer "In7.Cu")
		(net 547)
	)
	(segment
		(start 171.575 139.075)
		(end 171.575 138.497836)
		(width 0.157)
		(layer "In7.Cu")
		(net 547)
	)
	(arc
		(start 178.725 139.075)
		(mid 178.805546 139.269454)
		(end 179 139.35)
		(width 0.157)
		(layer "In7.Cu")
		(net 547)
	)
	(arc
		(start 171.85 138.222836)
		(mid 172.044454 138.303382)
		(end 172.125 138.497836)
		(width 0.157)
		(layer "In7.Cu")
		(net 547)
	)
	(arc
		(start 179 139.35)
		(mid 179.194454 139.269454)
		(end 179.275 139.075)
		(width 0.157)
		(layer "In7.Cu")
		(net 547)
	)
	(arc
		(start 172.4 139.35)
		(mid 172.594454 139.269454)
		(end 172.675 139.075)
		(width 0.157)
		(layer "In7.Cu")
		(net 547)
	)
	(arc
		(start 172.675 138.497836)
		(mid 172.755546 138.303382)
		(end 172.95 138.222836)
		(width 0.157)
		(layer "In7.Cu")
		(net 547)
	)
	(arc
		(start 171.025 139.075)
		(mid 171.105546 139.269454)
		(end 171.3 139.35)
		(width 0.157)
		(layer "In7.Cu")
		(net 547)
	)
	(arc
		(start 174.875 138.497836)
		(mid 174.955546 138.303382)
		(end 175.15 138.222836)
		(width 0.157)
		(layer "In7.Cu")
		(net 547)
	)
	(arc
		(start 174.05 138.272836)
		(mid 174.244454 138.353382)
		(end 174.325 138.547836)
		(width 0.157)
		(layer "In7.Cu")
		(net 547)
	)
	(arc
		(start 173.225 139.075)
		(mid 173.305546 139.269454)
		(end 173.5 139.35)
		(width 0.157)
		(layer "In7.Cu")
		(net 547)
	)
	(arc
		(start 170.475 138.497836)
		(mid 170.555546 138.303382)
		(end 170.75 138.222836)
		(width 0.157)
		(layer "In7.Cu")
		(net 547)
	)
	(arc
		(start 179.55 138.272836)
		(mid 179.744454 138.353382)
		(end 179.825 138.547836)
		(width 0.157)
		(layer "In7.Cu")
		(net 547)
	)
	(arc
		(start 173.5 139.35)
		(mid 173.694454 139.269454)
		(end 173.775 139.075)
		(width 0.157)
		(layer "In7.Cu")
		(net 547)
	)
	(arc
		(start 176.8 139.35)
		(mid 176.994454 139.269454)
		(end 177.075 139.075)
		(width 0.157)
		(layer "In7.Cu")
		(net 547)
	)
	(arc
		(start 174.6 139.35)
		(mid 174.794454 139.269454)
		(end 174.875 139.075)
		(width 0.157)
		(layer "In7.Cu")
		(net 547)
	)
	(arc
		(start 177.35 138.222836)
		(mid 177.544454 138.303382)
		(end 177.625 138.497836)
		(width 0.157)
		(layer "In7.Cu")
		(net 547)
	)
	(arc
		(start 170.75 138.222836)
		(mid 170.944454 138.303382)
		(end 171.025 138.497836)
		(width 0.157)
		(layer "In7.Cu")
		(net 547)
	)
	(arc
		(start 172.95 138.222836)
		(mid 173.144454 138.303382)
		(end 173.225 138.497836)
		(width 0.157)
		(layer "In7.Cu")
		(net 547)
	)
	(arc
		(start 171.3 139.35)
		(mid 171.494454 139.269454)
		(end 171.575 139.075)
		(width 0.157)
		(layer "In7.Cu")
		(net 547)
	)
	(arc
		(start 177.625 139.075)
		(mid 177.705546 139.269454)
		(end 177.9 139.35)
		(width 0.157)
		(layer "In7.Cu")
		(net 547)
	)
	(arc
		(start 178.45 138.222836)
		(mid 178.644454 138.303382)
		(end 178.725 138.497836)
		(width 0.157)
		(layer "In7.Cu")
		(net 547)
	)
	(arc
		(start 178.175 138.497836)
		(mid 178.255546 138.303382)
		(end 178.45 138.222836)
		(width 0.157)
		(layer "In7.Cu")
		(net 547)
	)
	(arc
		(start 175.425 139.075)
		(mid 175.505546 139.269454)
		(end 175.7 139.35)
		(width 0.157)
		(layer "In7.Cu")
		(net 547)
	)
	(arc
		(start 176.25 138.222836)
		(mid 176.444454 138.303382)
		(end 176.525 138.497836)
		(width 0.157)
		(layer "In7.Cu")
		(net 547)
	)
	(arc
		(start 177.9 139.35)
		(mid 178.094454 139.269454)
		(end 178.175 139.075)
		(width 0.157)
		(layer "In7.Cu")
		(net 547)
	)
	(arc
		(start 170.2 139.35)
		(mid 170.394454 139.269454)
		(end 170.475 139.075)
		(width 0.157)
		(layer "In7.Cu")
		(net 547)
	)
	(arc
		(start 175.15 138.222836)
		(mid 175.344454 138.303382)
		(end 175.425 138.497836)
		(width 0.157)
		(layer "In7.Cu")
		(net 547)
	)
	(arc
		(start 171.575 138.497836)
		(mid 171.655546 138.303382)
		(end 171.85 138.222836)
		(width 0.157)
		(layer "In7.Cu")
		(net 547)
	)
	(arc
		(start 174.325 139.075)
		(mid 174.405546 139.269454)
		(end 174.6 139.35)
		(width 0.157)
		(layer "In7.Cu")
		(net 547)
	)
	(arc
		(start 179.275 138.547836)
		(mid 179.355546 138.353382)
		(end 179.55 138.272836)
		(width 0.157)
		(layer "In7.Cu")
		(net 547)
	)
	(arc
		(start 175.7 139.35)
		(mid 175.894454 139.269454)
		(end 175.975 139.075)
		(width 0.157)
		(layer "In7.Cu")
		(net 547)
	)
	(arc
		(start 173.775 138.547836)
		(mid 173.855546 138.353382)
		(end 174.05 138.272836)
		(width 0.157)
		(layer "In7.Cu")
		(net 547)
	)
	(arc
		(start 179.825 139.075)
		(mid 179.905546 139.269454)
		(end 180.1 139.35)
		(width 0.157)
		(layer "In7.Cu")
		(net 547)
	)
	(arc
		(start 176.525 139.075)
		(mid 176.605546 139.269454)
		(end 176.8 139.35)
		(width 0.157)
		(layer "In7.Cu")
		(net 547)
	)
	(arc
		(start 175.975 138.497836)
		(mid 176.055546 138.303382)
		(end 176.25 138.222836)
		(width 0.157)
		(layer "In7.Cu")
		(net 547)
	)
	(arc
		(start 177.075 138.497836)
		(mid 177.155546 138.303382)
		(end 177.35 138.222836)
		(width 0.157)
		(layer "In7.Cu")
		(net 547)
	)
	(arc
		(start 172.125 139.075)
		(mid 172.205546 139.269454)
		(end 172.4 139.35)
		(width 0.157)
		(layer "In7.Cu")
		(net 547)
	)
	(segment
		(start 166.4 148.4)
		(end 166.8 148)
		(width 0.256)
		(layer "F.Cu")
		(net 548)
	)
	(segment
		(start 189.5 139.5)
		(end 189 140)
		(width 0.256)
		(layer "F.Cu")
		(net 548)
	)
	(via
		(at 189 140)
		(size 0.45)
		(drill 0.2)
		(layers "F.Cu" "B.Cu")
		(net 548)
	)
	(via
		(at 166.4 148.4)
		(size 0.45)
		(drill 0.2)
		(layers "F.Cu" "B.Cu")
		(net 548)
	)
	(segment
		(start 166.075 147.225)
		(end 166 147.3)
		(width 0.256)
		(layer "B.Cu")
		(net 548)
	)
	(segment
		(start 166.199999 146.499999)
		(end 166.199999 147.100001)
		(width 0.256)
		(layer "B.Cu")
		(net 548)
	)
	(segment
		(start 166.4 148.399996)
		(end 166.000001 147.999997)
		(width 0.256)
		(layer "B.Cu")
		(net 548)
	)
	(segment
		(start 166 147.3)
		(end 166 147.35)
		(width 0.256)
		(layer "B.Cu")
		(net 548)
	)
	(segment
		(start 166.000001 147.849997)
		(end 166 147.35)
		(width 0.15)
		(layer "B.Cu")
		(net 548)
	)
	(segment
		(start 166.000001 147.999997)
		(end 166.000001 147.849997)
		(width 0.256)
		(layer "B.Cu")
		(net 548)
	)
	(segment
		(start 166.199999 147.100001)
		(end 166.075 147.225)
		(width 0.256)
		(layer "B.Cu")
		(net 548)
	)
	(segment
		(start 190.35 147)
		(end 190.35 143.95)
		(width 0.157)
		(layer "In7.Cu")
		(net 548)
	)
	(segment
		(start 188.7 148.65)
		(end 190.35 147)
		(width 0.157)
		(layer "In7.Cu")
		(net 548)
	)
	(segment
		(start 185.65 148.425)
		(end 185.65 147.902007)
		(width 0.157)
		(layer "In7.Cu")
		(net 548)
	)
	(segment
		(start 190.5 140.75)
		(end 190.25 140.5)
		(width 0.157)
		(layer "In7.Cu")
		(net 548)
	)
	(segment
		(start 186.1 147.902007)
		(end 186.1 148.425)
		(width 0.157)
		(layer "In7.Cu")
		(net 548)
	)
	(segment
		(start 190.5 143.8)
		(end 190.5 140.75)
		(width 0.157)
		(layer "In7.Cu")
		(net 548)
	)
	(segment
		(start 187.225 148.65)
		(end 188.7 148.65)
		(width 0.157)
		(layer "In7.Cu")
		(net 548)
	)
	(segment
		(start 166.8 146.775)
		(end 168.05 145.525)
		(width 0.157)
		(layer "In7.Cu")
		(net 548)
	)
	(segment
		(start 166.8 147.775)
		(end 166.8 147.425)
		(width 0.15)
		(layer "In7.Cu")
		(net 548)
	)
	(segment
		(start 166.8 148)
		(end 166.8 147.775)
		(width 0.157)
		(layer "In7.Cu")
		(net 548)
	)
	(segment
		(start 176.675 145.525)
		(end 179.8 148.65)
		(width 0.157)
		(layer "In7.Cu")
		(net 548)
	)
	(segment
		(start 190.25 140.5)
		(end 189.5 140.5)
		(width 0.157)
		(layer "In7.Cu")
		(net 548)
	)
	(segment
		(start 186.55 148.425)
		(end 186.55 147.902007)
		(width 0.157)
		(layer "In7.Cu")
		(net 548)
	)
	(segment
		(start 184.75 148.425)
		(end 184.75 147.902007)
		(width 0.157)
		(layer "In7.Cu")
		(net 548)
	)
	(segment
		(start 179.8 148.65)
		(end 184.525 148.65)
		(width 0.157)
		(layer "In7.Cu")
		(net 548)
	)
	(segment
		(start 168.05 145.525)
		(end 176.675 145.525)
		(width 0.157)
		(layer "In7.Cu")
		(net 548)
	)
	(segment
		(start 190.35 143.95)
		(end 190.5 143.8)
		(width 0.157)
		(layer "In7.Cu")
		(net 548)
	)
	(segment
		(start 187 147.902007)
		(end 187 148.425)
		(width 0.157)
		(layer "In7.Cu")
		(net 548)
	)
	(segment
		(start 166.4 148.4)
		(end 166.8 148)
		(width 0.157)
		(layer "In7.Cu")
		(net 548)
	)
	(segment
		(start 185.2 147.902007)
		(end 185.2 148.425)
		(width 0.157)
		(layer "In7.Cu")
		(net 548)
	)
	(segment
		(start 166.8 147.425)
		(end 166.8 146.775)
		(width 0.157)
		(layer "In7.Cu")
		(net 548)
	)
	(segment
		(start 189.5 140.5)
		(end 189 140)
		(width 0.157)
		(layer "In7.Cu")
		(net 548)
	)
	(arc
		(start 186.775 147.677007)
		(mid 186.934099 147.742908)
		(end 187 147.902007)
		(width 0.157)
		(layer "In7.Cu")
		(net 548)
	)
	(arc
		(start 186.325 148.65)
		(mid 186.484099 148.584099)
		(end 186.55 148.425)
		(width 0.157)
		(layer "In7.Cu")
		(net 548)
	)
	(arc
		(start 184.975 147.677007)
		(mid 185.134099 147.742908)
		(end 185.2 147.902007)
		(width 0.157)
		(layer "In7.Cu")
		(net 548)
	)
	(arc
		(start 185.875 147.677007)
		(mid 186.034099 147.742908)
		(end 186.1 147.902007)
		(width 0.157)
		(layer "In7.Cu")
		(net 548)
	)
	(arc
		(start 184.525 148.65)
		(mid 184.684099 148.584099)
		(end 184.75 148.425)
		(width 0.157)
		(layer "In7.Cu")
		(net 548)
	)
	(arc
		(start 185.425 148.65)
		(mid 185.584099 148.584099)
		(end 185.65 148.425)
		(width 0.157)
		(layer "In7.Cu")
		(net 548)
	)
	(arc
		(start 187 148.425)
		(mid 187.065901 148.584099)
		(end 187.225 148.65)
		(width 0.157)
		(layer "In7.Cu")
		(net 548)
	)
	(arc
		(start 185.65 147.902007)
		(mid 185.715901 147.742908)
		(end 185.875 147.677007)
		(width 0.157)
		(layer "In7.Cu")
		(net 548)
	)
	(arc
		(start 186.1 148.425)
		(mid 186.165901 148.584099)
		(end 186.325 148.65)
		(width 0.157)
		(layer "In7.Cu")
		(net 548)
	)
	(arc
		(start 186.55 147.902007)
		(mid 186.615901 147.742908)
		(end 186.775 147.677007)
		(width 0.157)
		(layer "In7.Cu")
		(net 548)
	)
	(arc
		(start 184.75 147.902007)
		(mid 184.815901 147.742908)
		(end 184.975 147.677007)
		(width 0.157)
		(layer "In7.Cu")
		(net 548)
	)
	(arc
		(start 185.2 148.425)
		(mid 185.265901 148.584099)
		(end 185.425 148.65)
		(width 0.157)
		(layer "In7.Cu")
		(net 548)
	)
	(segment
		(start 167.2 143.6)
		(end 167.6 144)
		(width 0.256)
		(layer "F.Cu")
		(net 549)
	)
	(segment
		(start 187.5 139.5)
		(end 187 140)
		(width 0.256)
		(layer "F.Cu")
		(net 549)
	)
	(via
		(at 167.2 143.6)
		(size 0.45)
		(drill 0.2)
		(layers "F.Cu" "B.Cu")
		(net 549)
	)
	(via
		(at 187 140)
		(size 0.45)
		(drill 0.2)
		(layers "F.Cu" "B.Cu")
		(net 549)
	)
	(segment
		(start 167.199999 144.699999)
		(end 167.2 143.6)
		(width 0.256)
		(layer "B.Cu")
		(net 549)
	)
	(segment
		(start 177.425 137.081923)
		(end 177.425 137.675)
		(width 0.157)
		(layer "In7.Cu")
		(net 549)
	)
	(segment
		(start 176.075 137.675)
		(end 176.075 137.081923)
		(width 0.157)
		(layer "In7.Cu")
		(net 549)
	)
	(segment
		(start 166.8 143.2)
		(end 166.8 142.975)
		(width 0.157)
		(layer "In7.Cu")
		(net 549)
	)
	(segment
		(start 172.925 137.081923)
		(end 172.925 137.675)
		(width 0.157)
		(layer "In7.Cu")
		(net 549)
	)
	(segment
		(start 171.575 137.675)
		(end 171.575 137.081923)
		(width 0.157)
		(layer "In7.Cu")
		(net 549)
	)
	(segment
		(start 174.725 137.081923)
		(end 174.725 137.675)
		(width 0.157)
		(layer "In7.Cu")
		(net 549)
	)
	(segment
		(start 177.65 137.9)
		(end 180.35 137.9)
		(width 0.157)
		(layer "In7.Cu")
		(net 549)
	)
	(segment
		(start 174.275 137.675)
		(end 174.275 137.081923)
		(width 0.157)
		(layer "In7.Cu")
		(net 549)
	)
	(segment
		(start 180.35 137.9)
		(end 181.95 139.5)
		(width 0.157)
		(layer "In7.Cu")
		(net 549)
	)
	(segment
		(start 169.775 137.675)
		(end 169.775 137.081923)
		(width 0.157)
		(layer "In7.Cu")
		(net 549)
	)
	(segment
		(start 172.475 137.675)
		(end 172.475 137.081923)
		(width 0.157)
		(layer "In7.Cu")
		(net 549)
	)
	(segment
		(start 175.625 137.081923)
		(end 175.625 137.675)
		(width 0.157)
		(layer "In7.Cu")
		(net 549)
	)
	(segment
		(start 171.125 137.081923)
		(end 171.125 137.675)
		(width 0.157)
		(layer "In7.Cu")
		(net 549)
	)
	(segment
		(start 181.95 139.5)
		(end 186.225 139.5)
		(width 0.157)
		(layer "In7.Cu")
		(net 549)
	)
	(segment
		(start 167.2 143.6)
		(end 166.8 143.2)
		(width 0.157)
		(layer "In7.Cu")
		(net 549)
	)
	(segment
		(start 166.8 142.625)
		(end 166.8 140)
		(width 0.157)
		(layer "In7.Cu")
		(net 549)
	)
	(segment
		(start 166.8 140)
		(end 168.9 137.9)
		(width 0.157)
		(layer "In7.Cu")
		(net 549)
	)
	(segment
		(start 172.025 137.081923)
		(end 172.025 137.675)
		(width 0.157)
		(layer "In7.Cu")
		(net 549)
	)
	(segment
		(start 175.175 137.675)
		(end 175.175 137.081923)
		(width 0.157)
		(layer "In7.Cu")
		(net 549)
	)
	(segment
		(start 186.725 140)
		(end 187 140)
		(width 0.157)
		(layer "In7.Cu")
		(net 549)
	)
	(segment
		(start 170.225 137.081923)
		(end 170.225 137.675)
		(width 0.157)
		(layer "In7.Cu")
		(net 549)
	)
	(segment
		(start 166.8 142.975)
		(end 166.8 142.625)
		(width 0.15)
		(layer "In7.Cu")
		(net 549)
	)
	(segment
		(start 173.825 137.081923)
		(end 173.825 137.675)
		(width 0.157)
		(layer "In7.Cu")
		(net 549)
	)
	(segment
		(start 168.9 137.9)
		(end 169.55 137.9)
		(width 0.157)
		(layer "In7.Cu")
		(net 549)
	)
	(segment
		(start 170.675 137.675)
		(end 170.675 137.081923)
		(width 0.157)
		(layer "In7.Cu")
		(net 549)
	)
	(segment
		(start 176.975 137.675)
		(end 176.975 137.081923)
		(width 0.157)
		(layer "In7.Cu")
		(net 549)
	)
	(segment
		(start 176.525 137.081923)
		(end 176.525 137.675)
		(width 0.157)
		(layer "In7.Cu")
		(net 549)
	)
	(segment
		(start 173.375 137.675)
		(end 173.375 137.081923)
		(width 0.157)
		(layer "In7.Cu")
		(net 549)
	)
	(segment
		(start 186.225 139.5)
		(end 186.725 140)
		(width 0.157)
		(layer "In7.Cu")
		(net 549)
	)
	(arc
		(start 171.35 137.9)
		(mid 171.509099 137.834099)
		(end 171.575 137.675)
		(width 0.157)
		(layer "In7.Cu")
		(net 549)
	)
	(arc
		(start 172.025 137.675)
		(mid 172.090901 137.834099)
		(end 172.25 137.9)
		(width 0.157)
		(layer "In7.Cu")
		(net 549)
	)
	(arc
		(start 169.775 137.081923)
		(mid 169.840901 136.922824)
		(end 170 136.856923)
		(width 0.157)
		(layer "In7.Cu")
		(net 549)
	)
	(arc
		(start 172.7 136.856923)
		(mid 172.859099 136.922824)
		(end 172.925 137.081923)
		(width 0.157)
		(layer "In7.Cu")
		(net 549)
	)
	(arc
		(start 171.8 136.856923)
		(mid 171.959099 136.922824)
		(end 172.025 137.081923)
		(width 0.157)
		(layer "In7.Cu")
		(net 549)
	)
	(arc
		(start 177.425 137.675)
		(mid 177.490901 137.834099)
		(end 177.65 137.9)
		(width 0.157)
		(layer "In7.Cu")
		(net 549)
	)
	(arc
		(start 172.925 137.675)
		(mid 172.990901 137.834099)
		(end 173.15 137.9)
		(width 0.157)
		(layer "In7.Cu")
		(net 549)
	)
	(arc
		(start 176.075 137.081923)
		(mid 176.140901 136.922824)
		(end 176.3 136.856923)
		(width 0.157)
		(layer "In7.Cu")
		(net 549)
	)
	(arc
		(start 176.975 137.081923)
		(mid 177.040901 136.922824)
		(end 177.2 136.856923)
		(width 0.157)
		(layer "In7.Cu")
		(net 549)
	)
	(arc
		(start 170.45 137.9)
		(mid 170.609099 137.834099)
		(end 170.675 137.675)
		(width 0.157)
		(layer "In7.Cu")
		(net 549)
	)
	(arc
		(start 170.225 137.675)
		(mid 170.290901 137.834099)
		(end 170.45 137.9)
		(width 0.157)
		(layer "In7.Cu")
		(net 549)
	)
	(arc
		(start 174.05 137.9)
		(mid 174.209099 137.834099)
		(end 174.275 137.675)
		(width 0.157)
		(layer "In7.Cu")
		(net 549)
	)
	(arc
		(start 175.85 137.9)
		(mid 176.009099 137.834099)
		(end 176.075 137.675)
		(width 0.157)
		(layer "In7.Cu")
		(net 549)
	)
	(arc
		(start 173.15 137.9)
		(mid 173.309099 137.834099)
		(end 173.375 137.675)
		(width 0.157)
		(layer "In7.Cu")
		(net 549)
	)
	(arc
		(start 173.6 136.856923)
		(mid 173.759099 136.922824)
		(end 173.825 137.081923)
		(width 0.157)
		(layer "In7.Cu")
		(net 549)
	)
	(arc
		(start 175.625 137.675)
		(mid 175.690901 137.834099)
		(end 175.85 137.9)
		(width 0.157)
		(layer "In7.Cu")
		(net 549)
	)
	(arc
		(start 176.525 137.675)
		(mid 176.590901 137.834099)
		(end 176.75 137.9)
		(width 0.157)
		(layer "In7.Cu")
		(net 549)
	)
	(arc
		(start 170.9 136.856923)
		(mid 171.059099 136.922824)
		(end 171.125 137.081923)
		(width 0.157)
		(layer "In7.Cu")
		(net 549)
	)
	(arc
		(start 174.95 137.9)
		(mid 175.109099 137.834099)
		(end 175.175 137.675)
		(width 0.157)
		(layer "In7.Cu")
		(net 549)
	)
	(arc
		(start 175.4 136.856923)
		(mid 175.559099 136.922824)
		(end 175.625 137.081923)
		(width 0.157)
		(layer "In7.Cu")
		(net 549)
	)
	(arc
		(start 174.5 136.856923)
		(mid 174.659099 136.922824)
		(end 174.725 137.081923)
		(width 0.157)
		(layer "In7.Cu")
		(net 549)
	)
	(arc
		(start 169.55 137.9)
		(mid 169.709099 137.834099)
		(end 169.775 137.675)
		(width 0.157)
		(layer "In7.Cu")
		(net 549)
	)
	(arc
		(start 175.175 137.081923)
		(mid 175.240901 136.922824)
		(end 175.4 136.856923)
		(width 0.157)
		(layer "In7.Cu")
		(net 549)
	)
	(arc
		(start 174.275 137.081923)
		(mid 174.340901 136.922824)
		(end 174.5 136.856923)
		(width 0.157)
		(layer "In7.Cu")
		(net 549)
	)
	(arc
		(start 176.75 137.9)
		(mid 176.909099 137.834099)
		(end 176.975 137.675)
		(width 0.157)
		(layer "In7.Cu")
		(net 549)
	)
	(arc
		(start 173.375 137.081923)
		(mid 173.440901 136.922824)
		(end 173.6 136.856923)
		(width 0.157)
		(layer "In7.Cu")
		(net 549)
	)
	(arc
		(start 172.475 137.081923)
		(mid 172.540901 136.922824)
		(end 172.7 136.856923)
		(width 0.157)
		(layer "In7.Cu")
		(net 549)
	)
	(arc
		(start 170 136.856923)
		(mid 170.159099 136.922824)
		(end 170.225 137.081923)
		(width 0.157)
		(layer "In7.Cu")
		(net 549)
	)
	(arc
		(start 176.3 136.856923)
		(mid 176.459099 136.922824)
		(end 176.525 137.081923)
		(width 0.157)
		(layer "In7.Cu")
		(net 549)
	)
	(arc
		(start 177.2 136.856923)
		(mid 177.359099 136.922824)
		(end 177.425 137.081923)
		(width 0.157)
		(layer "In7.Cu")
		(net 549)
	)
	(arc
		(start 170.675 137.081923)
		(mid 170.740901 136.922824)
		(end 170.9 136.856923)
		(width 0.157)
		(layer "In7.Cu")
		(net 549)
	)
	(arc
		(start 173.825 137.675)
		(mid 173.890901 137.834099)
		(end 174.05 137.9)
		(width 0.157)
		(layer "In7.Cu")
		(net 549)
	)
	(arc
		(start 172.25 137.9)
		(mid 172.409099 137.834099)
		(end 172.475 137.675)
		(width 0.157)
		(layer "In7.Cu")
		(net 549)
	)
	(arc
		(start 174.725 137.675)
		(mid 174.790901 137.834099)
		(end 174.95 137.9)
		(width 0.157)
		(layer "In7.Cu")
		(net 549)
	)
	(arc
		(start 171.575 137.081923)
		(mid 171.640901 136.922824)
		(end 171.8 136.856923)
		(width 0.157)
		(layer "In7.Cu")
		(net 549)
	)
	(arc
		(start 171.125 137.675)
		(mid 171.190901 137.834099)
		(end 171.35 137.9)
		(width 0.157)
		(layer "In7.Cu")
		(net 549)
	)
	(segment
		(start 169.2 148.8)
		(end 168.8 148.4)
		(width 0.256)
		(layer "F.Cu")
		(net 550)
	)
	(segment
		(start 186.5 142.5)
		(end 186 143)
		(width 0.256)
		(layer "F.Cu")
		(net 550)
	)
	(via
		(at 186 143)
		(size 0.45)
		(drill 0.2)
		(layers "F.Cu" "B.Cu")
		(net 550)
	)
	(via
		(at 168.8 148.4)
		(size 0.45)
		(drill 0.2)
		(layers "F.Cu" "B.Cu")
		(net 550)
	)
	(segment
		(start 169.175 152.510608)
		(end 169.175 153.225)
		(width 0.256)
		(layer "B.Cu")
		(net 550)
	)
	(segment
		(start 174.95 153.5)
		(end 175 153.5)
		(width 0.256)
		(layer "B.Cu")
		(net 550)
	)
	(segment
		(start 174.675 152.510608)
		(end 174.675 153.225)
		(width 0.256)
		(layer "B.Cu")
		(net 550)
	)
	(segment
		(start 186.3 152.8)
		(end 186.3 147.6)
		(width 0.256)
		(layer "B.Cu")
		(net 550)
	)
	(segment
		(start 168.4 147.19)
		(end 168.4 147.35)
		(width 0.256)
		(layer "B.Cu")
		(net 550)
	)
	(segment
		(start 186.55 143.853)
		(end 186 143.303)
		(width 0.256)
		(layer "B.Cu")
		(net 550)
	)
	(segment
		(start 167.999999 146.789999)
		(end 168.4 147.19)
		(width 0.256)
		(layer "B.Cu")
		(net 550)
	)
	(segment
		(start 174.125 153.225)
		(end 174.125 152.510608)
		(width 0.256)
		(layer "B.Cu")
		(net 550)
	)
	(segment
		(start 168.4 147.85)
		(end 168.4 147.35)
		(width 0.15)
		(layer "B.Cu")
		(net 550)
	)
	(segment
		(start 168.8 148.4)
		(end 168.8 148.3)
		(width 0.256)
		(layer "B.Cu")
		(net 550)
	)
	(segment
		(start 186.3 147.6)
		(end 186.55 147.35)
		(width 0.256)
		(layer "B.Cu")
		(net 550)
	)
	(segment
		(start 169.725 153.225)
		(end 169.725 152.510608)
		(width 0.256)
		(layer "B.Cu")
		(net 550)
	)
	(segment
		(start 168.625 153.225)
		(end 168.625 152.510608)
		(width 0.256)
		(layer "B.Cu")
		(net 550)
	)
	(segment
		(start 175 153.5)
		(end 185.6 153.5)
		(width 0.256)
		(layer "B.Cu")
		(net 550)
	)
	(segment
		(start 167.999999 146.499999)
		(end 167.999999 146.789999)
		(width 0.256)
		(layer "B.Cu")
		(net 550)
	)
	(segment
		(start 167.75 153.5)
		(end 168.35 153.5)
		(width 0.256)
		(layer "B.Cu")
		(net 550)
	)
	(segment
		(start 170.275 152.510608)
		(end 170.275 153.225)
		(width 0.256)
		(layer "B.Cu")
		(net 550)
	)
	(segment
		(start 168.8 149.8)
		(end 167.2 151.4)
		(width 0.256)
		(layer "B.Cu")
		(net 550)
	)
	(segment
		(start 167.2 151.4)
		(end 167.2 152.95)
		(width 0.256)
		(layer "B.Cu")
		(net 550)
	)
	(segment
		(start 171.925 153.225)
		(end 171.925 152.510608)
		(width 0.256)
		(layer "B.Cu")
		(net 550)
	)
	(segment
		(start 173.025 153.225)
		(end 173.025 152.510608)
		(width 0.256)
		(layer "B.Cu")
		(net 550)
	)
	(segment
		(start 170.825 153.225)
		(end 170.825 152.510608)
		(width 0.256)
		(layer "B.Cu")
		(net 550)
	)
	(segment
		(start 173.575 152.510608)
		(end 173.575 153.225)
		(width 0.256)
		(layer "B.Cu")
		(net 550)
	)
	(segment
		(start 171.375 152.510608)
		(end 171.375 153.225)
		(width 0.256)
		(layer "B.Cu")
		(net 550)
	)
	(segment
		(start 168.4 147.9)
		(end 168.8 148.3)
		(width 0.256)
		(layer "B.Cu")
		(net 550)
	)
	(segment
		(start 167.2 152.95)
		(end 167.75 153.5)
		(width 0.256)
		(layer "B.Cu")
		(net 550)
	)
	(segment
		(start 185.6 153.5)
		(end 186.3 152.8)
		(width 0.256)
		(layer "B.Cu")
		(net 550)
	)
	(segment
		(start 168.8 148.4)
		(end 168.8 149.8)
		(width 0.256)
		(layer "B.Cu")
		(net 550)
	)
	(segment
		(start 172.475 152.510608)
		(end 172.475 153.225)
		(width 0.256)
		(layer "B.Cu")
		(net 550)
	)
	(segment
		(start 186 143.303)
		(end 186 143)
		(width 0.256)
		(layer "B.Cu")
		(net 550)
	)
	(segment
		(start 186.55 147.35)
		(end 186.55 143.853)
		(width 0.256)
		(layer "B.Cu")
		(net 550)
	)
	(segment
		(start 168.4 147.9)
		(end 168.4 147.85)
		(width 0.256)
		(layer "B.Cu")
		(net 550)
	)
	(arc
		(start 171.925 152.510608)
		(mid 172.005546 152.316154)
		(end 172.2 152.235608)
		(width 0.256)
		(layer "B.Cu")
		(net 550)
	)
	(arc
		(start 168.35 153.5)
		(mid 168.544454 153.419454)
		(end 168.625 153.225)
		(width 0.256)
		(layer "B.Cu")
		(net 550)
	)
	(arc
		(start 174.675 153.225)
		(mid 174.755546 153.419454)
		(end 174.95 153.5)
		(width 0.256)
		(layer "B.Cu")
		(net 550)
	)
	(arc
		(start 168.625 152.510608)
		(mid 168.705546 152.316154)
		(end 168.9 152.235608)
		(width 0.256)
		(layer "B.Cu")
		(net 550)
	)
	(arc
		(start 172.2 152.235608)
		(mid 172.394454 152.316154)
		(end 172.475 152.510608)
		(width 0.256)
		(layer "B.Cu")
		(net 550)
	)
	(arc
		(start 171.65 153.5)
		(mid 171.844454 153.419454)
		(end 171.925 153.225)
		(width 0.256)
		(layer "B.Cu")
		(net 550)
	)
	(arc
		(start 173.85 153.5)
		(mid 174.044454 153.419454)
		(end 174.125 153.225)
		(width 0.256)
		(layer "B.Cu")
		(net 550)
	)
	(arc
		(start 170.275 153.225)
		(mid 170.355546 153.419454)
		(end 170.55 153.5)
		(width 0.256)
		(layer "B.Cu")
		(net 550)
	)
	(arc
		(start 173.575 153.225)
		(mid 173.655546 153.419454)
		(end 173.85 153.5)
		(width 0.256)
		(layer "B.Cu")
		(net 550)
	)
	(arc
		(start 171.1 152.235608)
		(mid 171.294454 152.316154)
		(end 171.375 152.510608)
		(width 0.256)
		(layer "B.Cu")
		(net 550)
	)
	(arc
		(start 172.75 153.5)
		(mid 172.944454 153.419454)
		(end 173.025 153.225)
		(width 0.256)
		(layer "B.Cu")
		(net 550)
	)
	(arc
		(start 168.9 152.235608)
		(mid 169.094454 152.316154)
		(end 169.175 152.510608)
		(width 0.256)
		(layer "B.Cu")
		(net 550)
	)
	(arc
		(start 170 152.235608)
		(mid 170.194454 152.316154)
		(end 170.275 152.510608)
		(width 0.256)
		(layer "B.Cu")
		(net 550)
	)
	(arc
		(start 172.475 153.225)
		(mid 172.555546 153.419454)
		(end 172.75 153.5)
		(width 0.256)
		(layer "B.Cu")
		(net 550)
	)
	(arc
		(start 173.3 152.235608)
		(mid 173.494454 152.316154)
		(end 173.575 152.510608)
		(width 0.256)
		(layer "B.Cu")
		(net 550)
	)
	(arc
		(start 171.375 153.225)
		(mid 171.455546 153.419454)
		(end 171.65 153.5)
		(width 0.256)
		(layer "B.Cu")
		(net 550)
	)
	(arc
		(start 169.45 153.5)
		(mid 169.644454 153.419454)
		(end 169.725 153.225)
		(width 0.256)
		(layer "B.Cu")
		(net 550)
	)
	(arc
		(start 169.725 152.510608)
		(mid 169.805546 152.316154)
		(end 170 152.235608)
		(width 0.256)
		(layer "B.Cu")
		(net 550)
	)
	(arc
		(start 173.025 152.510608)
		(mid 173.105546 152.316154)
		(end 173.3 152.235608)
		(width 0.256)
		(layer "B.Cu")
		(net 550)
	)
	(arc
		(start 169.175 153.225)
		(mid 169.255546 153.419454)
		(end 169.45 153.5)
		(width 0.256)
		(layer "B.Cu")
		(net 550)
	)
	(arc
		(start 170.55 153.5)
		(mid 170.744454 153.419454)
		(end 170.825 153.225)
		(width 0.256)
		(layer "B.Cu")
		(net 550)
	)
	(arc
		(start 174.125 152.510608)
		(mid 174.205546 152.316154)
		(end 174.4 152.235608)
		(width 0.256)
		(layer "B.Cu")
		(net 550)
	)
	(arc
		(start 170.825 152.510608)
		(mid 170.905546 152.316154)
		(end 171.1 152.235608)
		(width 0.256)
		(layer "B.Cu")
		(net 550)
	)
	(arc
		(start 174.4 152.235608)
		(mid 174.594454 152.316154)
		(end 174.675 152.510608)
		(width 0.256)
		(layer "B.Cu")
		(net 550)
	)
	(segment
		(start 186.5 138.5)
		(end 186 138)
		(width 0.256)
		(layer "F.Cu")
		(net 551)
	)
	(segment
		(start 170 147.2)
		(end 170.4 146.8)
		(width 0.225)
		(layer "F.Cu")
		(net 551)
	)
	(via
		(at 170.4 146.8)
		(size 0.45)
		(drill 0.2)
		(layers "F.Cu" "B.Cu")
		(net 551)
	)
	(via
		(at 186 138)
		(size 0.45)
		(drill 0.2)
		(layers "F.Cu" "B.Cu")
		(net 551)
	)
	(segment
		(start 185.653 138.347)
		(end 186 138)
		(width 0.141)
		(layer "In5.Cu")
		(net 551)
	)
	(segment
		(start 185.063376 139.553)
		(end 185.653 138.963376)
		(width 0.141)
		(layer "In5.Cu")
		(net 551)
	)
	(segment
		(start 170.153 145.636624)
		(end 168.613376 144.097)
		(width 0.141)
		(layer "In5.Cu")
		(net 551)
	)
	(segment
		(start 181.775 140.228572)
		(end 181.775 138.871428)
		(width 0.141)
		(layer "In5.Cu")
		(net 551)
	)
	(segment
		(start 163.713376 144.097)
		(end 163.453 143.836624)
		(width 0.141)
		(layer "In5.Cu")
		(net 551)
	)
	(segment
		(start 163.453 143.836624)
		(end 163.453 142.563376)
		(width 0.141)
		(layer "In5.Cu")
		(net 551)
	)
	(segment
		(start 183.372 139.553)
		(end 185.063376 139.553)
		(width 0.141)
		(layer "In5.Cu")
		(net 551)
	)
	(segment
		(start 164.428161 141.588215)
		(end 164.428161 141.588211)
		(width 0.141)
		(layer "In5.Cu")
		(net 551)
	)
	(segment
		(start 185.653 138.963376)
		(end 185.653 138.347)
		(width 0.141)
		(layer "In5.Cu")
		(net 551)
	)
	(segment
		(start 166.463376 139.553)
		(end 179.872 139.553)
		(width 0.141)
		(layer "In5.Cu")
		(net 551)
	)
	(segment
		(start 170.153 146.553)
		(end 170.153 145.636624)
		(width 0.141)
		(layer "In5.Cu")
		(net 551)
	)
	(segment
		(start 180.375 139.05)
		(end 180.375 138.871428)
		(width 0.141)
		(layer "In5.Cu")
		(net 551)
	)
	(segment
		(start 180.769 138.871428)
		(end 180.769 140.228572)
		(width 0.141)
		(layer "In5.Cu")
		(net 551)
	)
	(segment
		(start 164.130674 142.133188)
		(end 164.130675 142.133188)
		(width 0.141)
		(layer "In5.Cu")
		(net 551)
	)
	(segment
		(start 163.453 142.563376)
		(end 163.883188 142.133188)
		(width 0.141)
		(layer "In5.Cu")
		(net 551)
	)
	(segment
		(start 164.398872 141.617501)
		(end 164.428161 141.588215)
		(width 0.141)
		(layer "In5.Cu")
		(net 551)
	)
	(segment
		(start 183.175 140.228572)
		(end 183.175 139.75)
		(width 0.141)
		(layer "In5.Cu")
		(net 551)
	)
	(segment
		(start 164.522214 142.029752)
		(end 164.378161 141.885699)
		(width 0.141)
		(layer "In5.Cu")
		(net 551)
	)
	(segment
		(start 168.613376 144.097)
		(end 163.713376 144.097)
		(width 0.141)
		(layer "In5.Cu")
		(net 551)
	)
	(segment
		(start 170.4 146.8)
		(end 170.153 146.553)
		(width 0.141)
		(layer "In5.Cu")
		(net 551)
	)
	(segment
		(start 164.378161 141.638211)
		(end 164.398872 141.617504)
		(width 0.141)
		(layer "In5.Cu")
		(net 551)
	)
	(segment
		(start 164.130675 142.133188)
		(end 164.274727 142.27724)
		(width 0.141)
		(layer "In5.Cu")
		(net 551)
	)
	(segment
		(start 182.169 138.871428)
		(end 182.169 140.228572)
		(width 0.141)
		(layer "In5.Cu")
		(net 551)
	)
	(segment
		(start 164.428161 141.588211)
		(end 166.463376 139.553)
		(width 0.141)
		(layer "In5.Cu")
		(net 551)
	)
	(segment
		(start 164.398872 141.617504)
		(end 164.398872 141.617501)
		(width 0.141)
		(layer "In5.Cu")
		(net 551)
	)
	(segment
		(start 164.522215 142.27724)
		(end 164.522214 142.27724)
		(width 0.141)
		(layer "In5.Cu")
		(net 551)
	)
	(arc
		(start 181.272 140.731572)
		(mid 181.627675 140.584247)
		(end 181.775 140.228572)
		(width 0.141)
		(layer "In5.Cu")
		(net 551)
	)
	(arc
		(start 180.375 138.871428)
		(mid 180.4327 138.732128)
		(end 180.572 138.674428)
		(width 0.141)
		(layer "In5.Cu")
		(net 551)
	)
	(arc
		(start 182.169 140.228572)
		(mid 182.316325 140.584247)
		(end 182.672 140.731572)
		(width 0.141)
		(layer "In5.Cu")
		(net 551)
	)
	(arc
		(start 183.175 139.75)
		(mid 183.2327 139.6107)
		(end 183.372 139.553)
		(width 0.141)
		(layer "In5.Cu")
		(net 551)
	)
	(arc
		(start 182.672 140.731572)
		(mid 183.027675 140.584247)
		(end 183.175 140.228572)
		(width 0.141)
		(layer "In5.Cu")
		(net 551)
	)
	(arc
		(start 179.872 139.553)
		(mid 180.227675 139.405675)
		(end 180.375 139.05)
		(width 0.141)
		(layer "In5.Cu")
		(net 551)
	)
	(arc
		(start 180.572 138.674428)
		(mid 180.7113 138.732128)
		(end 180.769 138.871428)
		(width 0.141)
		(layer "In5.Cu")
		(net 551)
	)
	(arc
		(start 180.769 140.228572)
		(mid 180.916325 140.584247)
		(end 181.272 140.731572)
		(width 0.141)
		(layer "In5.Cu")
		(net 551)
	)
	(arc
		(start 164.522214 142.27724)
		(mid 164.57347 142.153496)
		(end 164.522214 142.029752)
		(width 0.141)
		(layer "In5.Cu")
		(net 551)
	)
	(arc
		(start 164.378161 141.885699)
		(mid 164.326905 141.761955)
		(end 164.378161 141.638211)
		(width 0.141)
		(layer "In5.Cu")
		(net 551)
	)
	(arc
		(start 164.274727 142.27724)
		(mid 164.398471 142.328496)
		(end 164.522215 142.27724)
		(width 0.141)
		(layer "In5.Cu")
		(net 551)
	)
	(arc
		(start 181.775 138.871428)
		(mid 181.8327 138.732128)
		(end 181.972 138.674428)
		(width 0.141)
		(layer "In5.Cu")
		(net 551)
	)
	(arc
		(start 163.883188 142.133188)
		(mid 164.006931 142.081932)
		(end 164.130674 142.133188)
		(width 0.141)
		(layer "In5.Cu")
		(net 551)
	)
	(arc
		(start 181.972 138.674428)
		(mid 182.1113 138.732128)
		(end 182.169 138.871428)
		(width 0.141)
		(layer "In5.Cu")
		(net 551)
	)
	(segment
		(start 185.5 138.5)
		(end 185 138)
		(width 0.256)
		(layer "F.Cu")
		(net 552)
	)
	(segment
		(start 169.2 147.2)
		(end 169.6 146.8)
		(width 0.225)
		(layer "F.Cu")
		(net 552)
	)
	(via
		(at 185 138)
		(size 0.45)
		(drill 0.2)
		(layers "F.Cu" "B.Cu")
		(net 552)
	)
	(via
		(at 169.6 146.8)
		(size 0.45)
		(drill 0.2)
		(layers "F.Cu" "B.Cu")
		(net 552)
	)
	(segment
		(start 182.475 138.871428)
		(end 182.475 140.228572)
		(width 0.141)
		(layer "In5.Cu")
		(net 552)
	)
	(segment
		(start 163.586624 144.403)
		(end 163.147 143.963376)
		(width 0.141)
		(layer "In5.Cu")
		(net 552)
	)
	(segment
		(start 166.336624 139.247)
		(end 179.872 139.247)
		(width 0.141)
		(layer "In5.Cu")
		(net 552)
	)
	(segment
		(start 169.6 146.8)
		(end 169.847 146.553)
		(width 0.141)
		(layer "In5.Cu")
		(net 552)
	)
	(segment
		(start 181.075 138.871428)
		(end 181.075 140.228572)
		(width 0.141)
		(layer "In5.Cu")
		(net 552)
	)
	(segment
		(start 185.347 138.347)
		(end 185 138)
		(width 0.141)
		(layer "In5.Cu")
		(net 552)
	)
	(segment
		(start 183.372 139.247)
		(end 183.853 139.247)
		(width 0.141)
		(layer "In5.Cu")
		(net 552)
	)
	(segment
		(start 169.847 145.763376)
		(end 168.486624 144.403)
		(width 0.141)
		(layer "In5.Cu")
		(net 552)
	)
	(segment
		(start 168.486624 144.403)
		(end 163.586624 144.403)
		(width 0.141)
		(layer "In5.Cu")
		(net 552)
	)
	(segment
		(start 181.469 140.228572)
		(end 181.469 138.871428)
		(width 0.141)
		(layer "In5.Cu")
		(net 552)
	)
	(segment
		(start 163.147 142.436624)
		(end 166.336624 139.247)
		(width 0.141)
		(layer "In5.Cu")
		(net 552)
	)
	(segment
		(start 169.847 146.553)
		(end 169.847 145.763376)
		(width 0.141)
		(layer "In5.Cu")
		(net 552)
	)
	(segment
		(start 182.869 140.228572)
		(end 182.869 139.75)
		(width 0.141)
		(layer "In5.Cu")
		(net 552)
	)
	(segment
		(start 184.936624 139.247)
		(end 185.347 138.836624)
		(width 0.141)
		(layer "In5.Cu")
		(net 552)
	)
	(segment
		(start 184.078 139.022)
		(end 184.078 139.015358)
		(width 0.141)
		(layer "In5.Cu")
		(net 552)
	)
	(segment
		(start 180.069 139.05)
		(end 180.069 138.871428)
		(width 0.141)
		(layer "In5.Cu")
		(net 552)
	)
	(segment
		(start 184.528 139.015358)
		(end 184.528 139.022)
		(width 0.141)
		(layer "In5.Cu")
		(net 552)
	)
	(segment
		(start 163.147 143.963376)
		(end 163.147 142.436624)
		(width 0.141)
		(layer "In5.Cu")
		(net 552)
	)
	(segment
		(start 185.347 138.836624)
		(end 185.347 138.347)
		(width 0.141)
		(layer "In5.Cu")
		(net 552)
	)
	(segment
		(start 184.753 139.247)
		(end 184.936624 139.247)
		(width 0.141)
		(layer "In5.Cu")
		(net 552)
	)
	(arc
		(start 182.475 140.228572)
		(mid 182.5327 140.367872)
		(end 182.672 140.425572)
		(width 0.141)
		(layer "In5.Cu")
		(net 552)
	)
	(arc
		(start 184.303 138.790358)
		(mid 184.462099 138.856259)
		(end 184.528 139.015358)
		(width 0.141)
		(layer "In5.Cu")
		(net 552)
	)
	(arc
		(start 181.272 140.425572)
		(mid 181.4113 140.367872)
		(end 181.469 140.228572)
		(width 0.141)
		(layer "In5.Cu")
		(net 552)
	)
	(arc
		(start 184.078 139.015358)
		(mid 184.143901 138.856259)
		(end 184.303 138.790358)
		(width 0.141)
		(layer "In5.Cu")
		(net 552)
	)
	(arc
		(start 181.469 138.871428)
		(mid 181.616325 138.515753)
		(end 181.972 138.368428)
		(width 0.141)
		(layer "In5.Cu")
		(net 552)
	)
	(arc
		(start 181.075 140.228572)
		(mid 181.1327 140.367872)
		(end 181.272 140.425572)
		(width 0.141)
		(layer "In5.Cu")
		(net 552)
	)
	(arc
		(start 180.069 138.871428)
		(mid 180.216325 138.515753)
		(end 180.572 138.368428)
		(width 0.141)
		(layer "In5.Cu")
		(net 552)
	)
	(arc
		(start 182.869 139.75)
		(mid 183.016325 139.394325)
		(end 183.372 139.247)
		(width 0.141)
		(layer "In5.Cu")
		(net 552)
	)
	(arc
		(start 179.872 139.247)
		(mid 180.0113 139.1893)
		(end 180.069 139.05)
		(width 0.141)
		(layer "In5.Cu")
		(net 552)
	)
	(arc
		(start 184.528 139.022)
		(mid 184.593901 139.181099)
		(end 184.753 139.247)
		(width 0.141)
		(layer "In5.Cu")
		(net 552)
	)
	(arc
		(start 183.853 139.247)
		(mid 184.012099 139.181099)
		(end 184.078 139.022)
		(width 0.141)
		(layer "In5.Cu")
		(net 552)
	)
	(arc
		(start 182.672 140.425572)
		(mid 182.8113 140.367872)
		(end 182.869 140.228572)
		(width 0.141)
		(layer "In5.Cu")
		(net 552)
	)
	(arc
		(start 180.572 138.368428)
		(mid 180.927675 138.515753)
		(end 181.075 138.871428)
		(width 0.141)
		(layer "In5.Cu")
		(net 552)
	)
	(arc
		(start 181.972 138.368428)
		(mid 182.327675 138.515753)
		(end 182.475 138.871428)
		(width 0.141)
		(layer "In5.Cu")
		(net 552)
	)
	(segment
		(start 186 144)
		(end 186.5 143.5)
		(width 0.256)
		(layer "F.Cu")
		(net 553)
	)
	(segment
		(start 169.2 142.4)
		(end 168.8 142.8)
		(width 0.256)
		(layer "F.Cu")
		(net 553)
	)
	(via
		(at 186 144)
		(size 0.45)
		(drill 0.2)
		(layers "F.Cu" "B.Cu")
		(net 553)
	)
	(via
		(at 168.8 142.8)
		(size 0.45)
		(drill 0.2)
		(layers "F.Cu" "B.Cu")
		(net 553)
	)
	(segment
		(start 176.2 152.15)
		(end 176.2 142.3)
		(width 0.256)
		(layer "B.Cu")
		(net 553)
	)
	(segment
		(start 185.3 150.925)
		(end 184.811524 150.925)
		(width 0.256)
		(layer "B.Cu")
		(net 553)
	)
	(segment
		(start 184 145.95)
		(end 184.9 145.95)
		(width 0.256)
		(layer "B.Cu")
		(net 553)
	)
	(segment
		(start 185.6 146.65)
		(end 185.6 147.025)
		(width 0.256)
		(layer "B.Cu")
		(net 553)
	)
	(segment
		(start 176.85 152.8)
		(end 176.2 152.15)
		(width 0.256)
		(layer "B.Cu")
		(net 553)
	)
	(segment
		(start 168.399999 144.699999)
		(end 168.4 143.85)
		(width 0.256)
		(layer "B.Cu")
		(net 553)
	)
	(segment
		(start 183.55 145.5)
		(end 184 145.95)
		(width 0.256)
		(layer "B.Cu")
		(net 553)
	)
	(segment
		(start 185.6 152.25)
		(end 185.05 152.8)
		(width 0.256)
		(layer "B.Cu")
		(net 553)
	)
	(segment
		(start 184.9 145.95)
		(end 185.6 146.65)
		(width 0.256)
		(layer "B.Cu")
		(net 553)
	)
	(segment
		(start 184.811524 151.525)
		(end 185.3 151.525)
		(width 0.256)
		(layer "B.Cu")
		(net 553)
	)
	(segment
		(start 184.811524 149.125)
		(end 185.3 149.125)
		(width 0.256)
		(layer "B.Cu")
		(net 553)
	)
	(segment
		(start 185.3 148.525)
		(end 184.811524 148.525)
		(width 0.256)
		(layer "B.Cu")
		(net 553)
	)
	(segment
		(start 185.6 151.875)
		(end 185.6 152.25)
		(width 0.256)
		(layer "B.Cu")
		(net 553)
	)
	(segment
		(start 176.2 142.3)
		(end 174.85 140.95)
		(width 0.256)
		(layer "B.Cu")
		(net 553)
	)
	(segment
		(start 174.85 140.95)
		(end 169.8 140.95)
		(width 0.256)
		(layer "B.Cu")
		(net 553)
	)
	(segment
		(start 168.8 143.034818)
		(end 168.4 143.434818)
		(width 0.15)
		(layer "B.Cu")
		(net 553)
	)
	(segment
		(start 184.811524 150.325)
		(end 185.3 150.325)
		(width 0.256)
		(layer "B.Cu")
		(net 553)
	)
	(segment
		(start 185.3 147.325)
		(end 184.811524 147.325)
		(width 0.256)
		(layer "B.Cu")
		(net 553)
	)
	(segment
		(start 185.3 149.725)
		(end 184.811524 149.725)
		(width 0.256)
		(layer "B.Cu")
		(net 553)
	)
	(segment
		(start 169.8 140.95)
		(end 168.8 141.95)
		(width 0.256)
		(layer "B.Cu")
		(net 553)
	)
	(segment
		(start 186 144)
		(end 184 144)
		(width 0.256)
		(layer "B.Cu")
		(net 553)
	)
	(segment
		(start 168.8 141.95)
		(end 168.8 142.8)
		(width 0.256)
		(layer "B.Cu")
		(net 553)
	)
	(segment
		(start 168.4 143.434818)
		(end 168.4 143.85)
		(width 0.15)
		(layer "B.Cu")
		(net 553)
	)
	(segment
		(start 184.811524 147.925)
		(end 185.3 147.925)
		(width 0.256)
		(layer "B.Cu")
		(net 553)
	)
	(segment
		(start 183.55 144.45)
		(end 183.55 145.5)
		(width 0.256)
		(layer "B.Cu")
		(net 553)
	)
	(segment
		(start 185.6 151.825)
		(end 185.6 151.875)
		(width 0.256)
		(layer "B.Cu")
		(net 553)
	)
	(segment
		(start 184 144)
		(end 183.55 144.45)
		(width 0.256)
		(layer "B.Cu")
		(net 553)
	)
	(segment
		(start 185.05 152.8)
		(end 176.85 152.8)
		(width 0.256)
		(layer "B.Cu")
		(net 553)
	)
	(segment
		(start 168.8 142.8)
		(end 168.8 143.034818)
		(width 0.15)
		(layer "B.Cu")
		(net 553)
	)
	(arc
		(start 185.6 148.225)
		(mid 185.512132 148.437132)
		(end 185.3 148.525)
		(width 0.256)
		(layer "B.Cu")
		(net 553)
	)
	(arc
		(start 185.3 149.125)
		(mid 185.512132 149.212868)
		(end 185.6 149.425)
		(width 0.256)
		(layer "B.Cu")
		(net 553)
	)
	(arc
		(start 185.3 147.925)
		(mid 185.512132 148.012868)
		(end 185.6 148.225)
		(width 0.256)
		(layer "B.Cu")
		(net 553)
	)
	(arc
		(start 184.511524 147.625)
		(mid 184.599392 147.837132)
		(end 184.811524 147.925)
		(width 0.256)
		(layer "B.Cu")
		(net 553)
	)
	(arc
		(start 184.511524 151.225)
		(mid 184.599392 151.437132)
		(end 184.811524 151.525)
		(width 0.256)
		(layer "B.Cu")
		(net 553)
	)
	(arc
		(start 185.3 150.325)
		(mid 185.512132 150.412868)
		(end 185.6 150.625)
		(width 0.256)
		(layer "B.Cu")
		(net 553)
	)
	(arc
		(start 184.811524 147.325)
		(mid 184.599392 147.412868)
		(end 184.511524 147.625)
		(width 0.256)
		(layer "B.Cu")
		(net 553)
	)
	(arc
		(start 184.811524 150.925)
		(mid 184.599392 151.012868)
		(end 184.511524 151.225)
		(width 0.256)
		(layer "B.Cu")
		(net 553)
	)
	(arc
		(start 184.511524 150.025)
		(mid 184.599392 150.237132)
		(end 184.811524 150.325)
		(width 0.256)
		(layer "B.Cu")
		(net 553)
	)
	(arc
		(start 184.811524 148.525)
		(mid 184.599392 148.612868)
		(end 184.511524 148.825)
		(width 0.256)
		(layer "B.Cu")
		(net 553)
	)
	(arc
		(start 185.6 147.025)
		(mid 185.512132 147.237132)
		(end 185.3 147.325)
		(width 0.256)
		(layer "B.Cu")
		(net 553)
	)
	(arc
		(start 185.6 150.625)
		(mid 185.512132 150.837132)
		(end 185.3 150.925)
		(width 0.256)
		(layer "B.Cu")
		(net 553)
	)
	(arc
		(start 185.3 151.525)
		(mid 185.512132 151.612868)
		(end 185.6 151.825)
		(width 0.256)
		(layer "B.Cu")
		(net 553)
	)
	(arc
		(start 184.511524 148.825)
		(mid 184.599392 149.037132)
		(end 184.811524 149.125)
		(width 0.256)
		(layer "B.Cu")
		(net 553)
	)
	(arc
		(start 185.6 149.425)
		(mid 185.512132 149.637132)
		(end 185.3 149.725)
		(width 0.256)
		(layer "B.Cu")
		(net 553)
	)
	(arc
		(start 184.811524 149.725)
		(mid 184.599392 149.812868)
		(end 184.511524 150.025)
		(width 0.256)
		(layer "B.Cu")
		(net 553)
	)
	(segment
		(start 164 142.8)
		(end 164.4 143.2)
		(width 0.256)
		(layer "F.Cu")
		(net 554)
	)
	(segment
		(start 188.5 142.5)
		(end 188 143)
		(width 0.256)
		(layer "F.Cu")
		(net 554)
	)
	(via
		(at 188 143)
		(size 0.45)
		(drill 0.2)
		(layers "F.Cu" "B.Cu")
		(net 554)
	)
	(via
		(at 164 142.8)
		(size 0.45)
		(drill 0.2)
		(layers "F.Cu" "B.Cu")
		(net 554)
	)
	(segment
		(start 177.125 144.259195)
		(end 177.125 142.790805)
		(width 0.157)
		(layer "In7.Cu")
		(net 554)
	)
	(segment
		(start 175.325 143.3)
		(end 175.325 142.790805)
		(width 0.157)
		(layer "In7.Cu")
		(net 554)
	)
	(segment
		(start 175.775 142.790805)
		(end 175.775 144.259195)
		(width 0.157)
		(layer "In7.Cu")
		(net 554)
	)
	(segment
		(start 177.575 142.790805)
		(end 177.575 144.259195)
		(width 0.157)
		(layer "In7.Cu")
		(net 554)
	)
	(segment
		(start 173.675 143.525)
		(end 175.1 143.525)
		(width 0.157)
		(layer "In7.Cu")
		(net 554)
	)
	(segment
		(start 164 142.8)
		(end 163.575 143.225)
		(width 0.157)
		(layer "In7.Cu")
		(net 554)
	)
	(segment
		(start 178.025 144.259195)
		(end 178.025 142.790805)
		(width 0.157)
		(layer "In7.Cu")
		(net 554)
	)
	(segment
		(start 179.15 143.525)
		(end 187.475 143.525)
		(width 0.157)
		(layer "In7.Cu")
		(net 554)
	)
	(segment
		(start 187.475 143.525)
		(end 188 143)
		(width 0.157)
		(layer "In7.Cu")
		(net 554)
	)
	(segment
		(start 176.675 142.790805)
		(end 176.675 144.259195)
		(width 0.157)
		(layer "In7.Cu")
		(net 554)
	)
	(segment
		(start 170.675 144.825)
		(end 171.425 144.075)
		(width 0.157)
		(layer "In7.Cu")
		(net 554)
	)
	(segment
		(start 176.225 144.259195)
		(end 176.225 142.790805)
		(width 0.157)
		(layer "In7.Cu")
		(net 554)
	)
	(segment
		(start 164.025 144.825)
		(end 170.675 144.825)
		(width 0.157)
		(layer "In7.Cu")
		(net 554)
	)
	(segment
		(start 178.475 142.790805)
		(end 178.475 144.259195)
		(width 0.157)
		(layer "In7.Cu")
		(net 554)
	)
	(segment
		(start 173.125 144.075)
		(end 173.675 143.525)
		(width 0.157)
		(layer "In7.Cu")
		(net 554)
	)
	(segment
		(start 163.575 144.375)
		(end 164.025 144.825)
		(width 0.157)
		(layer "In7.Cu")
		(net 554)
	)
	(segment
		(start 178.925 144.259195)
		(end 178.925 143.75)
		(width 0.157)
		(layer "In7.Cu")
		(net 554)
	)
	(segment
		(start 171.425 144.075)
		(end 173.125 144.075)
		(width 0.157)
		(layer "In7.Cu")
		(net 554)
	)
	(segment
		(start 163.575 143.225)
		(end 163.575 144.375)
		(width 0.157)
		(layer "In7.Cu")
		(net 554)
	)
	(arc
		(start 177.575 144.259195)
		(mid 177.640901 144.418294)
		(end 177.8 144.484195)
		(width 0.157)
		(layer "In7.Cu")
		(net 554)
	)
	(arc
		(start 176.45 142.565805)
		(mid 176.609099 142.631706)
		(end 176.675 142.790805)
		(width 0.157)
		(layer "In7.Cu")
		(net 554)
	)
	(arc
		(start 175.1 143.525)
		(mid 175.259099 143.459099)
		(end 175.325 143.3)
		(width 0.157)
		(layer "In7.Cu")
		(net 554)
	)
	(arc
		(start 178.25 142.565805)
		(mid 178.409099 142.631706)
		(end 178.475 142.790805)
		(width 0.157)
		(layer "In7.Cu")
		(net 554)
	)
	(arc
		(start 176 144.484195)
		(mid 176.159099 144.418294)
		(end 176.225 144.259195)
		(width 0.157)
		(layer "In7.Cu")
		(net 554)
	)
	(arc
		(start 178.475 144.259195)
		(mid 178.540901 144.418294)
		(end 178.7 144.484195)
		(width 0.157)
		(layer "In7.Cu")
		(net 554)
	)
	(arc
		(start 176.9 144.484195)
		(mid 177.059099 144.418294)
		(end 177.125 144.259195)
		(width 0.157)
		(layer "In7.Cu")
		(net 554)
	)
	(arc
		(start 175.325 142.790805)
		(mid 175.390901 142.631706)
		(end 175.55 142.565805)
		(width 0.157)
		(layer "In7.Cu")
		(net 554)
	)
	(arc
		(start 175.55 142.565805)
		(mid 175.709099 142.631706)
		(end 175.775 142.790805)
		(width 0.157)
		(layer "In7.Cu")
		(net 554)
	)
	(arc
		(start 176.225 142.790805)
		(mid 176.290901 142.631706)
		(end 176.45 142.565805)
		(width 0.157)
		(layer "In7.Cu")
		(net 554)
	)
	(arc
		(start 175.775 144.259195)
		(mid 175.840901 144.418294)
		(end 176 144.484195)
		(width 0.157)
		(layer "In7.Cu")
		(net 554)
	)
	(arc
		(start 178.025 142.790805)
		(mid 178.090901 142.631706)
		(end 178.25 142.565805)
		(width 0.157)
		(layer "In7.Cu")
		(net 554)
	)
	(arc
		(start 178.7 144.484195)
		(mid 178.859099 144.418294)
		(end 178.925 144.259195)
		(width 0.157)
		(layer "In7.Cu")
		(net 554)
	)
	(arc
		(start 177.35 142.565805)
		(mid 177.509099 142.631706)
		(end 177.575 142.790805)
		(width 0.157)
		(layer "In7.Cu")
		(net 554)
	)
	(arc
		(start 178.925 143.75)
		(mid 178.990901 143.590901)
		(end 179.15 143.525)
		(width 0.157)
		(layer "In7.Cu")
		(net 554)
	)
	(arc
		(start 177.125 142.790805)
		(mid 177.190901 142.631706)
		(end 177.35 142.565805)
		(width 0.157)
		(layer "In7.Cu")
		(net 554)
	)
	(arc
		(start 177.8 144.484195)
		(mid 177.959099 144.418294)
		(end 178.025 144.259195)
		(width 0.157)
		(layer "In7.Cu")
		(net 554)
	)
	(arc
		(start 176.675 144.259195)
		(mid 176.740901 144.418294)
		(end 176.9 144.484195)
		(width 0.157)
		(layer "In7.Cu")
		(net 554)
	)
	(segment
		(start 171.185 151.26)
		(end 171.185 152)
		(width 0.157)
		(layer "F.Cu")
		(net 555)
	)
	(segment
		(start 168.4 148)
		(end 168.8 147.6)
		(width 0.256)
		(layer "F.Cu")
		(net 555)
	)
	(segment
		(start 171.175 151.25)
		(end 171.185 151.26)
		(width 0.157)
		(layer "F.Cu")
		(net 555)
	)
	(via
		(at 171.175 151.25)
		(size 0.45)
		(drill 0.2)
		(layers "F.Cu" "B.Cu")
		(net 555)
	)
	(via
		(at 168.8 147.6)
		(size 0.45)
		(drill 0.2)
		(layers "F.Cu" "B.Cu")
		(net 555)
	)
	(segment
		(start 169.4 149.475)
		(end 171.175 151.25)
		(width 0.157)
		(layer "In3.Cu")
		(net 555)
	)
	(segment
		(start 169.225 148.025002)
		(end 169.225 148.05)
		(width 0.1)
		(layer "In3.Cu")
		(net 555)
	)
	(segment
		(start 168.8 147.600002)
		(end 169.225 148.025002)
		(width 0.1)
		(layer "In3.Cu")
		(net 555)
	)
	(segment
		(start 169.225 148.95)
		(end 169.4 149.125)
		(width 0.1)
		(layer "In3.Cu")
		(net 555)
	)
	(segment
		(start 169.225 148.05)
		(end 169.225 148.95)
		(width 0.1)
		(layer "In3.Cu")
		(net 555)
	)
	(segment
		(start 169.4 149.125)
		(end 169.4 149.475)
		(width 0.157)
		(layer "In3.Cu")
		(net 555)
	)
	(segment
		(start 220.625 132.525)
		(end 220.25 132.9)
		(width 0.184)
		(layer "F.Cu")
		(net 556)
	)
	(segment
		(start 211.5 132.5)
		(end 212 133)
		(width 0.256)
		(layer "F.Cu")
		(net 556)
	)
	(via
		(at 220.25 132.9)
		(size 0.45)
		(drill 0.2)
		(layers "F.Cu" "B.Cu")
		(net 556)
	)
	(via
		(at 212 133)
		(size 0.45)
		(drill 0.2)
		(layers "F.Cu" "B.Cu")
		(net 556)
	)
	(segment
		(start 218.4 133)
		(end 220.15 133)
		(width 0.184)
		(layer "B.Cu")
		(net 556)
	)
	(segment
		(start 220.15 133)
		(end 220.25 132.9)
		(width 0.184)
		(layer "B.Cu")
		(net 556)
	)
	(segment
		(start 212.375 132.625)
		(end 212 133)
		(width 0.1)
		(layer "In5.Cu")
		(net 556)
	)
	(segment
		(start 219.975 132.625)
		(end 212.375 132.625)
		(width 0.1)
		(layer "In5.Cu")
		(net 556)
	)
	(segment
		(start 220.25 132.9)
		(end 219.975 132.625)
		(width 0.1)
		(layer "In5.Cu")
		(net 556)
	)
	(segment
		(start 192.5 140.5)
		(end 192.0177 140.9823)
		(width 0.256)
		(layer "F.Cu")
		(net 557)
	)
	(segment
		(start 173.2 147.2)
		(end 173.6 146.8)
		(width 0.256)
		(layer "F.Cu")
		(net 557)
	)
	(segment
		(start 192.0177 140.9823)
		(end 192.005766 140.9823)
		(width 0.256)
		(layer "F.Cu")
		(net 557)
	)
	(via
		(at 173.6 146.8)
		(size 0.45)
		(drill 0.2)
		(layers "F.Cu" "B.Cu")
		(net 557)
	)
	(via
		(at 192.005766 140.9823)
		(size 0.45)
		(drill 0.2)
		(layers "F.Cu" "B.Cu")
		(net 557)
	)
	(segment
		(start 174.71 146.8)
		(end 175.424999 147.514999)
		(width 0.256)
		(layer "B.Cu")
		(net 557)
	)
	(segment
		(start 173.6 146.8)
		(end 174.71 146.8)
		(width 0.256)
		(layer "B.Cu")
		(net 557)
	)
	(segment
		(start 178.65 157.325)
		(end 174.2 152.875)
		(width 0.157)
		(layer "In5.Cu")
		(net 557)
	)
	(segment
		(start 180.225 157.55)
		(end 180.225 157.773408)
		(width 0.157)
		(layer "In5.Cu")
		(net 557)
	)
	(segment
		(start 185.625 157.55)
		(end 185.625 157.773408)
		(width 0.157)
		(layer "In5.Cu")
		(net 557)
	)
	(segment
		(start 187.875 157.773408)
		(end 187.875 157.55)
		(width 0.157)
		(layer "In5.Cu")
		(net 557)
	)
	(segment
		(start 193.5 142.476534)
		(end 193.5 154.35)
		(width 0.157)
		(layer "In5.Cu")
		(net 557)
	)
	(segment
		(start 181.125 157.55)
		(end 181.125 157.773408)
		(width 0.157)
		(layer "In5.Cu")
		(net 557)
	)
	(segment
		(start 172.175 148.825)
		(end 172.175 148.225)
		(width 0.157)
		(layer "In5.Cu")
		(net 557)
	)
	(segment
		(start 172.175 148.225)
		(end 173.6 146.8)
		(width 0.157)
		(layer "In5.Cu")
		(net 557)
	)
	(segment
		(start 185.175 157.773408)
		(end 185.175 157.55)
		(width 0.157)
		(layer "In5.Cu")
		(net 557)
	)
	(segment
		(start 187.425 157.55)
		(end 187.425 157.773408)
		(width 0.157)
		(layer "In5.Cu")
		(net 557)
	)
	(segment
		(start 183.825 157.55)
		(end 183.825 157.773408)
		(width 0.157)
		(layer "In5.Cu")
		(net 557)
	)
	(segment
		(start 186.075 157.773408)
		(end 186.075 157.55)
		(width 0.157)
		(layer "In5.Cu")
		(net 557)
	)
	(segment
		(start 182.925 157.55)
		(end 182.925 157.773408)
		(width 0.157)
		(layer "In5.Cu")
		(net 557)
	)
	(segment
		(start 174.2 150.85)
		(end 172.175 148.825)
		(width 0.157)
		(layer "In5.Cu")
		(net 557)
	)
	(segment
		(start 188.325 157.55)
		(end 188.325 157.773408)
		(width 0.157)
		(layer "In5.Cu")
		(net 557)
	)
	(segment
		(start 184.275 157.773408)
		(end 184.275 157.55)
		(width 0.157)
		(layer "In5.Cu")
		(net 557)
	)
	(segment
		(start 180.675 157.773408)
		(end 180.675 157.55)
		(width 0.157)
		(layer "In5.Cu")
		(net 557)
	)
	(segment
		(start 186.525 157.55)
		(end 186.525 157.773408)
		(width 0.157)
		(layer "In5.Cu")
		(net 557)
	)
	(segment
		(start 190.525 157.325)
		(end 188.55 157.325)
		(width 0.157)
		(layer "In5.Cu")
		(net 557)
	)
	(segment
		(start 182.475 157.773408)
		(end 182.475 157.55)
		(width 0.157)
		(layer "In5.Cu")
		(net 557)
	)
	(segment
		(start 186.975 157.773408)
		(end 186.975 157.55)
		(width 0.157)
		(layer "In5.Cu")
		(net 557)
	)
	(segment
		(start 179.775 157.773408)
		(end 179.775 157.55)
		(width 0.157)
		(layer "In5.Cu")
		(net 557)
	)
	(segment
		(start 193.5 154.35)
		(end 190.525 157.325)
		(width 0.157)
		(layer "In5.Cu")
		(net 557)
	)
	(segment
		(start 174.2 152.875)
		(end 174.2 150.85)
		(width 0.157)
		(layer "In5.Cu")
		(net 557)
	)
	(segment
		(start 183.375 157.773408)
		(end 183.375 157.55)
		(width 0.157)
		(layer "In5.Cu")
		(net 557)
	)
	(segment
		(start 182.025 157.55)
		(end 182.025 157.773408)
		(width 0.157)
		(layer "In5.Cu")
		(net 557)
	)
	(segment
		(start 181.575 157.773408)
		(end 181.575 157.55)
		(width 0.157)
		(layer "In5.Cu")
		(net 557)
	)
	(segment
		(start 192.005766 140.9823)
		(end 193.5 142.476534)
		(width 0.157)
		(layer "In5.Cu")
		(net 557)
	)
	(segment
		(start 184.725 157.55)
		(end 184.725 157.773408)
		(width 0.157)
		(layer "In5.Cu")
		(net 557)
	)
	(segment
		(start 179.55 157.325)
		(end 178.65 157.325)
		(width 0.157)
		(layer "In5.Cu")
		(net 557)
	)
	(arc
		(start 182.925 157.773408)
		(mid 182.859099 157.932507)
		(end 182.7 157.998408)
		(width 0.157)
		(layer "In5.Cu")
		(net 557)
	)
	(arc
		(start 181.8 157.998408)
		(mid 181.640901 157.932507)
		(end 181.575 157.773408)
		(width 0.157)
		(layer "In5.Cu")
		(net 557)
	)
	(arc
		(start 184.725 157.773408)
		(mid 184.659099 157.932507)
		(end 184.5 157.998408)
		(width 0.157)
		(layer "In5.Cu")
		(net 557)
	)
	(arc
		(start 182.7 157.998408)
		(mid 182.540901 157.932507)
		(end 182.475 157.773408)
		(width 0.157)
		(layer "In5.Cu")
		(net 557)
	)
	(arc
		(start 184.5 157.998408)
		(mid 184.340901 157.932507)
		(end 184.275 157.773408)
		(width 0.157)
		(layer "In5.Cu")
		(net 557)
	)
	(arc
		(start 184.95 157.325)
		(mid 184.790901 157.390901)
		(end 184.725 157.55)
		(width 0.157)
		(layer "In5.Cu")
		(net 557)
	)
	(arc
		(start 182.25 157.325)
		(mid 182.090901 157.390901)
		(end 182.025 157.55)
		(width 0.157)
		(layer "In5.Cu")
		(net 557)
	)
	(arc
		(start 180.9 157.998408)
		(mid 180.740901 157.932507)
		(end 180.675 157.773408)
		(width 0.157)
		(layer "In5.Cu")
		(net 557)
	)
	(arc
		(start 185.4 157.998408)
		(mid 185.240901 157.932507)
		(end 185.175 157.773408)
		(width 0.157)
		(layer "In5.Cu")
		(net 557)
	)
	(arc
		(start 180.675 157.55)
		(mid 180.609099 157.390901)
		(end 180.45 157.325)
		(width 0.157)
		(layer "In5.Cu")
		(net 557)
	)
	(arc
		(start 179.775 157.55)
		(mid 179.709099 157.390901)
		(end 179.55 157.325)
		(width 0.157)
		(layer "In5.Cu")
		(net 557)
	)
	(arc
		(start 182.475 157.55)
		(mid 182.409099 157.390901)
		(end 182.25 157.325)
		(width 0.157)
		(layer "In5.Cu")
		(net 557)
	)
	(arc
		(start 185.175 157.55)
		(mid 185.109099 157.390901)
		(end 184.95 157.325)
		(width 0.157)
		(layer "In5.Cu")
		(net 557)
	)
	(arc
		(start 187.875 157.55)
		(mid 187.809099 157.390901)
		(end 187.65 157.325)
		(width 0.157)
		(layer "In5.Cu")
		(net 557)
	)
	(arc
		(start 184.275 157.55)
		(mid 184.209099 157.390901)
		(end 184.05 157.325)
		(width 0.157)
		(layer "In5.Cu")
		(net 557)
	)
	(arc
		(start 182.025 157.773408)
		(mid 181.959099 157.932507)
		(end 181.8 157.998408)
		(width 0.157)
		(layer "In5.Cu")
		(net 557)
	)
	(arc
		(start 188.55 157.325)
		(mid 188.390901 157.390901)
		(end 188.325 157.55)
		(width 0.157)
		(layer "In5.Cu")
		(net 557)
	)
	(arc
		(start 186.75 157.325)
		(mid 186.590901 157.390901)
		(end 186.525 157.55)
		(width 0.157)
		(layer "In5.Cu")
		(net 557)
	)
	(arc
		(start 186.3 157.998408)
		(mid 186.140901 157.932507)
		(end 186.075 157.773408)
		(width 0.157)
		(layer "In5.Cu")
		(net 557)
	)
	(arc
		(start 187.425 157.773408)
		(mid 187.359099 157.932507)
		(end 187.2 157.998408)
		(width 0.157)
		(layer "In5.Cu")
		(net 557)
	)
	(arc
		(start 181.35 157.325)
		(mid 181.190901 157.390901)
		(end 181.125 157.55)
		(width 0.157)
		(layer "In5.Cu")
		(net 557)
	)
	(arc
		(start 186.975 157.55)
		(mid 186.909099 157.390901)
		(end 186.75 157.325)
		(width 0.157)
		(layer "In5.Cu")
		(net 557)
	)
	(arc
		(start 186.525 157.773408)
		(mid 186.459099 157.932507)
		(end 186.3 157.998408)
		(width 0.157)
		(layer "In5.Cu")
		(net 557)
	)
	(arc
		(start 181.125 157.773408)
		(mid 181.059099 157.932507)
		(end 180.9 157.998408)
		(width 0.157)
		(layer "In5.Cu")
		(net 557)
	)
	(arc
		(start 188.1 157.998408)
		(mid 187.940901 157.932507)
		(end 187.875 157.773408)
		(width 0.157)
		(layer "In5.Cu")
		(net 557)
	)
	(arc
		(start 183.375 157.55)
		(mid 183.309099 157.390901)
		(end 183.15 157.325)
		(width 0.157)
		(layer "In5.Cu")
		(net 557)
	)
	(arc
		(start 181.575 157.55)
		(mid 181.509099 157.390901)
		(end 181.35 157.325)
		(width 0.157)
		(layer "In5.Cu")
		(net 557)
	)
	(arc
		(start 180.225 157.773408)
		(mid 180.159099 157.932507)
		(end 180 157.998408)
		(width 0.157)
		(layer "In5.Cu")
		(net 557)
	)
	(arc
		(start 188.325 157.773408)
		(mid 188.259099 157.932507)
		(end 188.1 157.998408)
		(width 0.157)
		(layer "In5.Cu")
		(net 557)
	)
	(arc
		(start 187.2 157.998408)
		(mid 187.040901 157.932507)
		(end 186.975 157.773408)
		(width 0.157)
		(layer "In5.Cu")
		(net 557)
	)
	(arc
		(start 185.85 157.325)
		(mid 185.690901 157.390901)
		(end 185.625 157.55)
		(width 0.157)
		(layer "In5.Cu")
		(net 557)
	)
	(arc
		(start 180.45 157.325)
		(mid 180.290901 157.390901)
		(end 180.225 157.55)
		(width 0.157)
		(layer "In5.Cu")
		(net 557)
	)
	(arc
		(start 183.6 157.998408)
		(mid 183.440901 157.932507)
		(end 183.375 157.773408)
		(width 0.157)
		(layer "In5.Cu")
		(net 557)
	)
	(arc
		(start 185.625 157.773408)
		(mid 185.559099 157.932507)
		(end 185.4 157.998408)
		(width 0.157)
		(layer "In5.Cu")
		(net 557)
	)
	(arc
		(start 180 157.998408)
		(mid 179.840901 157.932507)
		(end 179.775 157.773408)
		(width 0.157)
		(layer "In5.Cu")
		(net 557)
	)
	(arc
		(start 184.05 157.325)
		(mid 183.890901 157.390901)
		(end 183.825 157.55)
		(width 0.157)
		(layer "In5.Cu")
		(net 557)
	)
	(arc
		(start 183.825 157.773408)
		(mid 183.759099 157.932507)
		(end 183.6 157.998408)
		(width 0.157)
		(layer "In5.Cu")
		(net 557)
	)
	(arc
		(start 183.15 157.325)
		(mid 182.990901 157.390901)
		(end 182.925 157.55)
		(width 0.157)
		(layer "In5.Cu")
		(net 557)
	)
	(arc
		(start 186.075 157.55)
		(mid 186.009099 157.390901)
		(end 185.85 157.325)
		(width 0.157)
		(layer "In5.Cu")
		(net 557)
	)
	(arc
		(start 187.65 157.325)
		(mid 187.490901 157.390901)
		(end 187.425 157.55)
		(width 0.157)
		(layer "In5.Cu")
		(net 557)
	)
	(segment
		(start 186.5 141.5)
		(end 186 142)
		(width 0.256)
		(layer "F.Cu")
		(net 558)
	)
	(segment
		(start 168 143.6)
		(end 168.4 144)
		(width 0.256)
		(layer "F.Cu")
		(net 558)
	)
	(via
		(at 186 142)
		(size 0.45)
		(drill 0.2)
		(layers "F.Cu" "B.Cu")
		(net 558)
	)
	(via
		(at 168 143.6)
		(size 0.45)
		(drill 0.2)
		(layers "F.Cu" "B.Cu")
		(net 558)
	)
	(segment
		(start 169.5 140.15)
		(end 175.3 140.15)
		(width 0.256)
		(layer "B.Cu")
		(net 558)
	)
	(segment
		(start 183.6 151.075)
		(end 183.024486 151.075)
		(width 0.256)
		(layer "B.Cu")
		(net 558)
	)
	(segment
		(start 168.4 142.55)
		(end 168.4 141.25)
		(width 0.256)
		(layer "B.Cu")
		(net 558)
	)
	(segment
		(start 183.7 143.5)
		(end 185.2 143.5)
		(width 0.256)
		(layer "B.Cu")
		(net 558)
	)
	(segment
		(start 183.024486 147.575)
		(end 183.6 147.575)
		(width 0.256)
		(layer "B.Cu")
		(net 558)
	)
	(segment
		(start 183.024486 150.575)
		(end 183.6 150.575)
		(width 0.256)
		(layer "B.Cu")
		(net 558)
	)
	(segment
		(start 183.6 150.075)
		(end 183.024486 150.075)
		(width 0.256)
		(layer "B.Cu")
		(net 558)
	)
	(segment
		(start 183 144.2)
		(end 183.7 143.5)
		(width 0.256)
		(layer "B.Cu")
		(net 558)
	)
	(segment
		(start 185.2 143.5)
		(end 185.5 143.2)
		(width 0.256)
		(layer "B.Cu")
		(net 558)
	)
	(segment
		(start 185.5 142.5)
		(end 186 142)
		(width 0.256)
		(layer "B.Cu")
		(net 558)
	)
	(segment
		(start 175.3 140.15)
		(end 176.9 141.75)
		(width 0.256)
		(layer "B.Cu")
		(net 558)
	)
	(segment
		(start 183.85 151.55)
		(end 183.85 151.325)
		(width 0.256)
		(layer "B.Cu")
		(net 558)
	)
	(segment
		(start 183.85 147.325)
		(end 183.85 147.275)
		(width 0.256)
		(layer "B.Cu")
		(net 558)
	)
	(segment
		(start 183.6 148.075)
		(end 183.024486 148.075)
		(width 0.256)
		(layer "B.Cu")
		(net 558)
	)
	(segment
		(start 177.55 152.1)
		(end 183.3 152.1)
		(width 0.256)
		(layer "B.Cu")
		(net 558)
	)
	(segment
		(start 167.999999 144.699999)
		(end 168 143.6)
		(width 0.256)
		(layer "B.Cu")
		(net 558)
	)
	(segment
		(start 183.6 149.075)
		(end 183.024486 149.075)
		(width 0.256)
		(layer "B.Cu")
		(net 558)
	)
	(segment
		(start 183 146.2)
		(end 183 144.2)
		(width 0.256)
		(layer "B.Cu")
		(net 558)
	)
	(segment
		(start 185.5 143.2)
		(end 185.5 142.5)
		(width 0.256)
		(layer "B.Cu")
		(net 558)
	)
	(segment
		(start 183.85 147.275)
		(end 183.85 147.05)
		(width 0.256)
		(layer "B.Cu")
		(net 558)
	)
	(segment
		(start 176.9 141.75)
		(end 176.9 151.45)
		(width 0.256)
		(layer "B.Cu")
		(net 558)
	)
	(segment
		(start 168 143.6)
		(end 168 143.425)
		(width 0.15)
		(layer "B.Cu")
		(net 558)
	)
	(segment
		(start 168.4 141.25)
		(end 169.5 140.15)
		(width 0.256)
		(layer "B.Cu")
		(net 558)
	)
	(segment
		(start 183.85 147.05)
		(end 183 146.2)
		(width 0.256)
		(layer "B.Cu")
		(net 558)
	)
	(segment
		(start 176.9 151.45)
		(end 177.55 152.1)
		(width 0.256)
		(layer "B.Cu")
		(net 558)
	)
	(segment
		(start 183.024486 148.575)
		(end 183.6 148.575)
		(width 0.256)
		(layer "B.Cu")
		(net 558)
	)
	(segment
		(start 168 143.425)
		(end 168.4 143.025)
		(width 0.15)
		(layer "B.Cu")
		(net 558)
	)
	(segment
		(start 183.3 152.1)
		(end 183.85 151.55)
		(width 0.256)
		(layer "B.Cu")
		(net 558)
	)
	(segment
		(start 183.024486 149.575)
		(end 183.6 149.575)
		(width 0.256)
		(layer "B.Cu")
		(net 558)
	)
	(segment
		(start 168.4 143.025)
		(end 168.4 142.55)
		(width 0.15)
		(layer "B.Cu")
		(net 558)
	)
	(arc
		(start 183.024486 150.075)
		(mid 182.847709 150.001777)
		(end 182.774486 149.825)
		(width 0.256)
		(layer "B.Cu")
		(net 558)
	)
	(arc
		(start 183.85 150.325)
		(mid 183.776777 150.148223)
		(end 183.6 150.075)
		(width 0.256)
		(layer "B.Cu")
		(net 558)
	)
	(arc
		(start 183.6 150.575)
		(mid 183.776777 150.501777)
		(end 183.85 150.325)
		(width 0.256)
		(layer "B.Cu")
		(net 558)
	)
	(arc
		(start 183.6 148.575)
		(mid 183.776777 148.501777)
		(end 183.85 148.325)
		(width 0.256)
		(layer "B.Cu")
		(net 558)
	)
	(arc
		(start 182.774486 149.825)
		(mid 182.847709 149.648223)
		(end 183.024486 149.575)
		(width 0.256)
		(layer "B.Cu")
		(net 558)
	)
	(arc
		(start 183.85 149.325)
		(mid 183.776777 149.148223)
		(end 183.6 149.075)
		(width 0.256)
		(layer "B.Cu")
		(net 558)
	)
	(arc
		(start 183.024486 151.075)
		(mid 182.847709 151.001777)
		(end 182.774486 150.825)
		(width 0.256)
		(layer "B.Cu")
		(net 558)
	)
	(arc
		(start 182.774486 148.825)
		(mid 182.847709 148.648223)
		(end 183.024486 148.575)
		(width 0.256)
		(layer "B.Cu")
		(net 558)
	)
	(arc
		(start 182.774486 147.825)
		(mid 182.847709 147.648223)
		(end 183.024486 147.575)
		(width 0.256)
		(layer "B.Cu")
		(net 558)
	)
	(arc
		(start 183.6 149.575)
		(mid 183.776777 149.501777)
		(end 183.85 149.325)
		(width 0.256)
		(layer "B.Cu")
		(net 558)
	)
	(arc
		(start 183.85 148.325)
		(mid 183.776777 148.148223)
		(end 183.6 148.075)
		(width 0.256)
		(layer "B.Cu")
		(net 558)
	)
	(arc
		(start 183.024486 149.075)
		(mid 182.847709 149.001777)
		(end 182.774486 148.825)
		(width 0.256)
		(layer "B.Cu")
		(net 558)
	)
	(arc
		(start 183.85 151.325)
		(mid 183.776777 151.148223)
		(end 183.6 151.075)
		(width 0.256)
		(layer "B.Cu")
		(net 558)
	)
	(arc
		(start 183.6 147.575)
		(mid 183.776777 147.501777)
		(end 183.85 147.325)
		(width 0.256)
		(layer "B.Cu")
		(net 558)
	)
	(arc
		(start 183.024486 148.075)
		(mid 182.847709 148.001777)
		(end 182.774486 147.825)
		(width 0.256)
		(layer "B.Cu")
		(net 558)
	)
	(arc
		(start 182.774486 150.825)
		(mid 182.847709 150.648223)
		(end 183.024486 150.575)
		(width 0.256)
		(layer "B.Cu")
		(net 558)
	)
	(segment
		(start 190.003303 140.996697)
		(end 189.984597 140.996697)
		(width 0.256)
		(layer "F.Cu")
		(net 559)
	)
	(segment
		(start 168.8 143.6)
		(end 169.2 144)
		(width 0.256)
		(layer "F.Cu")
		(net 559)
	)
	(segment
		(start 190.5 140.5)
		(end 190.003303 140.996697)
		(width 0.256)
		(layer "F.Cu")
		(net 559)
	)
	(via
		(at 189.984597 140.996697)
		(size 0.45)
		(drill 0.2)
		(layers "F.Cu" "B.Cu")
		(net 559)
	)
	(via
		(at 168.8 143.6)
		(size 0.45)
		(drill 0.2)
		(layers "F.Cu" "B.Cu")
		(net 559)
	)
	(segment
		(start 168.8 146.099998)
		(end 168.399999 146.499999)
		(width 0.256)
		(layer "B.Cu")
		(net 559)
	)
	(segment
		(start 168.8 143.600504)
		(end 168.8 146.099998)
		(width 0.256)
		(layer "B.Cu")
		(net 559)
	)
	(segment
		(start 168.4 143.2)
		(end 168.4 142.95)
		(width 0.157)
		(layer "In7.Cu")
		(net 559)
	)
	(segment
		(start 178.475 140.975)
		(end 178.475 140.36139)
		(width 0.157)
		(layer "In7.Cu")
		(net 559)
	)
	(segment
		(start 171.275 140.975)
		(end 171.275 140.36139)
		(width 0.157)
		(layer "In7.Cu")
		(net 559)
	)
	(segment
		(start 189.984597 140.996697)
		(end 189.481294 141.5)
		(width 0.157)
		(layer "In7.Cu")
		(net 559)
	)
	(segment
		(start 169.7 141.2)
		(end 169.35 141.2)
		(width 0.157)
		(layer "In7.Cu")
		(net 559)
	)
	(segment
		(start 184.4 141.2)
		(end 178.7 141.2)
		(width 0.157)
		(layer "In7.Cu")
		(net 559)
	)
	(segment
		(start 175.775 140.975)
		(end 175.775 140.36139)
		(width 0.157)
		(layer "In7.Cu")
		(net 559)
	)
	(segment
		(start 171.725 140.36139)
		(end 171.725 140.975)
		(width 0.157)
		(layer "In7.Cu")
		(net 559)
	)
	(segment
		(start 184.7 141.5)
		(end 184.4 141.2)
		(width 0.157)
		(layer "In7.Cu")
		(net 559)
	)
	(segment
		(start 169.925 140.36139)
		(end 169.925 140.975)
		(width 0.157)
		(layer "In7.Cu")
		(net 559)
	)
	(segment
		(start 176.225 140.36139)
		(end 176.225 140.975)
		(width 0.157)
		(layer "In7.Cu")
		(net 559)
	)
	(segment
		(start 173.075 140.975)
		(end 173.075 140.36139)
		(width 0.157)
		(layer "In7.Cu")
		(net 559)
	)
	(segment
		(start 173.525 140.36139)
		(end 173.525 140.975)
		(width 0.157)
		(layer "In7.Cu")
		(net 559)
	)
	(segment
		(start 170.825 140.36139)
		(end 170.825 140.975)
		(width 0.157)
		(layer "In7.Cu")
		(net 559)
	)
	(segment
		(start 178.025 140.36139)
		(end 178.025 140.975)
		(width 0.157)
		(layer "In7.Cu")
		(net 559)
	)
	(segment
		(start 177.575 140.975)
		(end 177.575 140.36139)
		(width 0.157)
		(layer "In7.Cu")
		(net 559)
	)
	(segment
		(start 168.8 143.6)
		(end 168.4 143.2)
		(width 0.157)
		(layer "In7.Cu")
		(net 559)
	)
	(segment
		(start 168.399998 142.949998)
		(end 168.399998 142.675)
		(width 0.15)
		(layer "In7.Cu")
		(net 559)
	)
	(segment
		(start 169.35 141.2)
		(end 168.399998 142.150002)
		(width 0.157)
		(layer "In7.Cu")
		(net 559)
	)
	(segment
		(start 189.481294 141.5)
		(end 184.7 141.5)
		(width 0.157)
		(layer "In7.Cu")
		(net 559)
	)
	(segment
		(start 175.325 140.36139)
		(end 175.325 140.975)
		(width 0.157)
		(layer "In7.Cu")
		(net 559)
	)
	(segment
		(start 168.4 142.95)
		(end 168.399998 142.949998)
		(width 0.157)
		(layer "In7.Cu")
		(net 559)
	)
	(segment
		(start 168.399998 142.150002)
		(end 168.399998 142.675)
		(width 0.157)
		(layer "In7.Cu")
		(net 559)
	)
	(segment
		(start 174.875 140.975)
		(end 174.875 140.36139)
		(width 0.157)
		(layer "In7.Cu")
		(net 559)
	)
	(segment
		(start 172.175 140.975)
		(end 172.175 140.36139)
		(width 0.157)
		(layer "In7.Cu")
		(net 559)
	)
	(segment
		(start 177.125 140.36139)
		(end 177.125 140.975)
		(width 0.157)
		(layer "In7.Cu")
		(net 559)
	)
	(segment
		(start 176.675 140.975)
		(end 176.675 140.36139)
		(width 0.157)
		(layer "In7.Cu")
		(net 559)
	)
	(segment
		(start 173.975 140.975)
		(end 173.975 140.36139)
		(width 0.157)
		(layer "In7.Cu")
		(net 559)
	)
	(segment
		(start 174.425 140.36139)
		(end 174.425 140.975)
		(width 0.157)
		(layer "In7.Cu")
		(net 559)
	)
	(segment
		(start 170.375 140.975)
		(end 170.375 140.36139)
		(width 0.157)
		(layer "In7.Cu")
		(net 559)
	)
	(segment
		(start 172.625 140.36139)
		(end 172.625 140.975)
		(width 0.157)
		(layer "In7.Cu")
		(net 559)
	)
	(arc
		(start 176.675 140.36139)
		(mid 176.609099 140.202291)
		(end 176.45 140.13639)
		(width 0.157)
		(layer "In7.Cu")
		(net 559)
	)
	(arc
		(start 173.75 140.13639)
		(mid 173.590901 140.202291)
		(end 173.525 140.36139)
		(width 0.157)
		(layer "In7.Cu")
		(net 559)
	)
	(arc
		(start 176.45 140.13639)
		(mid 176.290901 140.202291)
		(end 176.225 140.36139)
		(width 0.157)
		(layer "In7.Cu")
		(net 559)
	)
	(arc
		(start 175.1 141.2)
		(mid 174.940901 141.134099)
		(end 174.875 140.975)
		(width 0.157)
		(layer "In7.Cu")
		(net 559)
	)
	(arc
		(start 171.275 140.36139)
		(mid 171.209099 140.202291)
		(end 171.05 140.13639)
		(width 0.157)
		(layer "In7.Cu")
		(net 559)
	)
	(arc
		(start 178.7 141.2)
		(mid 178.540901 141.134099)
		(end 178.475 140.975)
		(width 0.157)
		(layer "In7.Cu")
		(net 559)
	)
	(arc
		(start 178.475 140.36139)
		(mid 178.409099 140.202291)
		(end 178.25 140.13639)
		(width 0.157)
		(layer "In7.Cu")
		(net 559)
	)
	(arc
		(start 174.2 141.2)
		(mid 174.040901 141.134099)
		(end 173.975 140.975)
		(width 0.157)
		(layer "In7.Cu")
		(net 559)
	)
	(arc
		(start 171.5 141.2)
		(mid 171.340901 141.134099)
		(end 171.275 140.975)
		(width 0.157)
		(layer "In7.Cu")
		(net 559)
	)
	(arc
		(start 174.65 140.13639)
		(mid 174.490901 140.202291)
		(end 174.425 140.36139)
		(width 0.157)
		(layer "In7.Cu")
		(net 559)
	)
	(arc
		(start 170.375 140.36139)
		(mid 170.309099 140.202291)
		(end 170.15 140.13639)
		(width 0.157)
		(layer "In7.Cu")
		(net 559)
	)
	(arc
		(start 171.725 140.975)
		(mid 171.659099 141.134099)
		(end 171.5 141.2)
		(width 0.157)
		(layer "In7.Cu")
		(net 559)
	)
	(arc
		(start 177.125 140.975)
		(mid 177.059099 141.134099)
		(end 176.9 141.2)
		(width 0.157)
		(layer "In7.Cu")
		(net 559)
	)
	(arc
		(start 170.825 140.975)
		(mid 170.759099 141.134099)
		(end 170.6 141.2)
		(width 0.157)
		(layer "In7.Cu")
		(net 559)
	)
	(arc
		(start 170.15 140.13639)
		(mid 169.990901 140.202291)
		(end 169.925 140.36139)
		(width 0.157)
		(layer "In7.Cu")
		(net 559)
	)
	(arc
		(start 169.925 140.975)
		(mid 169.859099 141.134099)
		(end 169.7 141.2)
		(width 0.157)
		(layer "In7.Cu")
		(net 559)
	)
	(arc
		(start 177.575 140.36139)
		(mid 177.509099 140.202291)
		(end 177.35 140.13639)
		(width 0.157)
		(layer "In7.Cu")
		(net 559)
	)
	(arc
		(start 171.05 140.13639)
		(mid 170.890901 140.202291)
		(end 170.825 140.36139)
		(width 0.157)
		(layer "In7.Cu")
		(net 559)
	)
	(arc
		(start 175.55 140.13639)
		(mid 175.390901 140.202291)
		(end 175.325 140.36139)
		(width 0.157)
		(layer "In7.Cu")
		(net 559)
	)
	(arc
		(start 175.775 140.36139)
		(mid 175.709099 140.202291)
		(end 175.55 140.13639)
		(width 0.157)
		(layer "In7.Cu")
		(net 559)
	)
	(arc
		(start 176.9 141.2)
		(mid 176.740901 141.134099)
		(end 176.675 140.975)
		(width 0.157)
		(layer "In7.Cu")
		(net 559)
	)
	(arc
		(start 173.075 140.36139)
		(mid 173.009099 140.202291)
		(end 172.85 140.13639)
		(width 0.157)
		(layer "In7.Cu")
		(net 559)
	)
	(arc
		(start 172.625 140.975)
		(mid 172.559099 141.134099)
		(end 172.4 141.2)
		(width 0.157)
		(layer "In7.Cu")
		(net 559)
	)
	(arc
		(start 172.4 141.2)
		(mid 172.240901 141.134099)
		(end 172.175 140.975)
		(width 0.157)
		(layer "In7.Cu")
		(net 559)
	)
	(arc
		(start 177.35 140.13639)
		(mid 177.190901 140.202291)
		(end 177.125 140.36139)
		(width 0.157)
		(layer "In7.Cu")
		(net 559)
	)
	(arc
		(start 170.6 141.2)
		(mid 170.440901 141.134099)
		(end 170.375 140.975)
		(width 0.157)
		(layer "In7.Cu")
		(net 559)
	)
	(arc
		(start 171.95 140.13639)
		(mid 171.790901 140.202291)
		(end 171.725 140.36139)
		(width 0.157)
		(layer "In7.Cu")
		(net 559)
	)
	(arc
		(start 173.525 140.975)
		(mid 173.459099 141.134099)
		(end 173.3 141.2)
		(width 0.157)
		(layer "In7.Cu")
		(net 559)
	)
	(arc
		(start 172.85 140.13639)
		(mid 172.690901 140.202291)
		(end 172.625 140.36139)
		(width 0.157)
		(layer "In7.Cu")
		(net 559)
	)
	(arc
		(start 176 141.2)
		(mid 175.840901 141.134099)
		(end 175.775 140.975)
		(width 0.157)
		(layer "In7.Cu")
		(net 559)
	)
	(arc
		(start 174.425 140.975)
		(mid 174.359099 141.134099)
		(end 174.2 141.2)
		(width 0.157)
		(layer "In7.Cu")
		(net 559)
	)
	(arc
		(start 174.875 140.36139)
		(mid 174.809099 140.202291)
		(end 174.65 140.13639)
		(width 0.157)
		(layer "In7.Cu")
		(net 559)
	)
	(arc
		(start 176.225 140.975)
		(mid 176.159099 141.134099)
		(end 176 141.2)
		(width 0.157)
		(layer "In7.Cu")
		(net 559)
	)
	(arc
		(start 175.325 140.975)
		(mid 175.259099 141.134099)
		(end 175.1 141.2)
		(width 0.157)
		(layer "In7.Cu")
		(net 559)
	)
	(arc
		(start 173.975 140.36139)
		(mid 173.909099 140.202291)
		(end 173.75 140.13639)
		(width 0.157)
		(layer "In7.Cu")
		(net 559)
	)
	(arc
		(start 178.025 140.975)
		(mid 177.959099 141.134099)
		(end 177.8 141.2)
		(width 0.157)
		(layer "In7.Cu")
		(net 559)
	)
	(arc
		(start 178.25 140.13639)
		(mid 178.090901 140.202291)
		(end 178.025 140.36139)
		(width 0.157)
		(layer "In7.Cu")
		(net 559)
	)
	(arc
		(start 177.8 141.2)
		(mid 177.640901 141.134099)
		(end 177.575 140.975)
		(width 0.157)
		(layer "In7.Cu")
		(net 559)
	)
	(arc
		(start 172.175 140.36139)
		(mid 172.109099 140.202291)
		(end 171.95 140.13639)
		(width 0.157)
		(layer "In7.Cu")
		(net 559)
	)
	(arc
		(start 173.3 141.2)
		(mid 173.140901 141.134099)
		(end 173.075 140.975)
		(width 0.157)
		(layer "In7.Cu")
		(net 559)
	)
	(segment
		(start 189.5 141.5)
		(end 189 142)
		(width 0.256)
		(layer "F.Cu")
		(net 560)
	)
	(segment
		(start 170.4 144.4)
		(end 170 144)
		(width 0.256)
		(layer "F.Cu")
		(net 560)
	)
	(via
		(at 170.4 144.4)
		(size 0.45)
		(drill 0.2)
		(layers "F.Cu" "B.Cu")
		(net 560)
	)
	(via
		(at 189 142)
		(size 0.45)
		(drill 0.2)
		(layers "F.Cu" "B.Cu")
		(net 560)
	)
	(segment
		(start 175.584 140.858232)
		(end 175.584 141)
		(width 0.157)
		(layer "In5.Cu")
		(net 560)
	)
	(segment
		(start 176.384 140.858232)
		(end 176.384 141)
		(width 0.157)
		(layer "In5.Cu")
		(net 560)
	)
	(segment
		(start 172.384 140.858232)
		(end 172.384 141)
		(width 0.157)
		(layer "In5.Cu")
		(net 560)
	)
	(segment
		(start 182.782 143.3)
		(end 182.782 141.95)
		(width 0.157)
		(layer "In5.Cu")
		(net 560)
	)
	(segment
		(start 171.584 140.858232)
		(end 171.584 141)
		(width 0.157)
		(layer "In5.Cu")
		(net 560)
	)
	(segment
		(start 181.982 143.3)
		(end 181.982 141.95)
		(width 0.157)
		(layer "In5.Cu")
		(net 560)
	)
	(segment
		(start 177.184 140.858232)
		(end 177.184 141)
		(width 0.157)
		(layer "In5.Cu")
		(net 560)
	)
	(segment
		(start 171.984 141)
		(end 171.984 140.858232)
		(width 0.157)
		(layer "In5.Cu")
		(net 560)
	)
	(segment
		(start 170.4 144.4)
		(end 170 144)
		(width 0.15)
		(layer "In5.Cu")
		(net 560)
	)
	(segment
		(start 182.382 141.95)
		(end 182.382 143.3)
		(width 0.157)
		(layer "In5.Cu")
		(net 560)
	)
	(segment
		(start 172.784 141)
		(end 172.784 140.858232)
		(width 0.157)
		(layer "In5.Cu")
		(net 560)
	)
	(segment
		(start 181.582 141.95)
		(end 181.582 143.3)
		(width 0.157)
		(layer "In5.Cu")
		(net 560)
	)
	(segment
		(start 175.184 141)
		(end 175.184 140.858232)
		(width 0.157)
		(layer "In5.Cu")
		(net 560)
	)
	(segment
		(start 183.582 143.3)
		(end 183.582 141.95)
		(width 0.157)
		(layer "In5.Cu")
		(net 560)
	)
	(segment
		(start 181.182 142.3)
		(end 181.182 141.95)
		(width 0.157)
		(layer "In5.Cu")
		(net 560)
	)
	(segment
		(start 173.984 140.858232)
		(end 173.984 141)
		(width 0.157)
		(layer "In5.Cu")
		(net 560)
	)
	(segment
		(start 184.582 142.5)
		(end 188.5 142.5)
		(width 0.157)
		(layer "In5.Cu")
		(net 560)
	)
	(segment
		(start 173.584 141)
		(end 173.584 140.858232)
		(width 0.157)
		(layer "In5.Cu")
		(net 560)
	)
	(segment
		(start 170 141.8)
		(end 170.6 141.2)
		(width 0.157)
		(layer "In5.Cu")
		(net 560)
	)
	(segment
		(start 177.584 141)
		(end 177.584 140.858232)
		(width 0.157)
		(layer "In5.Cu")
		(net 560)
	)
	(segment
		(start 188.5 142.5)
		(end 189 142)
		(width 0.157)
		(layer "In5.Cu")
		(net 560)
	)
	(segment
		(start 171.184 141)
		(end 171.184 140.858232)
		(width 0.157)
		(layer "In5.Cu")
		(net 560)
	)
	(segment
		(start 179 141.2)
		(end 180.3 142.5)
		(width 0.157)
		(layer "In5.Cu")
		(net 560)
	)
	(segment
		(start 180.3 142.5)
		(end 180.982 142.5)
		(width 0.157)
		(layer "In5.Cu")
		(net 560)
	)
	(segment
		(start 176.784 141)
		(end 176.784 140.858232)
		(width 0.157)
		(layer "In5.Cu")
		(net 560)
	)
	(segment
		(start 174.784 140.858232)
		(end 174.784 141)
		(width 0.157)
		(layer "In5.Cu")
		(net 560)
	)
	(segment
		(start 178.184 141.2)
		(end 179 141.2)
		(width 0.157)
		(layer "In5.Cu")
		(net 560)
	)
	(segment
		(start 173.184 140.858232)
		(end 173.184 141)
		(width 0.157)
		(layer "In5.Cu")
		(net 560)
	)
	(segment
		(start 184.382 143.3)
		(end 184.382 142.7)
		(width 0.157)
		(layer "In5.Cu")
		(net 560)
	)
	(segment
		(start 183.982 141.95)
		(end 183.982 143.3)
		(width 0.157)
		(layer "In5.Cu")
		(net 560)
	)
	(segment
		(start 175.984 141)
		(end 175.984 140.858232)
		(width 0.157)
		(layer "In5.Cu")
		(net 560)
	)
	(segment
		(start 183.182 141.95)
		(end 183.182 143.3)
		(width 0.157)
		(layer "In5.Cu")
		(net 560)
	)
	(segment
		(start 170 144)
		(end 170 141.8)
		(width 0.15)
		(layer "In5.Cu")
		(net 560)
	)
	(segment
		(start 174.384 141)
		(end 174.384 140.858232)
		(width 0.157)
		(layer "In5.Cu")
		(net 560)
	)
	(segment
		(start 177.984 140.858232)
		(end 177.984 141)
		(width 0.157)
		(layer "In5.Cu")
		(net 560)
	)
	(segment
		(start 170.6 141.2)
		(end 170.984 141.2)
		(width 0.157)
		(layer "In5.Cu")
		(net 560)
	)
	(arc
		(start 175.384 140.658232)
		(mid 175.525421 140.716811)
		(end 175.584 140.858232)
		(width 0.157)
		(layer "In5.Cu")
		(net 560)
	)
	(arc
		(start 180.982 142.5)
		(mid 181.123421 142.441421)
		(end 181.182 142.3)
		(width 0.157)
		(layer "In5.Cu")
		(net 560)
	)
	(arc
		(start 175.184 140.858232)
		(mid 175.242579 140.716811)
		(end 175.384 140.658232)
		(width 0.157)
		(layer "In5.Cu")
		(net 560)
	)
	(arc
		(start 171.384 140.658232)
		(mid 171.525421 140.716811)
		(end 171.584 140.858232)
		(width 0.157)
		(layer "In5.Cu")
		(net 560)
	)
	(arc
		(start 181.782 143.5)
		(mid 181.923421 143.441421)
		(end 181.982 143.3)
		(width 0.157)
		(layer "In5.Cu")
		(net 560)
	)
	(arc
		(start 182.382 143.3)
		(mid 182.440579 143.441421)
		(end 182.582 143.5)
		(width 0.157)
		(layer "In5.Cu")
		(net 560)
	)
	(arc
		(start 182.582 143.5)
		(mid 182.723421 143.441421)
		(end 182.782 143.3)
		(width 0.157)
		(layer "In5.Cu")
		(net 560)
	)
	(arc
		(start 171.184 140.858232)
		(mid 171.242579 140.716811)
		(end 171.384 140.658232)
		(width 0.157)
		(layer "In5.Cu")
		(net 560)
	)
	(arc
		(start 177.384 141.2)
		(mid 177.525421 141.141421)
		(end 177.584 141)
		(width 0.157)
		(layer "In5.Cu")
		(net 560)
	)
	(arc
		(start 176.584 141.2)
		(mid 176.725421 141.141421)
		(end 176.784 141)
		(width 0.157)
		(layer "In5.Cu")
		(net 560)
	)
	(arc
		(start 176.984 140.658232)
		(mid 177.125421 140.716811)
		(end 177.184 140.858232)
		(width 0.157)
		(layer "In5.Cu")
		(net 560)
	)
	(arc
		(start 173.584 140.858232)
		(mid 173.642579 140.716811)
		(end 173.784 140.658232)
		(width 0.157)
		(layer "In5.Cu")
		(net 560)
	)
	(arc
		(start 175.984 140.858232)
		(mid 176.042579 140.716811)
		(end 176.184 140.658232)
		(width 0.157)
		(layer "In5.Cu")
		(net 560)
	)
	(arc
		(start 182.182 141.75)
		(mid 182.323421 141.808579)
		(end 182.382 141.95)
		(width 0.157)
		(layer "In5.Cu")
		(net 560)
	)
	(arc
		(start 182.982 141.75)
		(mid 183.123421 141.808579)
		(end 183.182 141.95)
		(width 0.157)
		(layer "In5.Cu")
		(net 560)
	)
	(arc
		(start 172.184 140.658232)
		(mid 172.325421 140.716811)
		(end 172.384 140.858232)
		(width 0.157)
		(layer "In5.Cu")
		(net 560)
	)
	(arc
		(start 172.384 141)
		(mid 172.442579 141.141421)
		(end 172.584 141.2)
		(width 0.157)
		(layer "In5.Cu")
		(net 560)
	)
	(arc
		(start 183.382 143.5)
		(mid 183.523421 143.441421)
		(end 183.582 143.3)
		(width 0.157)
		(layer "In5.Cu")
		(net 560)
	)
	(arc
		(start 184.382 142.7)
		(mid 184.440579 142.558579)
		(end 184.582 142.5)
		(width 0.157)
		(layer "In5.Cu")
		(net 560)
	)
	(arc
		(start 173.784 140.658232)
		(mid 173.925421 140.716811)
		(end 173.984 140.858232)
		(width 0.157)
		(layer "In5.Cu")
		(net 560)
	)
	(arc
		(start 177.184 141)
		(mid 177.242579 141.141421)
		(end 177.384 141.2)
		(width 0.157)
		(layer "In5.Cu")
		(net 560)
	)
	(arc
		(start 176.184 140.658232)
		(mid 176.325421 140.716811)
		(end 176.384 140.858232)
		(width 0.157)
		(layer "In5.Cu")
		(net 560)
	)
	(arc
		(start 171.984 140.858232)
		(mid 172.042579 140.716811)
		(end 172.184 140.658232)
		(width 0.157)
		(layer "In5.Cu")
		(net 560)
	)
	(arc
		(start 181.382 141.75)
		(mid 181.523421 141.808579)
		(end 181.582 141.95)
		(width 0.157)
		(layer "In5.Cu")
		(net 560)
	)
	(arc
		(start 173.984 141)
		(mid 174.042579 141.141421)
		(end 174.184 141.2)
		(width 0.157)
		(layer "In5.Cu")
		(net 560)
	)
	(arc
		(start 176.784 140.858232)
		(mid 176.842579 140.716811)
		(end 176.984 140.658232)
		(width 0.157)
		(layer "In5.Cu")
		(net 560)
	)
	(arc
		(start 174.584 140.658232)
		(mid 174.725421 140.716811)
		(end 174.784 140.858232)
		(width 0.157)
		(layer "In5.Cu")
		(net 560)
	)
	(arc
		(start 184.182 143.5)
		(mid 184.323421 143.441421)
		(end 184.382 143.3)
		(width 0.157)
		(layer "In5.Cu")
		(net 560)
	)
	(arc
		(start 175.584 141)
		(mid 175.642579 141.141421)
		(end 175.784 141.2)
		(width 0.157)
		(layer "In5.Cu")
		(net 560)
	)
	(arc
		(start 173.184 141)
		(mid 173.242579 141.141421)
		(end 173.384 141.2)
		(width 0.157)
		(layer "In5.Cu")
		(net 560)
	)
	(arc
		(start 174.184 141.2)
		(mid 174.325421 141.141421)
		(end 174.384 141)
		(width 0.157)
		(layer "In5.Cu")
		(net 560)
	)
	(arc
		(start 177.784 140.658232)
		(mid 177.925421 140.716811)
		(end 177.984 140.858232)
		(width 0.157)
		(layer "In5.Cu")
		(net 560)
	)
	(arc
		(start 177.584 140.858232)
		(mid 177.642579 140.716811)
		(end 177.784 140.658232)
		(width 0.157)
		(layer "In5.Cu")
		(net 560)
	)
	(arc
		(start 171.784 141.2)
		(mid 171.925421 141.141421)
		(end 171.984 141)
		(width 0.157)
		(layer "In5.Cu")
		(net 560)
	)
	(arc
		(start 174.984 141.2)
		(mid 175.125421 141.141421)
		(end 175.184 141)
		(width 0.157)
		(layer "In5.Cu")
		(net 560)
	)
	(arc
		(start 171.584 141)
		(mid 171.642579 141.141421)
		(end 171.784 141.2)
		(width 0.157)
		(layer "In5.Cu")
		(net 560)
	)
	(arc
		(start 174.384 140.858232)
		(mid 174.442579 140.716811)
		(end 174.584 140.658232)
		(width 0.157)
		(layer "In5.Cu")
		(net 560)
	)
	(arc
		(start 181.182 141.95)
		(mid 181.240579 141.808579)
		(end 181.382 141.75)
		(width 0.157)
		(layer "In5.Cu")
		(net 560)
	)
	(arc
		(start 174.784 141)
		(mid 174.842579 141.141421)
		(end 174.984 141.2)
		(width 0.157)
		(layer "In5.Cu")
		(net 560)
	)
	(arc
		(start 181.582 143.3)
		(mid 181.640579 143.441421)
		(end 181.782 143.5)
		(width 0.157)
		(layer "In5.Cu")
		(net 560)
	)
	(arc
		(start 183.982 143.3)
		(mid 184.040579 143.441421)
		(end 184.182 143.5)
		(width 0.157)
		(layer "In5.Cu")
		(net 560)
	)
	(arc
		(start 183.582 141.95)
		(mid 183.640579 141.808579)
		(end 183.782 141.75)
		(width 0.157)
		(layer "In5.Cu")
		(net 560)
	)
	(arc
		(start 176.384 141)
		(mid 176.442579 141.141421)
		(end 176.584 141.2)
		(width 0.157)
		(layer "In5.Cu")
		(net 560)
	)
	(arc
		(start 172.984 140.658232)
		(mid 173.125421 140.716811)
		(end 173.184 140.858232)
		(width 0.157)
		(layer "In5.Cu")
		(net 560)
	)
	(arc
		(start 172.584 141.2)
		(mid 172.725421 141.141421)
		(end 172.784 141)
		(width 0.157)
		(layer "In5.Cu")
		(net 560)
	)
	(arc
		(start 170.984 141.2)
		(mid 171.125421 141.141421)
		(end 171.184 141)
		(width 0.157)
		(layer "In5.Cu")
		(net 560)
	)
	(arc
		(start 175.784 141.2)
		(mid 175.925421 141.141421)
		(end 175.984 141)
		(width 0.157)
		(layer "In5.Cu")
		(net 560)
	)
	(arc
		(start 182.782 141.95)
		(mid 182.840579 141.808579)
		(end 182.982 141.75)
		(width 0.157)
		(layer "In5.Cu")
		(net 560)
	)
	(arc
		(start 183.182 143.3)
		(mid 183.240579 143.441421)
		(end 183.382 143.5)
		(width 0.157)
		(layer "In5.Cu")
		(net 560)
	)
	(arc
		(start 172.784 140.858232)
		(mid 172.842579 140.716811)
		(end 172.984 140.658232)
		(width 0.157)
		(layer "In5.Cu")
		(net 560)
	)
	(arc
		(start 183.782 141.75)
		(mid 183.923421 141.808579)
		(end 183.982 141.95)
		(width 0.157)
		(layer "In5.Cu")
		(net 560)
	)
	(arc
		(start 177.984 141)
		(mid 178.042579 141.141421)
		(end 178.184 141.2)
		(width 0.157)
		(layer "In5.Cu")
		(net 560)
	)
	(arc
		(start 181.982 141.95)
		(mid 182.040579 141.808579)
		(end 182.182 141.75)
		(width 0.157)
		(layer "In5.Cu")
		(net 560)
	)
	(arc
		(start 173.384 141.2)
		(mid 173.525421 141.141421)
		(end 173.584 141)
		(width 0.157)
		(layer "In5.Cu")
		(net 560)
	)
	(segment
		(start 185.5 142.5)
		(end 185 143)
		(width 0.256)
		(layer "F.Cu")
		(net 561)
	)
	(segment
		(start 168.399999 143.199999)
		(end 168 142.8)
		(width 0.256)
		(layer "F.Cu")
		(net 561)
	)
	(via
		(at 168 142.8)
		(size 0.45)
		(drill 0.2)
		(layers "F.Cu" "B.Cu")
		(net 561)
	)
	(via
		(at 185 143)
		(size 0.45)
		(drill 0.2)
		(layers "F.Cu" "B.Cu")
		(net 561)
	)
	(segment
		(start 181.625 149.325)
		(end 179.293277 149.325)
		(width 0.256)
		(layer "B.Cu")
		(net 561)
	)
	(segment
		(start 179.293277 149.875)
		(end 181.625 149.875)
		(width 0.256)
		(layer "B.Cu")
		(net 561)
	)
	(segment
		(start 183.15 143)
		(end 185 143)
		(width 0.256)
		(layer "B.Cu")
		(net 561)
	)
	(segment
		(start 175.55 139.35)
		(end 177.65 141.45)
		(width 0.256)
		(layer "B.Cu")
		(net 561)
	)
	(segment
		(start 167.599999 144.699999)
		(end 167.6 143.85)
		(width 0.256)
		(layer "B.Cu")
		(net 561)
	)
	(segment
		(start 181.9 144.25)
		(end 183.15 143)
		(width 0.256)
		(layer "B.Cu")
		(net 561)
	)
	(segment
		(start 167.6 143.350002)
		(end 167.599997 143.349999)
		(width 0.15)
		(layer "B.Cu")
		(net 561)
	)
	(segment
		(start 181.625 150.425)
		(end 179.293277 150.425)
		(width 0.256)
		(layer "B.Cu")
		(net 561)
	)
	(segment
		(start 177.65 150.9)
		(end 178.3 151.55)
		(width 0.256)
		(layer "B.Cu")
		(net 561)
	)
	(segment
		(start 168.85 139.35)
		(end 175.55 139.35)
		(width 0.256)
		(layer "B.Cu")
		(net 561)
	)
	(segment
		(start 181.25 151.55)
		(end 181.9 150.9)
		(width 0.256)
		(layer "B.Cu")
		(net 561)
	)
	(segment
		(start 181.9 148.5)
		(end 181.9 148.45)
		(width 0.256)
		(layer "B.Cu")
		(net 561)
	)
	(segment
		(start 167.599997 143.199999)
		(end 167.599997 143.349999)
		(width 0.256)
		(layer "B.Cu")
		(net 561)
	)
	(segment
		(start 168.025 140.175)
		(end 168.85 139.35)
		(width 0.256)
		(layer "B.Cu")
		(net 561)
	)
	(segment
		(start 181.9 150.9)
		(end 181.9 150.7)
		(width 0.256)
		(layer "B.Cu")
		(net 561)
	)
	(segment
		(start 168 142.8)
		(end 168.025 142.775)
		(width 0.256)
		(layer "B.Cu")
		(net 561)
	)
	(segment
		(start 167.6 143.85)
		(end 167.6 143.350002)
		(width 0.15)
		(layer "B.Cu")
		(net 561)
	)
	(segment
		(start 167.999996 142.8)
		(end 167.599997 143.199999)
		(width 0.256)
		(layer "B.Cu")
		(net 561)
	)
	(segment
		(start 168.025 142.775)
		(end 168.025 140.175)
		(width 0.256)
		(layer "B.Cu")
		(net 561)
	)
	(segment
		(start 179.293277 148.775)
		(end 181.625 148.775)
		(width 0.256)
		(layer "B.Cu")
		(net 561)
	)
	(segment
		(start 181.9 148.45)
		(end 181.9 144.25)
		(width 0.256)
		(layer "B.Cu")
		(net 561)
	)
	(segment
		(start 178.3 151.55)
		(end 181.25 151.55)
		(width 0.256)
		(layer "B.Cu")
		(net 561)
	)
	(segment
		(start 177.65 141.45)
		(end 177.65 150.9)
		(width 0.256)
		(layer "B.Cu")
		(net 561)
	)
	(arc
		(start 179.018277 149.05)
		(mid 179.098823 148.855546)
		(end 179.293277 148.775)
		(width 0.256)
		(layer "B.Cu")
		(net 561)
	)
	(arc
		(start 181.625 148.775)
		(mid 181.819454 148.694454)
		(end 181.9 148.5)
		(width 0.256)
		(layer "B.Cu")
		(net 561)
	)
	(arc
		(start 181.9 150.7)
		(mid 181.819454 150.505546)
		(end 181.625 150.425)
		(width 0.256)
		(layer "B.Cu")
		(net 561)
	)
	(arc
		(start 179.018277 150.15)
		(mid 179.098823 149.955546)
		(end 179.293277 149.875)
		(width 0.256)
		(layer "B.Cu")
		(net 561)
	)
	(arc
		(start 181.625 149.875)
		(mid 181.819454 149.794454)
		(end 181.9 149.6)
		(width 0.256)
		(layer "B.Cu")
		(net 561)
	)
	(arc
		(start 181.9 149.6)
		(mid 181.819454 149.405546)
		(end 181.625 149.325)
		(width 0.256)
		(layer "B.Cu")
		(net 561)
	)
	(arc
		(start 179.293277 150.425)
		(mid 179.098823 150.344454)
		(end 179.018277 150.15)
		(width 0.256)
		(layer "B.Cu")
		(net 561)
	)
	(arc
		(start 179.293277 149.325)
		(mid 179.098823 149.244454)
		(end 179.018277 149.05)
		(width 0.256)
		(layer "B.Cu")
		(net 561)
	)
	(segment
		(start 206.5 131.5)
		(end 207 132)
		(width 0.256)
		(layer "F.Cu")
		(net 562)
	)
	(segment
		(start 219.875 133.275)
		(end 219.5 133.65)
		(width 0.184)
		(layer "F.Cu")
		(net 562)
	)
	(via
		(at 219.5 133.65)
		(size 0.45)
		(drill 0.2)
		(layers "F.Cu" "B.Cu")
		(net 562)
	)
	(via
		(at 207 132)
		(size 0.45)
		(drill 0.2)
		(layers "F.Cu" "B.Cu")
		(net 562)
	)
	(segment
		(start 219.5 133.65)
		(end 219.25 133.4)
		(width 0.184)
		(layer "B.Cu")
		(net 562)
	)
	(segment
		(start 219.25 133.4)
		(end 218.4 133.4)
		(width 0.184)
		(layer "B.Cu")
		(net 562)
	)
	(segment
		(start 219.25 133.4)
		(end 215.6 133.4)
		(width 0.1)
		(layer "In5.Cu")
		(net 562)
	)
	(segment
		(start 206.975 132.025)
		(end 207 132)
		(width 0.1)
		(layer "In5.Cu")
		(net 562)
	)
	(segment
		(start 215.6 133.4)
		(end 215.4 133.6)
		(width 0.1)
		(layer "In5.Cu")
		(net 562)
	)
	(segment
		(start 213.8875 133.375)
		(end 207.525 133.375)
		(width 0.1)
		(layer "In5.Cu")
		(net 562)
	)
	(segment
		(start 207.525 133.375)
		(end 206.975 132.825)
		(width 0.1)
		(layer "In5.Cu")
		(net 562)
	)
	(segment
		(start 219.5 133.65)
		(end 219.25 133.4)
		(width 0.1)
		(layer "In5.Cu")
		(net 562)
	)
	(segment
		(start 214.1125 133.6)
		(end 213.8875 133.375)
		(width 0.1)
		(layer "In5.Cu")
		(net 562)
	)
	(segment
		(start 215.4 133.6)
		(end 214.1125 133.6)
		(width 0.1)
		(layer "In5.Cu")
		(net 562)
	)
	(segment
		(start 206.975 132.825)
		(end 206.975 132.025)
		(width 0.1)
		(layer "In5.Cu")
		(net 562)
	)
	(segment
		(start 206.5 133.5)
		(end 207 134)
		(width 0.256)
		(layer "F.Cu")
		(net 563)
	)
	(segment
		(start 220.625 128.775)
		(end 220.25 128.4)
		(width 0.184)
		(layer "F.Cu")
		(net 563)
	)
	(via
		(at 220.25 128.4)
		(size 0.45)
		(drill 0.2)
		(layers "F.Cu" "B.Cu")
		(net 563)
	)
	(via
		(at 207 134)
		(size 0.45)
		(drill 0.2)
		(layers "F.Cu" "B.Cu")
		(net 563)
	)
	(segment
		(start 218.8 131.9)
		(end 218.5 132.2)
		(width 0.184)
		(layer "B.Cu")
		(net 563)
	)
	(segment
		(start 218.5 132.2)
		(end 218.4 132.2)
		(width 0.184)
		(layer "B.Cu")
		(net 563)
	)
	(segment
		(start 219.75 128.9)
		(end 220.25 128.4)
		(width 0.184)
		(layer "B.Cu")
		(net 563)
	)
	(segment
		(start 219.1 128.9)
		(end 219.75 128.9)
		(width 0.184)
		(layer "B.Cu")
		(net 563)
	)
	(segment
		(start 218.8 131.9)
		(end 218.8 129.2)
		(width 0.184)
		(layer "B.Cu")
		(net 563)
	)
	(segment
		(start 218.8 129.2)
		(end 219.1 128.9)
		(width 0.184)
		(layer "B.Cu")
		(net 563)
	)
	(segment
		(start 206.49 129.41)
		(end 206.375 129.525)
		(width 0.1)
		(layer "In5.Cu")
		(net 563)
	)
	(segment
		(start 220.25 128.025)
		(end 219.875 127.65)
		(width 0.1)
		(layer "In5.Cu")
		(net 563)
	)
	(segment
		(start 215.49 129.41)
		(end 206.49 129.41)
		(width 0.1)
		(layer "In5.Cu")
		(net 563)
	)
	(segment
		(start 219.875 127.65)
		(end 217.25 127.65)
		(width 0.1)
		(layer "In5.Cu")
		(net 563)
	)
	(segment
		(start 217.25 127.65)
		(end 215.49 129.41)
		(width 0.1)
		(layer "In5.Cu")
		(net 563)
	)
	(segment
		(start 206.375 129.525)
		(end 206.375 133.375)
		(width 0.1)
		(layer "In5.Cu")
		(net 563)
	)
	(segment
		(start 220.25 128.4)
		(end 220.25 128.025)
		(width 0.1)
		(layer "In5.Cu")
		(net 563)
	)
	(segment
		(start 206.375 133.375)
		(end 207 134)
		(width 0.1)
		(layer "In5.Cu")
		(net 563)
	)
	(segment
		(start 210.5 128.5)
		(end 211 128)
		(width 0.256)
		(layer "F.Cu")
		(net 564)
	)
	(segment
		(start 222.875 133.275)
		(end 223.25 132.9)
		(width 0.184)
		(layer "F.Cu")
		(net 564)
	)
	(via
		(at 223.25 132.9)
		(size 0.45)
		(drill 0.2)
		(layers "F.Cu" "B.Cu")
		(net 564)
	)
	(via
		(at 211 128)
		(size 0.45)
		(drill 0.2)
		(layers "F.Cu" "B.Cu")
		(net 564)
	)
	(segment
		(start 218.4 132.6)
		(end 219.7 132.6)
		(width 0.184)
		(layer "B.Cu")
		(net 564)
	)
	(segment
		(start 221.2 132.4)
		(end 221.7 132.9)
		(width 0.184)
		(layer "B.Cu")
		(net 564)
	)
	(segment
		(start 219.9 132.4)
		(end 221.2 132.4)
		(width 0.184)
		(layer "B.Cu")
		(net 564)
	)
	(segment
		(start 221.7 132.9)
		(end 223.25 132.9)
		(width 0.184)
		(layer "B.Cu")
		(net 564)
	)
	(segment
		(start 219.7 132.6)
		(end 219.9 132.4)
		(width 0.184)
		(layer "B.Cu")
		(net 564)
	)
	(segment
		(start 215.130331 127.4)
		(end 212.562842 127.4)
		(width 0.1)
		(layer "In3.Cu")
		(net 564)
	)
	(segment
		(start 223.25 132.9)
		(end 224.375 131.775)
		(width 0.1)
		(layer "In3.Cu")
		(net 564)
	)
	(segment
		(start 212.562842 127.4)
		(end 212.352842 127.61)
		(width 0.1)
		(layer "In3.Cu")
		(net 564)
	)
	(segment
		(start 212.352842 127.61)
		(end 211.39 127.61)
		(width 0.1)
		(layer "In3.Cu")
		(net 564)
	)
	(segment
		(start 211.39 127.61)
		(end 211 128)
		(width 0.1)
		(layer "In3.Cu")
		(net 564)
	)
	(segment
		(start 217.0625 127.275)
		(end 215.255331 127.275)
		(width 0.1)
		(layer "In3.Cu")
		(net 564)
	)
	(segment
		(start 215.255331 127.275)
		(end 215.130331 127.4)
		(width 0.1)
		(layer "In3.Cu")
		(net 564)
	)
	(segment
		(start 224.375 131.775)
		(end 224.375 127.0875)
		(width 0.1)
		(layer "In3.Cu")
		(net 564)
	)
	(segment
		(start 223.8125 126.525)
		(end 217.8125 126.525)
		(width 0.1)
		(layer "In3.Cu")
		(net 564)
	)
	(segment
		(start 224.375 127.0875)
		(end 223.8125 126.525)
		(width 0.1)
		(layer "In3.Cu")
		(net 564)
	)
	(segment
		(start 217.8125 126.525)
		(end 217.0625 127.275)
		(width 0.1)
		(layer "In3.Cu")
		(net 564)
	)
	(segment
		(start 206.9 115.175)
		(end 206.8195 115.0945)
		(width 0.1)
		(layer "F.Cu")
		(net 565)
	)
	(segment
		(start 218.325 108.400976)
		(end 218.325 108.8195)
		(width 0.153)
		(layer "F.Cu")
		(net 565)
	)
	(segment
		(start 215.714 109.699024)
		(end 215.714 109.1805)
		(width 0.153)
		(layer "F.Cu")
		(net 565)
	)
	(segment
		(start 206.733578 115.9)
		(end 206.9 115.733578)
		(width 0.1)
		(layer "F.Cu")
		(net 565)
	)
	(segment
		(start 215.714 109.1805)
		(end 215.714 108.400976)
		(width 0.153)
		(layer "F.Cu")
		(net 565)
	)
	(segment
		(start 215.325 108.400976)
		(end 215.325 108.625)
		(width 0.153)
		(layer "F.Cu")
		(net 565)
	)
	(segment
		(start 215.325 108.625)
		(end 215.325 109.699024)
		(width 0.153)
		(layer "F.Cu")
		(net 565)
	)
	(segment
		(start 216.825 108.8195)
		(end 216.825 109.699024)
		(width 0.153)
		(layer "F.Cu")
		(net 565)
	)
	(segment
		(start 241.3455 108.8195)
		(end 241.665 108.5)
		(width 0.153)
		(layer "F.Cu")
		(net 565)
	)
	(segment
		(start 218.714 109.1805)
		(end 218.714 108.400976)
		(width 0.153)
		(layer "F.Cu")
		(net 565)
	)
	(segment
		(start 219.825 108.8195)
		(end 219.825 109.699024)
		(width 0.153)
		(layer "F.Cu")
		(net 565)
	)
	(segment
		(start 221.849999 108.8195)
		(end 241.3455 108.8195)
		(width 0.153)
		(layer "F.Cu")
		(net 565)
	)
	(segment
		(start 220.7695 108.8195)
		(end 221.849999 108.8195)
		(width 0.153)
		(layer "F.Cu")
		(net 565)
	)
	(segment
		(start 219.825 108.400976)
		(end 219.825 108.8195)
		(width 0.153)
		(layer "F.Cu")
		(net 565)
	)
	(segment
		(start 206.5 115.8)
		(end 206.6 115.9)
		(width 0.1)
		(layer "F.Cu")
		(net 565)
	)
	(segment
		(start 217.214 109.699024)
		(end 217.214 109.1805)
		(width 0.153)
		(layer "F.Cu")
		(net 565)
	)
	(segment
		(start 206.8195 114.700234)
		(end 212.700234 108.8195)
		(width 0.153)
		(layer "F.Cu")
		(net 565)
	)
	(segment
		(start 206.8195 115.0945)
		(end 206.8195 114.700234)
		(width 0.153)
		(layer "F.Cu")
		(net 565)
	)
	(segment
		(start 218.325 108.8195)
		(end 218.325 109.699024)
		(width 0.153)
		(layer "F.Cu")
		(net 565)
	)
	(segment
		(start 206.9 115.733578)
		(end 206.9 115.175)
		(width 0.1)
		(layer "F.Cu")
		(net 565)
	)
	(segment
		(start 216.825 108.400976)
		(end 216.825 108.8195)
		(width 0.153)
		(layer "F.Cu")
		(net 565)
	)
	(segment
		(start 218.714 109.699024)
		(end 218.714 109.1805)
		(width 0.153)
		(layer "F.Cu")
		(net 565)
	)
	(segment
		(start 206.6 115.9)
		(end 206.733578 115.9)
		(width 0.1)
		(layer "F.Cu")
		(net 565)
	)
	(segment
		(start 206.5 115.5)
		(end 206.5 115.8)
		(width 0.1)
		(layer "F.Cu")
		(net 565)
	)
	(segment
		(start 214.214 108.625)
		(end 214.214 108.400976)
		(width 0.153)
		(layer "F.Cu")
		(net 565)
	)
	(segment
		(start 217.214 109.1805)
		(end 217.214 108.400976)
		(width 0.153)
		(layer "F.Cu")
		(net 565)
	)
	(segment
		(start 220.214 109.699024)
		(end 220.214 109.375)
		(width 0.153)
		(layer "F.Cu")
		(net 565)
	)
	(segment
		(start 212.700234 108.8195)
		(end 214.0195 108.8195)
		(width 0.153)
		(layer "F.Cu")
		(net 565)
	)
	(arc
		(start 218.325 109.699024)
		(mid 218.381968 109.836556)
		(end 218.5195 109.893524)
		(width 0.153)
		(layer "F.Cu")
		(net 565)
	)
	(arc
		(start 215.5195 109.893524)
		(mid 215.657032 109.836556)
		(end 215.714 109.699024)
		(width 0.153)
		(layer "F.Cu")
		(net 565)
	)
	(arc
		(start 219.2695 107.845476)
		(mid 219.662298 108.008178)
		(end 219.825 108.400976)
		(width 0.153)
		(layer "F.Cu")
		(net 565)
	)
	(arc
		(start 218.5195 109.893524)
		(mid 218.657032 109.836556)
		(end 218.714 109.699024)
		(width 0.153)
		(layer "F.Cu")
		(net 565)
	)
	(arc
		(start 214.7695 107.845476)
		(mid 215.162298 108.008178)
		(end 215.325 108.400976)
		(width 0.153)
		(layer "F.Cu")
		(net 565)
	)
	(arc
		(start 220.0195 109.893524)
		(mid 220.157032 109.836556)
		(end 220.214 109.699024)
		(width 0.153)
		(layer "F.Cu")
		(net 565)
	)
	(arc
		(start 216.2695 107.845476)
		(mid 216.662298 108.008178)
		(end 216.825 108.400976)
		(width 0.153)
		(layer "F.Cu")
		(net 565)
	)
	(arc
		(start 214.214 108.400976)
		(mid 214.376702 108.008178)
		(end 214.7695 107.845476)
		(width 0.153)
		(layer "F.Cu")
		(net 565)
	)
	(arc
		(start 216.825 109.699024)
		(mid 216.881968 109.836556)
		(end 217.0195 109.893524)
		(width 0.153)
		(layer "F.Cu")
		(net 565)
	)
	(arc
		(start 215.325 109.699024)
		(mid 215.381968 109.836556)
		(end 215.5195 109.893524)
		(width 0.153)
		(layer "F.Cu")
		(net 565)
	)
	(arc
		(start 214.0195 108.8195)
		(mid 214.157032 108.762532)
		(end 214.214 108.625)
		(width 0.153)
		(layer "F.Cu")
		(net 565)
	)
	(arc
		(start 215.714 108.400976)
		(mid 215.876702 108.008178)
		(end 216.2695 107.845476)
		(width 0.153)
		(layer "F.Cu")
		(net 565)
	)
	(arc
		(start 220.214 109.375)
		(mid 220.376702 108.982202)
		(end 220.7695 108.8195)
		(width 0.153)
		(layer "F.Cu")
		(net 565)
	)
	(arc
		(start 217.7695 107.845476)
		(mid 218.162298 108.008178)
		(end 218.325 108.400976)
		(width 0.153)
		(layer "F.Cu")
		(net 565)
	)
	(arc
		(start 218.714 108.400976)
		(mid 218.876702 108.008178)
		(end 219.2695 107.845476)
		(width 0.153)
		(layer "F.Cu")
		(net 565)
	)
	(arc
		(start 219.825 109.699024)
		(mid 219.881968 109.836556)
		(end 220.0195 109.893524)
		(width 0.153)
		(layer "F.Cu")
		(net 565)
	)
	(arc
		(start 217.214 108.400976)
		(mid 217.376702 108.008178)
		(end 217.7695 107.845476)
		(width 0.153)
		(layer "F.Cu")
		(net 565)
	)
	(arc
		(start 217.0195 109.893524)
		(mid 217.157032 109.836556)
		(end 217.214 109.699024)
		(width 0.153)
		(layer "F.Cu")
		(net 565)
	)
	(segment
		(start 207.5 129.5)
		(end 208 129)
		(width 0.256)
		(layer "F.Cu")
		(net 566)
	)
	(via
		(at 208 129)
		(size 0.45)
		(drill 0.2)
		(layers "F.Cu" "B.Cu")
		(net 566)
	)
	(segment
		(start 207.985 129)
		(end 207.585 128.6)
		(width 0.182)
		(layer "B.Cu")
		(net 566)
	)
	(segment
		(start 208 129)
		(end 207.985 129)
		(width 0.182)
		(layer "B.Cu")
		(net 566)
	)
	(segment
		(start 190.5 137.5)
		(end 190.01236 137.98764)
		(width 0.256)
		(layer "F.Cu")
		(net 567)
	)
	(segment
		(start 190.01236 137.98764)
		(end 190.000117 137.98764)
		(width 0.256)
		(layer "F.Cu")
		(net 567)
	)
	(via
		(at 190.000117 137.98764)
		(size 0.45)
		(drill 0.2)
		(layers "F.Cu" "B.Cu")
		(net 567)
	)
	(segment
		(start 189.5 137.5)
		(end 189.98764 137.98764)
		(width 0.4)
		(layer "B.Cu")
		(net 567)
	)
	(segment
		(start 189.98764 137.98764)
		(end 190.000117 137.98764)
		(width 0.4)
		(layer "B.Cu")
		(net 567)
	)
	(segment
		(start 190.974179 137.025821)
		(end 190.974179 137.057322)
		(width 0.4)
		(layer "F.Cu")
		(net 568)
	)
	(segment
		(start 191.5 136.5)
		(end 190.974179 137.025821)
		(width 0.4)
		(layer "F.Cu")
		(net 568)
	)
	(via
		(at 190.974179 137.057322)
		(size 0.45)
		(drill 0.2)
		(layers "F.Cu" "B.Cu")
		(net 568)
	)
	(segment
		(start 190.942678 137.057322)
		(end 190.974179 137.057322)
		(width 0.4)
		(layer "B.Cu")
		(net 568)
	)
	(segment
		(start 190.5 137.5)
		(end 190.942678 137.057322)
		(width 0.4)
		(layer "B.Cu")
		(net 568)
	)
	(segment
		(start 249.585 97.985)
		(end 250.4 97.985)
		(width 0.1)
		(layer "F.Cu")
		(net 569)
	)
	(segment
		(start 247.35 95.75)
		(end 249.585 97.985)
		(width 0.1)
		(layer "F.Cu")
		(net 569)
	)
	(segment
		(start 212 142)
		(end 211.5 141.5)
		(width 0.256)
		(layer "F.Cu")
		(net 569)
	)
	(via
		(at 225.5 109.75)
		(size 0.45)
		(drill 0.2)
		(layers "F.Cu" "B.Cu")
		(net 569)
	)
	(via
		(at 247.35 95.75)
		(size 0.45)
		(drill 0.2)
		(layers "F.Cu" "B.Cu")
		(net 569)
	)
	(via
		(at 212 142)
		(size 0.45)
		(drill 0.2)
		(layers "F.Cu" "B.Cu")
		(net 569)
	)
	(segment
		(start 225.5 109.75)
		(end 225.5 107.25)
		(width 0.1)
		(layer "In3.Cu")
		(net 569)
	)
	(segment
		(start 225.5 107.25)
		(end 232.05 100.7)
		(width 0.1)
		(layer "In3.Cu")
		(net 569)
	)
	(segment
		(start 232.05 100.7)
		(end 242.4 100.7)
		(width 0.1)
		(layer "In3.Cu")
		(net 569)
	)
	(segment
		(start 242.4 100.7)
		(end 247.35 95.75)
		(width 0.1)
		(layer "In3.Cu")
		(net 569)
	)
	(segment
		(start 201.1 140.15)
		(end 201.1 137.8)
		(width 0.1)
		(layer "In7.Cu")
		(net 569)
	)
	(segment
		(start 213.6 110.5)
		(end 224.95 110.5)
		(width 0.1)
		(layer "In7.Cu")
		(net 569)
	)
	(segment
		(start 208.5 123.25)
		(end 208.5 118.5)
		(width 0.1)
		(layer "In7.Cu")
		(net 569)
	)
	(segment
		(start 202.55 141.6)
		(end 201.1 140.15)
		(width 0.1)
		(layer "In7.Cu")
		(net 569)
	)
	(segment
		(start 201.5 135.05)
		(end 201.45 135)
		(width 0.1)
		(layer "In7.Cu")
		(net 569)
	)
	(segment
		(start 207.3 124.45)
		(end 208.5 123.25)
		(width 0.1)
		(layer "In7.Cu")
		(net 569)
	)
	(segment
		(start 201.45 125.75)
		(end 202.75 124.45)
		(width 0.1)
		(layer "In7.Cu")
		(net 569)
	)
	(segment
		(start 201.45 135)
		(end 201.45 125.75)
		(width 0.1)
		(layer "In7.Cu")
		(net 569)
	)
	(segment
		(start 201.5 137.4)
		(end 201.5 135.05)
		(width 0.1)
		(layer "In7.Cu")
		(net 569)
	)
	(segment
		(start 202.55 141.6)
		(end 211.6 141.6)
		(width 0.1)
		(layer "In7.Cu")
		(net 569)
	)
	(segment
		(start 208.5 118.5)
		(end 209.55 117.45)
		(width 0.1)
		(layer "In7.Cu")
		(net 569)
	)
	(segment
		(start 209.55 117.45)
		(end 209.55 114.55)
		(width 0.1)
		(layer "In7.Cu")
		(net 569)
	)
	(segment
		(start 202.75 124.45)
		(end 207.3 124.45)
		(width 0.1)
		(layer "In7.Cu")
		(net 569)
	)
	(segment
		(start 209.55 114.55)
		(end 213.6 110.5)
		(width 0.1)
		(layer "In7.Cu")
		(net 569)
	)
	(segment
		(start 225.5 109.95)
		(end 224.95 110.5)
		(width 0.1)
		(layer "In7.Cu")
		(net 569)
	)
	(segment
		(start 225.5 109.75)
		(end 225.5 109.95)
		(width 0.1)
		(layer "In7.Cu")
		(net 569)
	)
	(segment
		(start 201.1 137.8)
		(end 201.5 137.4)
		(width 0.1)
		(layer "In7.Cu")
		(net 569)
	)
	(segment
		(start 212 142)
		(end 211.6 141.6)
		(width 0.1)
		(layer "In7.Cu")
		(net 569)
	)
	(segment
		(start 213.5 138.5)
		(end 214.025921 139.025921)
		(width 0.256)
		(layer "F.Cu")
		(net 570)
	)
	(segment
		(start 242.585 115.9)
		(end 242.6 115.885)
		(width 0.198)
		(layer "F.Cu")
		(net 570)
	)
	(segment
		(start 214.025921 139.025921)
		(end 214.025921 139.034831)
		(width 0.256)
		(layer "F.Cu")
		(net 570)
	)
	(segment
		(start 241.8 115.9)
		(end 242.585 115.9)
		(width 0.198)
		(layer "F.Cu")
		(net 570)
	)
	(via
		(at 241.8 115.9)
		(size 0.45)
		(drill 0.2)
		(layers "F.Cu" "B.Cu")
		(net 570)
	)
	(via
		(at 214.025921 139.034831)
		(size 0.45)
		(drill 0.2)
		(layers "F.Cu" "B.Cu")
		(net 570)
	)
	(segment
		(start 217.330331 140.6)
		(end 217.930331 141.2)
		(width 0.1)
		(layer "In3.Cu")
		(net 570)
	)
	(segment
		(start 229.263173 139.25)
		(end 230.825 137.688173)
		(width 0.1)
		(layer "In3.Cu")
		(net 570)
	)
	(segment
		(start 235.3 124.119669)
		(end 234.925 123.744669)
		(width 0.1)
		(layer "In3.Cu")
		(net 570)
	)
	(segment
		(start 244.2 108.975)
		(end 244.2 115.475)
		(width 0.1)
		(layer "In3.Cu")
		(net 570)
	)
	(segment
		(start 243.775 115.9)
		(end 241.8 115.9)
		(width 0.1)
		(layer "In3.Cu")
		(net 570)
	)
	(segment
		(start 244.225 108.95)
		(end 244.2 108.975)
		(width 0.1)
		(layer "In3.Cu")
		(net 570)
	)
	(segment
		(start 225.882842 141.2)
		(end 227.832841 139.25)
		(width 0.1)
		(layer "In3.Cu")
		(net 570)
	)
	(segment
		(start 234.425 132.794669)
		(end 234.425 126.4)
		(width 0.1)
		(layer "In3.Cu")
		(net 570)
	)
	(segment
		(start 227.832841 139.25)
		(end 229.263173 139.25)
		(width 0.1)
		(layer "In3.Cu")
		(net 570)
	)
	(segment
		(start 215.59109 140.6)
		(end 217.330331 140.6)
		(width 0.1)
		(layer "In3.Cu")
		(net 570)
	)
	(segment
		(start 234.425 126.4)
		(end 235.3 125.525)
		(width 0.1)
		(layer "In3.Cu")
		(net 570)
	)
	(segment
		(start 234.925 109.125)
		(end 235.575 108.475)
		(width 0.1)
		(layer "In3.Cu")
		(net 570)
	)
	(segment
		(start 235.3 125.525)
		(end 235.3 124.119669)
		(width 0.1)
		(layer "In3.Cu")
		(net 570)
	)
	(segment
		(start 234.925 123.744669)
		(end 234.925 109.125)
		(width 0.1)
		(layer "In3.Cu")
		(net 570)
	)
	(segment
		(start 230.825 136.394669)
		(end 234.425 132.794669)
		(width 0.1)
		(layer "In3.Cu")
		(net 570)
	)
	(segment
		(start 243.75 108.475)
		(end 244.225 108.95)
		(width 0.1)
		(layer "In3.Cu")
		(net 570)
	)
	(segment
		(start 244.2 115.475)
		(end 243.775 115.9)
		(width 0.1)
		(layer "In3.Cu")
		(net 570)
	)
	(segment
		(start 214.025921 139.034831)
		(end 215.59109 140.6)
		(width 0.1)
		(layer "In3.Cu")
		(net 570)
	)
	(segment
		(start 235.575 108.475)
		(end 243.75 108.475)
		(width 0.1)
		(layer "In3.Cu")
		(net 570)
	)
	(segment
		(start 230.825 137.688173)
		(end 230.825 136.394669)
		(width 0.1)
		(layer "In3.Cu")
		(net 570)
	)
	(segment
		(start 217.930331 141.2)
		(end 225.882842 141.2)
		(width 0.1)
		(layer "In3.Cu")
		(net 570)
	)
	(segment
		(start 210.5 140.5)
		(end 211 141)
		(width 0.256)
		(layer "F.Cu")
		(net 571)
	)
	(via
		(at 201.96 164.99)
		(size 0.45)
		(drill 0.2)
		(layers "F.Cu" "B.Cu")
		(net 571)
	)
	(via
		(at 211 141)
		(size 0.45)
		(drill 0.2)
		(layers "F.Cu" "B.Cu")
		(net 571)
	)
	(via
		(at 159 184.48)
		(size 0.45)
		(drill 0.2)
		(layers "F.Cu" "B.Cu")
		(net 571)
	)
	(segment
		(start 209.56 143.64)
		(end 209.7 143.5)
		(width 0.1)
		(layer "B.Cu")
		(net 571)
	)
	(segment
		(start 201.96 164.99)
		(end 201.96 164.71)
		(width 0.1)
		(layer "B.Cu")
		(net 571)
	)
	(segment
		(start 210.4 143.3)
		(end 210.4 141.4)
		(width 0.1)
		(layer "B.Cu")
		(net 571)
	)
	(segment
		(start 201.96 164.71)
		(end 209.56 157.11)
		(width 0.1)
		(layer "B.Cu")
		(net 571)
	)
	(segment
		(start 210.8 141)
		(end 211 141)
		(width 0.1)
		(layer "B.Cu")
		(net 571)
	)
	(segment
		(start 209.7 143.5)
		(end 210.2 143.5)
		(width 0.1)
		(layer "B.Cu")
		(net 571)
	)
	(segment
		(start 210.4 141.4)
		(end 210.8 141)
		(width 0.1)
		(layer "B.Cu")
		(net 571)
	)
	(segment
		(start 209.56 157.11)
		(end 209.56 143.64)
		(width 0.1)
		(layer "B.Cu")
		(net 571)
	)
	(segment
		(start 210.2 143.5)
		(end 210.4 143.3)
		(width 0.1)
		(layer "B.Cu")
		(net 571)
	)
	(segment
		(start 167.25 180.22)
		(end 195.74 180.22)
		(width 0.1)
		(layer "In7.Cu")
		(net 571)
	)
	(segment
		(start 197.75 169.2)
		(end 201.96 164.99)
		(width 0.1)
		(layer "In7.Cu")
		(net 571)
	)
	(segment
		(start 195.74 180.22)
		(end 197.75 178.21)
		(width 0.1)
		(layer "In7.Cu")
		(net 571)
	)
	(segment
		(start 197.75 178.21)
		(end 197.75 169.2)
		(width 0.1)
		(layer "In7.Cu")
		(net 571)
	)
	(segment
		(start 159 184.48)
		(end 159 183.994169)
		(width 0.1)
		(layer "In7.Cu")
		(net 571)
	)
	(segment
		(start 159 183.994169)
		(end 159.914169 183.08)
		(width 0.1)
		(layer "In7.Cu")
		(net 571)
	)
	(segment
		(start 159.914169 183.08)
		(end 164.39 183.08)
		(width 0.1)
		(layer "In7.Cu")
		(net 571)
	)
	(segment
		(start 164.39 183.08)
		(end 167.25 180.22)
		(width 0.1)
		(layer "In7.Cu")
		(net 571)
	)
	(segment
		(start 211.5 140.5)
		(end 212 141)
		(width 0.256)
		(layer "F.Cu")
		(net 572)
	)
	(via
		(at 160 183.5245)
		(size 0.45)
		(drill 0.2)
		(layers "F.Cu" "B.Cu")
		(net 572)
	)
	(via
		(at 210.125 147.575)
		(size 0.45)
		(drill 0.2)
		(layers "F.Cu" "B.Cu")
		(net 572)
	)
	(via
		(at 212 141)
		(size 0.45)
		(drill 0.2)
		(layers "F.Cu" "B.Cu")
		(net 572)
	)
	(segment
		(start 212.375 146.325)
		(end 212.375 144.475)
		(width 0.1)
		(layer "B.Cu")
		(net 572)
	)
	(segment
		(start 212.375 144.475)
		(end 211.4 143.5)
		(width 0.1)
		(layer "B.Cu")
		(net 572)
	)
	(segment
		(start 211.4 141.6)
		(end 212 141)
		(width 0.1)
		(layer "B.Cu")
		(net 572)
	)
	(segment
		(start 210.125 147.575)
		(end 211.125 147.575)
		(width 0.1)
		(layer "B.Cu")
		(net 572)
	)
	(segment
		(start 211.4 143.5)
		(end 211.4 141.6)
		(width 0.1)
		(layer "B.Cu")
		(net 572)
	)
	(segment
		(start 211.125 147.575)
		(end 212.375 146.325)
		(width 0.1)
		(layer "B.Cu")
		(net 572)
	)
	(segment
		(start 192.85 154.8)
		(end 189.725 157.925)
		(width 0.1)
		(layer "In3.Cu")
		(net 572)
	)
	(segment
		(start 161.95 172.375)
		(end 163.99 174.415)
		(width 0.1)
		(layer "In3.Cu")
		(net 572)
	)
	(segment
		(start 189.725 157.925)
		(end 170.425 157.925)
		(width 0.1)
		(layer "In3.Cu")
		(net 572)
	)
	(segment
		(start 170.425 157.925)
		(end 161.95 166.4)
		(width 0.1)
		(layer "In3.Cu")
		(net 572)
	)
	(segment
		(start 209.075 154.8)
		(end 192.85 154.8)
		(width 0.1)
		(layer "In3.Cu")
		(net 572)
	)
	(segment
		(start 209.7 148)
		(end 209.7 154.175)
		(width 0.1)
		(layer "In3.Cu")
		(net 572)
	)
	(segment
		(start 209.7 154.175)
		(end 209.075 154.8)
		(width 0.1)
		(layer "In3.Cu")
		(net 572)
	)
	(segment
		(start 161.3755 183.5245)
		(end 160 183.5245)
		(width 0.1)
		(layer "In3.Cu")
		(net 572)
	)
	(segment
		(start 161.95 166.4)
		(end 161.95 172.375)
		(width 0.1)
		(layer "In3.Cu")
		(net 572)
	)
	(segment
		(start 163.99 180.91)
		(end 161.3755 183.5245)
		(width 0.1)
		(layer "In3.Cu")
		(net 572)
	)
	(segment
		(start 210.125 147.575)
		(end 209.7 148)
		(width 0.1)
		(layer "In3.Cu")
		(net 572)
	)
	(segment
		(start 163.99 174.415)
		(end 163.99 180.91)
		(width 0.1)
		(layer "In3.Cu")
		(net 572)
	)
	(segment
		(start 159.95 184.535)
		(end 160 184.485)
		(width 0.1)
		(layer "F.Cu")
		(net 577)
	)
	(segment
		(start 159.95 185.75)
		(end 159.95 184.535)
		(width 0.1)
		(layer "F.Cu")
		(net 577)
	)
	(segment
		(start 161 184.485)
		(end 160 184.485)
		(width 0.1)
		(layer "F.Cu")
		(net 577)
	)
	(via
		(at 160 184.485)
		(size 0.45)
		(drill 0.2)
		(layers "F.Cu" "B.Cu")
		(net 577)
	)
	(segment
		(start 160 185.415)
		(end 160 184.485)
		(width 0.1)
		(layer "B.Cu")
		(net 577)
	)
	(segment
		(start 200.5 115.5)
		(end 200.5 114.4)
		(width 0.182)
		(layer "F.Cu")
		(net 578)
	)
	(segment
		(start 195.575 113.275)
		(end 196.2 113.9)
		(width 0.184)
		(layer "F.Cu")
		(net 578)
	)
	(segment
		(start 195.575 111.225)
		(end 195.575 113.275)
		(width 0.182)
		(layer "F.Cu")
		(net 578)
	)
	(segment
		(start 196.2 113.9)
		(end 200 113.9)
		(width 0.184)
		(layer "F.Cu")
		(net 578)
	)
	(segment
		(start 200 113.9)
		(end 200.5 114.4)
		(width 0.184)
		(layer "F.Cu")
		(net 578)
	)
	(segment
		(start 201.5 115.5)
		(end 201.5 114.2)
		(width 0.182)
		(layer "F.Cu")
		(net 579)
	)
	(segment
		(start 201.5 114.2)
		(end 201.5 114)
		(width 0.184)
		(layer "F.Cu")
		(net 579)
	)
	(segment
		(start 196.575 111.225)
		(end 196.575 112.275)
		(width 0.182)
		(layer "F.Cu")
		(net 579)
	)
	(segment
		(start 201.5 114)
		(end 200.5 113)
		(width 0.184)
		(layer "F.Cu")
		(net 579)
	)
	(segment
		(start 197.3 113)
		(end 196.575 112.275)
		(width 0.184)
		(layer "F.Cu")
		(net 579)
	)
	(segment
		(start 200.5 113)
		(end 197.3 113)
		(width 0.184)
		(layer "F.Cu")
		(net 579)
	)
	(segment
		(start 202.5 113.35)
		(end 202.5 113.25)
		(width 0.182)
		(layer "F.Cu")
		(net 580)
	)
	(segment
		(start 198.5 112)
		(end 197.8 111.3)
		(width 0.184)
		(layer "F.Cu")
		(net 580)
	)
	(segment
		(start 202.5 115.5)
		(end 202.5 113.35)
		(width 0.182)
		(layer "F.Cu")
		(net 580)
	)
	(segment
		(start 202.5 113.25)
		(end 201.25 112)
		(width 0.184)
		(layer "F.Cu")
		(net 580)
	)
	(segment
		(start 201.25 112)
		(end 198.5 112)
		(width 0.184)
		(layer "F.Cu")
		(net 580)
	)
	(segment
		(start 197.8 110.5)
		(end 197.8 111.3)
		(width 0.182)
		(layer "F.Cu")
		(net 580)
	)
	(segment
		(start 250.4 96.015)
		(end 250.415 96)
		(width 0.1)
		(layer "F.Cu")
		(net 583)
	)
	(segment
		(start 252.415 96)
		(end 252.415 96.96)
		(width 0.182)
		(layer "F.Cu")
		(net 583)
	)
	(segment
		(start 251.7 97.55)
		(end 251.25 97.55)
		(width 0.1)
		(layer "F.Cu")
		(net 583)
	)
	(segment
		(start 250.715 97.015)
		(end 250.4 97.015)
		(width 0.1)
		(layer "F.Cu")
		(net 583)
	)
	(segment
		(start 251.825 97.55)
		(end 251.7 97.55)
		(width 0.182)
		(layer "F.Cu")
		(net 583)
	)
	(segment
		(start 252.415 96.96)
		(end 251.825 97.55)
		(width 0.182)
		(layer "F.Cu")
		(net 583)
	)
	(segment
		(start 250.4 97.015)
		(end 250.4 96.015)
		(width 0.1)
		(layer "F.Cu")
		(net 583)
	)
	(segment
		(start 251.25 97.55)
		(end 250.715 97.015)
		(width 0.1)
		(layer "F.Cu")
		(net 583)
	)
	(segment
		(start 232.3 148.6)
		(end 232.9 148.6)
		(width 0.182)
		(layer "F.Cu")
		(net 584)
	)
	(segment
		(start 232 148.9)
		(end 232.3 148.6)
		(width 0.182)
		(layer "F.Cu")
		(net 584)
	)
	(segment
		(start 199.5 135.5)
		(end 199 136)
		(width 0.256)
		(layer "F.Cu")
		(net 584)
	)
	(via
		(at 232 148.9)
		(size 0.45)
		(drill 0.2)
		(layers "F.Cu" "B.Cu")
		(net 584)
	)
	(via
		(at 199 136)
		(size 0.45)
		(drill 0.2)
		(layers "F.Cu" "B.Cu")
		(net 584)
	)
	(segment
		(start 231.2 148.9)
		(end 231 149.1)
		(width 0.1)
		(layer "In7.Cu")
		(net 584)
	)
	(segment
		(start 216.36 146.36)
		(end 199.96 146.36)
		(width 0.1)
		(layer "In7.Cu")
		(net 584)
	)
	(segment
		(start 197.4 137.6)
		(end 199 136)
		(width 0.1)
		(layer "In7.Cu")
		(net 584)
	)
	(segment
		(start 197.4 143.8)
		(end 197.4 137.6)
		(width 0.1)
		(layer "In7.Cu")
		(net 584)
	)
	(segment
		(start 231 149.1)
		(end 219.1 149.1)
		(width 0.1)
		(layer "In7.Cu")
		(net 584)
	)
	(segment
		(start 219.1 149.1)
		(end 216.36 146.36)
		(width 0.1)
		(layer "In7.Cu")
		(net 584)
	)
	(segment
		(start 199.96 146.36)
		(end 197.4 143.8)
		(width 0.1)
		(layer "In7.Cu")
		(net 584)
	)
	(segment
		(start 232 148.9)
		(end 231.2 148.9)
		(width 0.1)
		(layer "In7.Cu")
		(net 584)
	)
	(segment
		(start 232.1 148.2)
		(end 232.9 148.2)
		(width 0.182)
		(layer "F.Cu")
		(net 587)
	)
	(segment
		(start 199.5 136.5)
		(end 199 137)
		(width 0.256)
		(layer "F.Cu")
		(net 587)
	)
	(segment
		(start 232 148.3)
		(end 232.1 148.2)
		(width 0.182)
		(layer "F.Cu")
		(net 587)
	)
	(via
		(at 232 148.3)
		(size 0.45)
		(drill 0.2)
		(layers "F.Cu" "B.Cu")
		(net 587)
	)
	(via
		(at 199 137)
		(size 0.45)
		(drill 0.2)
		(layers "F.Cu" "B.Cu")
		(net 587)
	)
	(segment
		(start 199.9 145.9)
		(end 197.6 143.6)
		(width 0.1)
		(layer "In7.Cu")
		(net 587)
	)
	(segment
		(start 197.6 138.4)
		(end 199 137)
		(width 0.1)
		(layer "In7.Cu")
		(net 587)
	)
	(segment
		(start 219.2 148.3)
		(end 216.8 145.9)
		(width 0.1)
		(layer "In7.Cu")
		(net 587)
	)
	(segment
		(start 197.6 143.6)
		(end 197.6 138.4)
		(width 0.1)
		(layer "In7.Cu")
		(net 587)
	)
	(segment
		(start 232 148.3)
		(end 219.2 148.3)
		(width 0.1)
		(layer "In7.Cu")
		(net 587)
	)
	(segment
		(start 216.8 145.9)
		(end 199.9 145.9)
		(width 0.1)
		(layer "In7.Cu")
		(net 587)
	)
	(segment
		(start 202.5 136.5)
		(end 203 137)
		(width 0.256)
		(layer "F.Cu")
		(net 589)
	)
	(segment
		(start 219.95 149.05)
		(end 219.7 148.8)
		(width 0.184)
		(layer "F.Cu")
		(net 589)
	)
	(segment
		(start 219.7 148.8)
		(end 219.7 147.6165)
		(width 0.184)
		(layer "F.Cu")
		(net 589)
	)
	(segment
		(start 220.4625 149.05)
		(end 219.95 149.05)
		(width 0.184)
		(layer "F.Cu")
		(net 589)
	)
	(via
		(at 203 137)
		(size 0.45)
		(drill 0.2)
		(layers "F.Cu" "B.Cu")
		(net 589)
	)
	(via
		(at 219.7 147.6165)
		(size 0.45)
		(drill 0.2)
		(layers "F.Cu" "B.Cu")
		(net 589)
	)
	(segment
		(start 207.518665 156.457268)
		(end 207.518664 156.45727)
		(width 0.1)
		(layer "In5.Cu")
		(net 589)
	)
	(segment
		(start 202.625 151.582842)
		(end 203.2 152.157842)
		(width 0.1)
		(layer "In5.Cu")
		(net 589)
	)
	(segment
		(start 207.2 157.1)
		(end 207.525 157.1)
		(width 0.1)
		(layer "In5.Cu")
		(net 589)
	)
	(segment
		(start 217 148.175)
		(end 219.1415 148.175)
		(width 0.1)
		(layer "In5.Cu")
		(net 589)
	)
	(segment
		(start 207.595711 156.781802)
		(end 207.518665 156.704756)
		(width 0.1)
		(layer "In5.Cu")
		(net 589)
	)
	(segment
		(start 206.275 156.41604)
		(end 206.275 156.925)
		(width 0.1)
		(layer "In5.Cu")
		(net 589)
	)
	(segment
		(start 219.1415 148.175)
		(end 219.7 147.6165)
		(width 0.1)
		(layer "In5.Cu")
		(net 589)
	)
	(segment
		(start 205.925 156.925)
		(end 205.925 156.41604)
		(width 0.1)
		(layer "In5.Cu")
		(net 589)
	)
	(segment
		(start 207.525 157.1)
		(end 207.59571 157.02929)
		(width 0.1)
		(layer "In5.Cu")
		(net 589)
	)
	(segment
		(start 216.65 149.925)
		(end 216.65 148.525)
		(width 0.1)
		(layer "In5.Cu")
		(net 589)
	)
	(segment
		(start 205.575 156.41604)
		(end 205.575 156.925)
		(width 0.1)
		(layer "In5.Cu")
		(net 589)
	)
	(segment
		(start 206.975 156.41604)
		(end 206.975 156.925)
		(width 0.1)
		(layer "In5.Cu")
		(net 589)
	)
	(segment
		(start 203.6 157.1)
		(end 203.65 157.1)
		(width 0.1)
		(layer "In5.Cu")
		(net 589)
	)
	(segment
		(start 208.090687 156.534316)
		(end 208.197116 156.427884)
		(width 0.1)
		(layer "In5.Cu")
		(net 589)
	)
	(segment
		(start 205.225 156.925)
		(end 205.225 156.41604)
		(width 0.1)
		(layer "In5.Cu")
		(net 589)
	)
	(segment
		(start 216.65 148.525)
		(end 217 148.175)
		(width 0.1)
		(layer "In5.Cu")
		(net 589)
	)
	(segment
		(start 203.825 156.925)
		(end 203.825 156.41604)
		(width 0.1)
		(layer "In5.Cu")
		(net 589)
	)
	(segment
		(start 203 137)
		(end 202.625 137.375)
		(width 0.1)
		(layer "In5.Cu")
		(net 589)
	)
	(segment
		(start 203.2 156.7)
		(end 203.6 157.1)
		(width 0.1)
		(layer "In5.Cu")
		(net 589)
	)
	(segment
		(start 202.625 137.375)
		(end 202.625 151.582842)
		(width 0.1)
		(layer "In5.Cu")
		(net 589)
	)
	(segment
		(start 207.15 157.1)
		(end 207.2 157.1)
		(width 0.1)
		(layer "In5.Cu")
		(net 589)
	)
	(segment
		(start 208.090687 156.534317)
		(end 208.090687 156.534316)
		(width 0.1)
		(layer "In5.Cu")
		(net 589)
	)
	(segment
		(start 213.075 153.5)
		(end 216.65 149.925)
		(width 0.1)
		(layer "In5.Cu")
		(net 589)
	)
	(segment
		(start 207.766152 156.45727)
		(end 207.843199 156.534317)
		(width 0.1)
		(layer "In5.Cu")
		(net 589)
	)
	(segment
		(start 206.625 156.925)
		(end 206.625 156.41604)
		(width 0.1)
		(layer "In5.Cu")
		(net 589)
	)
	(segment
		(start 204.875 156.41604)
		(end 204.875 156.925)
		(width 0.1)
		(layer "In5.Cu")
		(net 589)
	)
	(segment
		(start 204.525 156.925)
		(end 204.525 156.41604)
		(width 0.1)
		(layer "In5.Cu")
		(net 589)
	)
	(segment
		(start 208.197116 156.427884)
		(end 211.125 153.5)
		(width 0.1)
		(layer "In5.Cu")
		(net 589)
	)
	(segment
		(start 211.125 153.5)
		(end 213.075 153.5)
		(width 0.1)
		(layer "In5.Cu")
		(net 589)
	)
	(segment
		(start 204.175 156.41604)
		(end 204.175 156.925)
		(width 0.1)
		(layer "In5.Cu")
		(net 589)
	)
	(segment
		(start 207.59571 156.781804)
		(end 207.595711 156.781802)
		(width 0.1)
		(layer "In5.Cu")
		(net 589)
	)
	(segment
		(start 203.2 152.157842)
		(end 203.2 156.7)
		(width 0.1)
		(layer "In5.Cu")
		(net 589)
	)
	(arc
		(start 206.625 156.41604)
		(mid 206.676256 156.292296)
		(end 206.8 156.24104)
		(width 0.1)
		(layer "In5.Cu")
		(net 589)
	)
	(arc
		(start 204.875 156.925)
		(mid 204.926256 157.048744)
		(end 205.05 157.1)
		(width 0.1)
		(layer "In5.Cu")
		(net 589)
	)
	(arc
		(start 207.518664 156.45727)
		(mid 207.642408 156.406014)
		(end 207.766152 156.45727)
		(width 0.1)
		(layer "In5.Cu")
		(net 589)
	)
	(arc
		(start 205.925 156.41604)
		(mid 205.976256 156.292296)
		(end 206.1 156.24104)
		(width 0.1)
		(layer "In5.Cu")
		(net 589)
	)
	(arc
		(start 207.59571 157.02929)
		(mid 207.646967 156.905546)
		(end 207.59571 156.781804)
		(width 0.1)
		(layer "In5.Cu")
		(net 589)
	)
	(arc
		(start 204.35 157.1)
		(mid 204.473744 157.048744)
		(end 204.525 156.925)
		(width 0.1)
		(layer "In5.Cu")
		(net 589)
	)
	(arc
		(start 204.175 156.925)
		(mid 204.226256 157.048744)
		(end 204.35 157.1)
		(width 0.1)
		(layer "In5.Cu")
		(net 589)
	)
	(arc
		(start 205.4 156.24104)
		(mid 205.523744 156.292296)
		(end 205.575 156.41604)
		(width 0.1)
		(layer "In5.Cu")
		(net 589)
	)
	(arc
		(start 206.275 156.925)
		(mid 206.326256 157.048744)
		(end 206.45 157.1)
		(width 0.1)
		(layer "In5.Cu")
		(net 589)
	)
	(arc
		(start 206.45 157.1)
		(mid 206.573744 157.048744)
		(end 206.625 156.925)
		(width 0.1)
		(layer "In5.Cu")
		(net 589)
	)
	(arc
		(start 207.843199 156.534317)
		(mid 207.966943 156.585573)
		(end 208.090687 156.534317)
		(width 0.1)
		(layer "In5.Cu")
		(net 589)
	)
	(arc
		(start 206.975 156.925)
		(mid 207.026256 157.048744)
		(end 207.15 157.1)
		(width 0.1)
		(layer "In5.Cu")
		(net 589)
	)
	(arc
		(start 205.05 157.1)
		(mid 205.173744 157.048744)
		(end 205.225 156.925)
		(width 0.1)
		(layer "In5.Cu")
		(net 589)
	)
	(arc
		(start 205.75 157.1)
		(mid 205.873744 157.048744)
		(end 205.925 156.925)
		(width 0.1)
		(layer "In5.Cu")
		(net 589)
	)
	(arc
		(start 203.65 157.1)
		(mid 203.773744 157.048744)
		(end 203.825 156.925)
		(width 0.1)
		(layer "In5.Cu")
		(net 589)
	)
	(arc
		(start 203.825 156.41604)
		(mid 203.876256 156.292296)
		(end 204 156.24104)
		(width 0.1)
		(layer "In5.Cu")
		(net 589)
	)
	(arc
		(start 206.1 156.24104)
		(mid 206.223744 156.292296)
		(end 206.275 156.41604)
		(width 0.1)
		(layer "In5.Cu")
		(net 589)
	)
	(arc
		(start 205.225 156.41604)
		(mid 205.276256 156.292296)
		(end 205.4 156.24104)
		(width 0.1)
		(layer "In5.Cu")
		(net 589)
	)
	(arc
		(start 205.575 156.925)
		(mid 205.626256 157.048744)
		(end 205.75 157.1)
		(width 0.1)
		(layer "In5.Cu")
		(net 589)
	)
	(arc
		(start 206.8 156.24104)
		(mid 206.923744 156.292296)
		(end 206.975 156.41604)
		(width 0.1)
		(layer "In5.Cu")
		(net 589)
	)
	(arc
		(start 204.7 156.24104)
		(mid 204.823744 156.292296)
		(end 204.875 156.41604)
		(width 0.1)
		(layer "In5.Cu")
		(net 589)
	)
	(arc
		(start 204.525 156.41604)
		(mid 204.576256 156.292296)
		(end 204.7 156.24104)
		(width 0.1)
		(layer "In5.Cu")
		(net 589)
	)
	(arc
		(start 204 156.24104)
		(mid 204.123744 156.292296)
		(end 204.175 156.41604)
		(width 0.1)
		(layer "In5.Cu")
		(net 589)
	)
	(arc
		(start 207.518665 156.704756)
		(mid 207.467409 156.581012)
		(end 207.518665 156.457268)
		(width 0.1)
		(layer "In5.Cu")
		(net 589)
	)
	(segment
		(start 176.483051 105.799501)
		(end 177.012339 106.328789)
		(width 0.201)
		(layer "F.Cu")
		(net 591)
	)
	(segment
		(start 174.330751 105.799501)
		(end 176.483051 105.799501)
		(width 0.201)
		(layer "F.Cu")
		(net 591)
	)
	(segment
		(start 177.012339 106.328789)
		(end 177.012339 106.973077)
		(width 0.201)
		(layer "F.Cu")
		(net 591)
	)
	(segment
		(start 177.012339 106.973077)
		(end 177.136839 107.097577)
		(width 0.201)
		(layer "F.Cu")
		(net 591)
	)
	(segment
		(start 174.055001 105.523751)
		(end 174.330751 105.799501)
		(width 0.201)
		(layer "F.Cu")
		(net 591)
	)
	(via
		(at 177.136839 107.097577)
		(size 0.45)
		(drill 0.2)
		(layers "F.Cu" "B.Cu")
		(net 591)
	)
	(via
		(at 192.5 131.5)
		(size 0.45)
		(drill 0.2)
		(layers "F.Cu" "B.Cu")
		(net 591)
	)
	(segment
		(start 177.020501 107.213915)
		(end 177.020501 128.576951)
		(width 0.201)
		(layer "B.Cu")
		(net 591)
	)
	(segment
		(start 192.500001 131.500001)
		(end 192.169001 131.500001)
		(width 0.1)
		(layer "B.Cu")
		(net 591)
	)
	(segment
		(start 179.242551 130.799001)
		(end 183.346376 130.799001)
		(width 0.201)
		(layer "B.Cu")
		(net 591)
	)
	(segment
		(start 183.447376 130.900001)
		(end 183.346376 130.799001)
		(width 0.1)
		(layer "B.Cu")
		(net 591)
	)
	(segment
		(start 177.020501 128.576951)
		(end 179.242551 130.799001)
		(width 0.201)
		(layer "B.Cu")
		(net 591)
	)
	(segment
		(start 177.136839 107.097577)
		(end 177.020501 107.213915)
		(width 0.201)
		(layer "B.Cu")
		(net 591)
	)
	(segment
		(start 192.169001 131.500001)
		(end 192.0994 131.4304)
		(width 0.1)
		(layer "B.Cu")
		(net 591)
	)
	(segment
		(start 192.0994 131.4304)
		(end 192.0994 131.137977)
		(width 0.1)
		(layer "B.Cu")
		(net 591)
	)
	(segment
		(start 191.861424 130.900001)
		(end 183.447376 130.900001)
		(width 0.1)
		(layer "B.Cu")
		(net 591)
	)
	(segment
		(start 192.0994 131.137977)
		(end 191.861424 130.900001)
		(width 0.1)
		(layer "B.Cu")
		(net 591)
	)
	(segment
		(start 176.611339 106.494889)
		(end 176.611339 106.973077)
		(width 0.201)
		(layer "F.Cu")
		(net 592)
	)
	(segment
		(start 174.055001 106.476251)
		(end 174.330751 106.200501)
		(width 0.201)
		(layer "F.Cu")
		(net 592)
	)
	(segment
		(start 176.316951 106.200501)
		(end 176.611339 106.494889)
		(width 0.201)
		(layer "F.Cu")
		(net 592)
	)
	(segment
		(start 174.330751 106.200501)
		(end 176.316951 106.200501)
		(width 0.201)
		(layer "F.Cu")
		(net 592)
	)
	(segment
		(start 176.611339 106.973077)
		(end 176.486839 107.097577)
		(width 0.201)
		(layer "F.Cu")
		(net 592)
	)
	(via
		(at 176.486839 107.097577)
		(size 0.45)
		(drill 0.2)
		(layers "F.Cu" "B.Cu")
		(net 592)
	)
	(via
		(at 191.5 131.5)
		(size 0.45)
		(drill 0.2)
		(layers "F.Cu" "B.Cu")
		(net 592)
	)
	(segment
		(start 176.619501 128.743051)
		(end 179.076451 131.200001)
		(width 0.201)
		(layer "B.Cu")
		(net 592)
	)
	(segment
		(start 191.77858 131.100001)
		(end 183.446376 131.100001)
		(width 0.1)
		(layer "B.Cu")
		(net 592)
	)
	(segment
		(start 183.446376 131.100001)
		(end 183.346376 131.200001)
		(width 0.1)
		(layer "B.Cu")
		(net 592)
	)
	(segment
		(start 191.807001 131.500001)
		(end 191.8994 131.407602)
		(width 0.1)
		(layer "B.Cu")
		(net 592)
	)
	(segment
		(start 191.8994 131.407602)
		(end 191.8994 131.220821)
		(width 0.1)
		(layer "B.Cu")
		(net 592)
	)
	(segment
		(start 176.619501 107.230239)
		(end 176.619501 128.743051)
		(width 0.201)
		(layer "B.Cu")
		(net 592)
	)
	(segment
		(start 191.500001 131.500001)
		(end 191.807001 131.500001)
		(width 0.1)
		(layer "B.Cu")
		(net 592)
	)
	(segment
		(start 179.076451 131.200001)
		(end 183.346376 131.200001)
		(width 0.201)
		(layer "B.Cu")
		(net 592)
	)
	(segment
		(start 191.8994 131.220821)
		(end 191.77858 131.100001)
		(width 0.1)
		(layer "B.Cu")
		(net 592)
	)
	(segment
		(start 176.486839 107.097577)
		(end 176.619501 107.230239)
		(width 0.201)
		(layer "B.Cu")
		(net 592)
	)
	(segment
		(start 156.285001 85.045001)
		(end 156.285001 85.226198)
		(width 0.16)
		(layer "F.Cu")
		(net 593)
	)
	(segment
		(start 156.285001 85.226198)
		(end 156.606804 85.548001)
		(width 0.16)
		(layer "F.Cu")
		(net 593)
	)
	(segment
		(start 156.775002 85.548)
		(end 156.606804 85.548001)
		(width 0.16)
		(layer "F.Cu")
		(net 593)
	)
	(segment
		(start 156.775002 85.548)
		(end 156.920001 85.403001)
		(width 0.16)
		(layer "F.Cu")
		(net 593)
	)
	(via
		(at 156.920001 85.403001)
		(size 0.45)
		(drill 0.2)
		(layers "F.Cu" "B.Cu")
		(net 593)
	)
	(segment
		(start 157.377002 85.548)
		(end 157.760001 85.165001)
		(width 0.16)
		(layer "B.Cu")
		(net 593)
	)
	(segment
		(start 156.920001 85.403001)
		(end 157.065 85.548)
		(width 0.16)
		(layer "B.Cu")
		(net 593)
	)
	(segment
		(start 157.065 85.548)
		(end 157.377002 85.548)
		(width 0.16)
		(layer "B.Cu")
		(net 593)
	)
	(segment
		(start 192.500001 125.500001)
		(end 192.210001 125.500001)
		(width 0.1)
		(layer "F.Cu")
		(net 594)
	)
	(segment
		(start 172.320001 86.459001)
		(end 176.207451 86.459001)
		(width 0.201)
		(layer "F.Cu")
		(net 594)
	)
	(segment
		(start 182.200501 105.916951)
		(end 184.820001 108.536451)
		(width 0.201)
		(layer "F.Cu")
		(net 594)
	)
	(segment
		(start 184.820001 108.536451)
		(end 184.820001 124.613849)
		(width 0.201)
		(layer "F.Cu")
		(net 594)
	)
	(segment
		(start 185.241 124.900001)
		(end 185.14 124.799)
		(width 0.1)
		(layer "F.Cu")
		(net 594)
	)
	(segment
		(start 185.005152 124.799)
		(end 185.14 124.799)
		(width 0.201)
		(layer "F.Cu")
		(net 594)
	)
	(segment
		(start 182.200501 87.216951)
		(end 182.200501 105.916951)
		(width 0.201)
		(layer "F.Cu")
		(net 594)
	)
	(segment
		(start 180.563051 85.579501)
		(end 182.200501 87.216951)
		(width 0.201)
		(layer "F.Cu")
		(net 594)
	)
	(segment
		(start 184.820001 124.613849)
		(end 185.005152 124.799)
		(width 0.201)
		(layer "F.Cu")
		(net 594)
	)
	(segment
		(start 192.210001 125.500001)
		(end 192.0994 125.3894)
		(width 0.1)
		(layer "F.Cu")
		(net 594)
	)
	(segment
		(start 176.207451 86.459001)
		(end 177.086951 85.579501)
		(width 0.201)
		(layer "F.Cu")
		(net 594)
	)
	(segment
		(start 192.0994 125.137977)
		(end 191.861424 124.900001)
		(width 0.1)
		(layer "F.Cu")
		(net 594)
	)
	(segment
		(start 177.086951 85.579501)
		(end 180.563051 85.579501)
		(width 0.201)
		(layer "F.Cu")
		(net 594)
	)
	(segment
		(start 172.195501 86.334501)
		(end 172.320001 86.459001)
		(width 0.201)
		(layer "F.Cu")
		(net 594)
	)
	(segment
		(start 192.0994 125.3894)
		(end 192.0994 125.137977)
		(width 0.1)
		(layer "F.Cu")
		(net 594)
	)
	(segment
		(start 185.241 124.900001)
		(end 191.861424 124.900001)
		(width 0.1)
		(layer "F.Cu")
		(net 594)
	)
	(via
		(at 172.195501 86.334501)
		(size 0.45)
		(drill 0.2)
		(layers "F.Cu" "B.Cu")
		(net 594)
	)
	(segment
		(start 172.071001 86.459001)
		(end 170.642551 86.459001)
		(width 0.201)
		(layer "B.Cu")
		(net 594)
	)
	(segment
		(start 160.063051 85.479501)
		(end 159.044501 85.479501)
		(width 0.201)
		(layer "B.Cu")
		(net 594)
	)
	(segment
		(start 160.583051 85.999501)
		(end 160.063051 85.479501)
		(width 0.201)
		(layer "B.Cu")
		(net 594)
	)
	(segment
		(start 172.195501 86.334501)
		(end 172.071001 86.459001)
		(width 0.201)
		(layer "B.Cu")
		(net 594)
	)
	(segment
		(start 159.044501 85.479501)
		(end 158.730001 85.165001)
		(width 0.201)
		(layer "B.Cu")
		(net 594)
	)
	(segment
		(start 170.642551 86.459001)
		(end 170.183051 85.999501)
		(width 0.201)
		(layer "B.Cu")
		(net 594)
	)
	(segment
		(start 170.183051 85.999501)
		(end 160.583051 85.999501)
		(width 0.201)
		(layer "B.Cu")
		(net 594)
	)
	(segment
		(start 156.775002 85.812002)
		(end 156.606804 85.812001)
		(width 0.16)
		(layer "F.Cu")
		(net 595)
	)
	(segment
		(start 156.285001 86.133804)
		(end 156.285001 86.315001)
		(width 0.16)
		(layer "F.Cu")
		(net 595)
	)
	(segment
		(start 156.606804 85.812001)
		(end 156.285001 86.133804)
		(width 0.16)
		(layer "F.Cu")
		(net 595)
	)
	(segment
		(start 156.775002 85.812002)
		(end 156.920001 85.957001)
		(width 0.16)
		(layer "F.Cu")
		(net 595)
	)
	(via
		(at 156.920001 85.957001)
		(size 0.45)
		(drill 0.2)
		(layers "F.Cu" "B.Cu")
		(net 595)
	)
	(segment
		(start 157.377002 85.812002)
		(end 157.760001 86.195001)
		(width 0.16)
		(layer "B.Cu")
		(net 595)
	)
	(segment
		(start 156.920001 85.957001)
		(end 157.065 85.812002)
		(width 0.16)
		(layer "B.Cu")
		(net 595)
	)
	(segment
		(start 157.065 85.812002)
		(end 157.377002 85.812002)
		(width 0.16)
		(layer "B.Cu")
		(net 595)
	)
	(segment
		(start 191.77858 125.100001)
		(end 191.8994 125.220821)
		(width 0.1)
		(layer "F.Cu")
		(net 596)
	)
	(segment
		(start 185.14 125.2)
		(end 185.24 125.1)
		(width 0.1)
		(layer "F.Cu")
		(net 596)
	)
	(segment
		(start 184.419001 124.779949)
		(end 184.839052 125.2)
		(width 0.201)
		(layer "F.Cu")
		(net 596)
	)
	(segment
		(start 180.396951 85.980501)
		(end 181.799501 87.383051)
		(width 0.201)
		(layer "F.Cu")
		(net 596)
	)
	(segment
		(start 190.888001 125.200001)
		(end 190.888001 125.331282)
		(width 0.1)
		(layer "F.Cu")
		(net 596)
	)
	(segment
		(start 191.8994 125.220821)
		(end 191.899399 125.430604)
		(width 0.1)
		(layer "F.Cu")
		(net 596)
	)
	(segment
		(start 181.799501 106.083051)
		(end 184.419001 108.702551)
		(width 0.201)
		(layer "F.Cu")
		(net 596)
	)
	(segment
		(start 191.188001 125.100001)
		(end 191.77858 125.100001)
		(width 0.1)
		(layer "F.Cu")
		(net 596)
	)
	(segment
		(start 191.088001 125.331282)
		(end 191.088001 125.200001)
		(width 0.1)
		(layer "F.Cu")
		(net 596)
	)
	(segment
		(start 184.839052 125.2)
		(end 185.14 125.2)
		(width 0.201)
		(layer "F.Cu")
		(net 596)
	)
	(segment
		(start 181.799501 87.383051)
		(end 181.799501 106.083051)
		(width 0.201)
		(layer "F.Cu")
		(net 596)
	)
	(segment
		(start 176.373551 86.860001)
		(end 177.253051 85.980501)
		(width 0.201)
		(layer "F.Cu")
		(net 596)
	)
	(segment
		(start 191.830002 125.500001)
		(end 191.500001 125.500001)
		(width 0.1)
		(layer "F.Cu")
		(net 596)
	)
	(segment
		(start 185.24 125.1)
		(end 190.788001 125.100001)
		(width 0.1)
		(layer "F.Cu")
		(net 596)
	)
	(segment
		(start 177.253051 85.980501)
		(end 180.396951 85.980501)
		(width 0.201)
		(layer "F.Cu")
		(net 596)
	)
	(segment
		(start 172.195501 86.984501)
		(end 172.320001 86.860001)
		(width 0.201)
		(layer "F.Cu")
		(net 596)
	)
	(segment
		(start 184.419001 108.702551)
		(end 184.419001 124.779949)
		(width 0.201)
		(layer "F.Cu")
		(net 596)
	)
	(segment
		(start 191.899399 125.430604)
		(end 191.830002 125.500001)
		(width 0.1)
		(layer "F.Cu")
		(net 596)
	)
	(segment
		(start 172.320001 86.860001)
		(end 176.373551 86.860001)
		(width 0.201)
		(layer "F.Cu")
		(net 596)
	)
	(via
		(at 172.195501 86.984501)
		(size 0.45)
		(drill 0.2)
		(layers "F.Cu" "B.Cu")
		(net 596)
	)
	(arc
		(start 190.788001 125.100001)
		(mid 190.858712 125.12929)
		(end 190.888001 125.200001)
		(width 0.1)
		(layer "F.Cu")
		(net 596)
	)
	(arc
		(start 191.088001 125.200001)
		(mid 191.11729 125.12929)
		(end 191.188001 125.100001)
		(width 0.1)
		(layer "F.Cu")
		(net 596)
	)
	(arc
		(start 190.988001 125.431282)
		(mid 191.058712 125.401993)
		(end 191.088001 125.331282)
		(width 0.1)
		(layer "F.Cu")
		(net 596)
	)
	(arc
		(start 190.888001 125.331282)
		(mid 190.91729 125.401993)
		(end 190.988001 125.431282)
		(width 0.1)
		(layer "F.Cu")
		(net 596)
	)
	(segment
		(start 172.195501 86.984501)
		(end 172.071001 86.860001)
		(width 0.201)
		(layer "B.Cu")
		(net 596)
	)
	(segment
		(start 160.416951 86.400501)
		(end 159.896951 85.880501)
		(width 0.201)
		(layer "B.Cu")
		(net 596)
	)
	(segment
		(start 170.476451 86.860001)
		(end 170.016951 86.400501)
		(width 0.201)
		(layer "B.Cu")
		(net 596)
	)
	(segment
		(start 159.896951 85.880501)
		(end 159.044501 85.880501)
		(width 0.201)
		(layer "B.Cu")
		(net 596)
	)
	(segment
		(start 172.071001 86.860001)
		(end 170.476451 86.860001)
		(width 0.201)
		(layer "B.Cu")
		(net 596)
	)
	(segment
		(start 170.016951 86.400501)
		(end 160.416951 86.400501)
		(width 0.201)
		(layer "B.Cu")
		(net 596)
	)
	(segment
		(start 159.044501 85.880501)
		(end 158.730001 86.195001)
		(width 0.201)
		(layer "B.Cu")
		(net 596)
	)
	(segment
		(start 157.555001 82.686198)
		(end 157.876804 83.008001)
		(width 0.16)
		(layer "F.Cu")
		(net 597)
	)
	(segment
		(start 158.045002 83.008)
		(end 158.190001 82.863001)
		(width 0.16)
		(layer "F.Cu")
		(net 597)
	)
	(segment
		(start 157.555001 82.505001)
		(end 157.555001 82.686198)
		(width 0.16)
		(layer "F.Cu")
		(net 597)
	)
	(segment
		(start 158.045002 83.008)
		(end 157.876804 83.008001)
		(width 0.16)
		(layer "F.Cu")
		(net 597)
	)
	(via
		(at 158.190001 82.863001)
		(size 0.45)
		(drill 0.2)
		(layers "F.Cu" "B.Cu")
		(net 597)
	)
	(segment
		(start 158.659136 83.005866)
		(end 159.030001 82.635001)
		(width 0.16)
		(layer "B.Cu")
		(net 597)
	)
	(segment
		(start 158.659136 83.008001)
		(end 158.659136 83.005866)
		(width 0.16)
		(layer "B.Cu")
		(net 597)
	)
	(segment
		(start 158.335 83.008)
		(end 158.659136 83.008001)
		(width 0.16)
		(layer "B.Cu")
		(net 597)
	)
	(segment
		(start 158.190001 82.863001)
		(end 158.335 83.008)
		(width 0.16)
		(layer "B.Cu")
		(net 597)
	)
	(via
		(at 192.5 127.5)
		(size 0.45)
		(drill 0.2)
		(layers "F.Cu" "B.Cu")
		(net 598)
	)
	(segment
		(start 184.524001 126.900001)
		(end 191.861424 126.900001)
		(width 0.1)
		(layer "B.Cu")
		(net 598)
	)
	(segment
		(start 160.000001 82.635001)
		(end 160.299501 82.934501)
		(width 0.201)
		(layer "B.Cu")
		(net 598)
	)
	(segment
		(start 183.999001 126.725001)
		(end 183.999001 126.685996)
		(width 0.1)
		(layer "B.Cu")
		(net 598)
	)
	(segment
		(start 183.447376 126.900001)
		(end 183.824001 126.900001)
		(width 0.1)
		(layer "B.Cu")
		(net 598)
	)
	(segment
		(start 182.220501 126.190283)
		(end 182.829219 126.799001)
		(width 0.201)
		(layer "B.Cu")
		(net 598)
	)
	(segment
		(start 184.349001 126.685996)
		(end 184.349001 126.725001)
		(width 0.1)
		(layer "B.Cu")
		(net 598)
	)
	(segment
		(start 192.0994 127.137977)
		(end 192.0994 127.3894)
		(width 0.1)
		(layer "B.Cu")
		(net 598)
	)
	(segment
		(start 182.829219 126.799001)
		(end 183.346376 126.799001)
		(width 0.201)
		(layer "B.Cu")
		(net 598)
	)
	(segment
		(start 162.078051 82.934501)
		(end 163.993051 84.849501)
		(width 0.201)
		(layer "B.Cu")
		(net 598)
	)
	(segment
		(start 192.210001 127.500001)
		(end 192.500001 127.500001)
		(width 0.1)
		(layer "B.Cu")
		(net 598)
	)
	(segment
		(start 177.203051 82.199501)
		(end 178.325501 83.321951)
		(width 0.201)
		(layer "B.Cu")
		(net 598)
	)
	(segment
		(start 170.666951 84.849501)
		(end 173.316951 82.199501)
		(width 0.201)
		(layer "B.Cu")
		(net 598)
	)
	(segment
		(start 191.861424 126.900001)
		(end 192.0994 127.137977)
		(width 0.1)
		(layer "B.Cu")
		(net 598)
	)
	(segment
		(start 192.0994 127.3894)
		(end 192.210001 127.500001)
		(width 0.1)
		(layer "B.Cu")
		(net 598)
	)
	(segment
		(start 183.346376 126.799001)
		(end 183.447376 126.900001)
		(width 0.1)
		(layer "B.Cu")
		(net 598)
	)
	(segment
		(start 160.299501 82.934501)
		(end 162.078051 82.934501)
		(width 0.201)
		(layer "B.Cu")
		(net 598)
	)
	(segment
		(start 163.993051 84.849501)
		(end 170.666951 84.849501)
		(width 0.201)
		(layer "B.Cu")
		(net 598)
	)
	(segment
		(start 178.325501 88.731951)
		(end 182.220501 92.626951)
		(width 0.201)
		(layer "B.Cu")
		(net 598)
	)
	(segment
		(start 178.325501 83.321951)
		(end 178.325501 88.731951)
		(width 0.201)
		(layer "B.Cu")
		(net 598)
	)
	(segment
		(start 173.316951 82.199501)
		(end 177.203051 82.199501)
		(width 0.201)
		(layer "B.Cu")
		(net 598)
	)
	(segment
		(start 182.220501 92.626951)
		(end 182.220501 126.190283)
		(width 0.201)
		(layer "B.Cu")
		(net 598)
	)
	(arc
		(start 183.824001 126.900001)
		(mid 183.947745 126.848745)
		(end 183.999001 126.725001)
		(width 0.1)
		(layer "B.Cu")
		(net 598)
	)
	(arc
		(start 183.999001 126.685996)
		(mid 184.050257 126.562252)
		(end 184.174001 126.510996)
		(width 0.1)
		(layer "B.Cu")
		(net 598)
	)
	(arc
		(start 184.174001 126.510996)
		(mid 184.297745 126.562252)
		(end 184.349001 126.685996)
		(width 0.1)
		(layer "B.Cu")
		(net 598)
	)
	(arc
		(start 184.349001 126.725001)
		(mid 184.400257 126.848745)
		(end 184.524001 126.900001)
		(width 0.1)
		(layer "B.Cu")
		(net 598)
	)
	(segment
		(start 158.045002 83.272002)
		(end 158.190001 83.417001)
		(width 0.16)
		(layer "F.Cu")
		(net 599)
	)
	(segment
		(start 157.876804 83.272001)
		(end 157.555001 83.593804)
		(width 0.16)
		(layer "F.Cu")
		(net 599)
	)
	(segment
		(start 158.045002 83.272002)
		(end 157.876804 83.272001)
		(width 0.16)
		(layer "F.Cu")
		(net 599)
	)
	(segment
		(start 157.555001 83.593804)
		(end 157.555001 83.775001)
		(width 0.16)
		(layer "F.Cu")
		(net 599)
	)
	(via
		(at 158.190001 83.417001)
		(size 0.45)
		(drill 0.2)
		(layers "F.Cu" "B.Cu")
		(net 599)
	)
	(segment
		(start 158.190001 83.417001)
		(end 158.335 83.272002)
		(width 0.16)
		(layer "B.Cu")
		(net 599)
	)
	(segment
		(start 158.667001 83.272001)
		(end 159.030001 83.635001)
		(width 0.16)
		(layer "B.Cu")
		(net 599)
	)
	(segment
		(start 158.335 83.272002)
		(end 158.667001 83.272001)
		(width 0.16)
		(layer "B.Cu")
		(net 599)
	)
	(via
		(at 191.5 127.5)
		(size 0.45)
		(drill 0.2)
		(layers "F.Cu" "B.Cu")
		(net 600)
	)
	(segment
		(start 191.8994 127.220821)
		(end 191.77858 127.100001)
		(width 0.1)
		(layer "B.Cu")
		(net 600)
	)
	(segment
		(start 173.483051 82.600501)
		(end 177.036951 82.600501)
		(width 0.201)
		(layer "B.Cu")
		(net 600)
	)
	(segment
		(start 191.77858 127.100001)
		(end 191.240004 127.100001)
		(width 0.1)
		(layer "B.Cu")
		(net 600)
	)
	(segment
		(start 160.000001 83.635001)
		(end 160.299501 83.335501)
		(width 0.201)
		(layer "B.Cu")
		(net 600)
	)
	(segment
		(start 177.924501 83.488051)
		(end 177.924501 88.898051)
		(width 0.201)
		(layer "B.Cu")
		(net 600)
	)
	(segment
		(start 170.833051 85.250501)
		(end 173.483051 82.600501)
		(width 0.201)
		(layer "B.Cu")
		(net 600)
	)
	(segment
		(start 183.446376 127.100001)
		(end 183.346376 127.200001)
		(width 0.1)
		(layer "B.Cu")
		(net 600)
	)
	(segment
		(start 191.115004 127.225001)
		(end 191.115004 127.248021)
		(width 0.1)
		(layer "B.Cu")
		(net 600)
	)
	(segment
		(start 190.740004 127.100001)
		(end 183.446376 127.100001)
		(width 0.1)
		(layer "B.Cu")
		(net 600)
	)
	(segment
		(start 181.819501 92.793051)
		(end 181.819501 126.356383)
		(width 0.201)
		(layer "B.Cu")
		(net 600)
	)
	(segment
		(start 161.911951 83.335501)
		(end 163.826951 85.250501)
		(width 0.201)
		(layer "B.Cu")
		(net 600)
	)
	(segment
		(start 177.036951 82.600501)
		(end 177.924501 83.488051)
		(width 0.201)
		(layer "B.Cu")
		(net 600)
	)
	(segment
		(start 191.830002 127.500001)
		(end 191.899399 127.430604)
		(width 0.1)
		(layer "B.Cu")
		(net 600)
	)
	(segment
		(start 191.899399 127.430604)
		(end 191.8994 127.220821)
		(width 0.1)
		(layer "B.Cu")
		(net 600)
	)
	(segment
		(start 181.819501 126.356383)
		(end 182.663119 127.200001)
		(width 0.201)
		(layer "B.Cu")
		(net 600)
	)
	(segment
		(start 160.299501 83.335501)
		(end 161.911951 83.335501)
		(width 0.201)
		(layer "B.Cu")
		(net 600)
	)
	(segment
		(start 177.924501 88.898051)
		(end 181.819501 92.793051)
		(width 0.201)
		(layer "B.Cu")
		(net 600)
	)
	(segment
		(start 191.830002 127.500001)
		(end 191.500001 127.500001)
		(width 0.1)
		(layer "B.Cu")
		(net 600)
	)
	(segment
		(start 182.663119 127.200001)
		(end 183.346376 127.200001)
		(width 0.201)
		(layer "B.Cu")
		(net 600)
	)
	(segment
		(start 163.826951 85.250501)
		(end 170.833051 85.250501)
		(width 0.201)
		(layer "B.Cu")
		(net 600)
	)
	(segment
		(start 190.865004 127.248021)
		(end 190.865004 127.225001)
		(width 0.1)
		(layer "B.Cu")
		(net 600)
	)
	(arc
		(start 190.865004 127.225001)
		(mid 190.828392 127.136613)
		(end 190.740004 127.100001)
		(width 0.1)
		(layer "B.Cu")
		(net 600)
	)
	(arc
		(start 191.240004 127.100001)
		(mid 191.151616 127.136613)
		(end 191.115004 127.225001)
		(width 0.1)
		(layer "B.Cu")
		(net 600)
	)
	(arc
		(start 190.990004 127.373021)
		(mid 190.901616 127.336409)
		(end 190.865004 127.248021)
		(width 0.1)
		(layer "B.Cu")
		(net 600)
	)
	(arc
		(start 191.115004 127.248021)
		(mid 191.078392 127.336409)
		(end 190.990004 127.373021)
		(width 0.1)
		(layer "B.Cu")
		(net 600)
	)
	(segment
		(start 200.987651 140.987651)
		(end 200.987651 140.999895)
		(width 0.256)
		(layer "F.Cu")
		(net 616)
	)
	(segment
		(start 234.8255 149.6)
		(end 234.3 149.6)
		(width 0.182)
		(layer "F.Cu")
		(net 616)
	)
	(segment
		(start 200.5 140.5)
		(end 200.987651 140.987651)
		(width 0.256)
		(layer "F.Cu")
		(net 616)
	)
	(via
		(at 200.987651 140.999895)
		(size 0.45)
		(drill 0.2)
		(layers "F.Cu" "B.Cu")
		(net 616)
	)
	(via
		(at 234.8255 149.6)
		(size 0.45)
		(drill 0.2)
		(layers "F.Cu" "B.Cu")
		(net 616)
	)
	(segment
		(start 236.3 147.3)
		(end 234.8255 148.7745)
		(width 0.1)
		(layer "In7.Cu")
		(net 616)
	)
	(segment
		(start 212.74 142.41)
		(end 213.375 141.775)
		(width 0.1)
		(layer "In7.Cu")
		(net 616)
	)
	(segment
		(start 236.3 144.95)
		(end 236.3 147.3)
		(width 0.1)
		(layer "In7.Cu")
		(net 616)
	)
	(segment
		(start 200.987651 140.999895)
		(end 201.5 141.512244)
		(width 0.1)
		(layer "In7.Cu")
		(net 616)
	)
	(segment
		(start 201.5 141.512244)
		(end 201.5 142.1)
		(width 0.1)
		(layer "In7.Cu")
		(net 616)
	)
	(segment
		(start 201.5 142.1)
		(end 201.81 142.41)
		(width 0.1)
		(layer "In7.Cu")
		(net 616)
	)
	(segment
		(start 201.81 142.41)
		(end 212.74 142.41)
		(width 0.1)
		(layer "In7.Cu")
		(net 616)
	)
	(segment
		(start 234.8255 148.7745)
		(end 234.8255 149.6)
		(width 0.1)
		(layer "In7.Cu")
		(net 616)
	)
	(segment
		(start 213.375 141.775)
		(end 233.125 141.775)
		(width 0.1)
		(layer "In7.Cu")
		(net 616)
	)
	(segment
		(start 233.125 141.775)
		(end 236.3 144.95)
		(width 0.1)
		(layer "In7.Cu")
		(net 616)
	)
	(segment
		(start 233.1 147.1)
		(end 232.8 146.8)
		(width 0.182)
		(layer "F.Cu")
		(net 619)
	)
	(segment
		(start 233.1 147.2)
		(end 233.1 147.1)
		(width 0.182)
		(layer "F.Cu")
		(net 619)
	)
	(segment
		(start 199.5 141.5)
		(end 199 142)
		(width 0.256)
		(layer "F.Cu")
		(net 619)
	)
	(via
		(at 232.8 146.8)
		(size 0.45)
		(drill 0.2)
		(layers "F.Cu" "B.Cu")
		(net 619)
	)
	(via
		(at 199 142)
		(size 0.45)
		(drill 0.2)
		(layers "F.Cu" "B.Cu")
		(net 619)
	)
	(segment
		(start 234.7 147.2)
		(end 233.2 147.2)
		(width 0.1)
		(layer "In7.Cu")
		(net 619)
	)
	(segment
		(start 233.2 147.2)
		(end 232.8 146.8)
		(width 0.1)
		(layer "In7.Cu")
		(net 619)
	)
	(segment
		(start 235.1 146.8)
		(end 234.7 147.2)
		(width 0.1)
		(layer "In7.Cu")
		(net 619)
	)
	(segment
		(start 215.6 143.8)
		(end 233 143.8)
		(width 0.1)
		(layer "In7.Cu")
		(net 619)
	)
	(segment
		(start 233 143.8)
		(end 235.1 145.9)
		(width 0.1)
		(layer "In7.Cu")
		(net 619)
	)
	(segment
		(start 235.1 145.9)
		(end 235.1 146.8)
		(width 0.1)
		(layer "In7.Cu")
		(net 619)
	)
	(segment
		(start 199.5 142.5)
		(end 199.5 143.030331)
		(width 0.1)
		(layer "In7.Cu")
		(net 619)
	)
	(segment
		(start 200.069669 143.6)
		(end 215.4 143.6)
		(width 0.1)
		(layer "In7.Cu")
		(net 619)
	)
	(segment
		(start 199 142)
		(end 199.5 142.5)
		(width 0.1)
		(layer "In7.Cu")
		(net 619)
	)
	(segment
		(start 215.4 143.6)
		(end 215.6 143.8)
		(width 0.1)
		(layer "In7.Cu")
		(net 619)
	)
	(segment
		(start 199.5 143.030331)
		(end 200.069669 143.6)
		(width 0.1)
		(layer "In7.Cu")
		(net 619)
	)
	(segment
		(start 156.2 148)
		(end 156.2 147.135)
		(width 0.256)
		(layer "F.Cu")
		(net 622)
	)
	(segment
		(start 199.5 128.5)
		(end 199 128)
		(width 0.256)
		(layer "F.Cu")
		(net 622)
	)
	(via
		(at 199 128)
		(size 0.45)
		(drill 0.2)
		(layers "F.Cu" "B.Cu")
		(net 622)
	)
	(via
		(at 156.2 148)
		(size 0.45)
		(drill 0.2)
		(layers "F.Cu" "B.Cu")
		(net 622)
	)
	(segment
		(start 192.379361 128.98)
		(end 192.01 129.349361)
		(width 0.256)
		(layer "In7.Cu")
		(net 622)
	)
	(segment
		(start 157.300001 131.800001)
		(end 153.500001 135.600001)
		(width 0.256)
		(layer "In7.Cu")
		(net 622)
	)
	(segment
		(start 163.000001 132.400001)
		(end 162.400001 131.800001)
		(width 0.256)
		(layer "In7.Cu")
		(net 622)
	)
	(segment
		(start 198.500001 128.500001)
		(end 193.469999 128.500001)
		(width 0.256)
		(layer "In7.Cu")
		(net 622)
	)
	(segment
		(start 193.469999 128.500001)
		(end 192.99 128.98)
		(width 0.256)
		(layer "In7.Cu")
		(net 622)
	)
	(segment
		(start 192.01 129.349361)
		(end 192.01 129.803998)
		(width 0.256)
		(layer "In7.Cu")
		(net 622)
	)
	(segment
		(start 162.400001 131.800001)
		(end 157.300001 131.800001)
		(width 0.256)
		(layer "In7.Cu")
		(net 622)
	)
	(segment
		(start 199.000001 128.000001)
		(end 198.500001 128.500001)
		(width 0.256)
		(layer "In7.Cu")
		(net 622)
	)
	(segment
		(start 170.200001 132.400001)
		(end 163.000001 132.400001)
		(width 0.256)
		(layer "In7.Cu")
		(net 622)
	)
	(segment
		(start 153.500001 135.600001)
		(end 153.500001 145.300001)
		(width 0.256)
		(layer "In7.Cu")
		(net 622)
	)
	(segment
		(start 191.803998 130.01)
		(end 172.590002 130.01)
		(width 0.256)
		(layer "In7.Cu")
		(net 622)
	)
	(segment
		(start 172.590002 130.01)
		(end 170.200001 132.400001)
		(width 0.256)
		(layer "In7.Cu")
		(net 622)
	)
	(segment
		(start 192.99 128.98)
		(end 192.379361 128.98)
		(width 0.256)
		(layer "In7.Cu")
		(net 622)
	)
	(segment
		(start 153.500001 145.300001)
		(end 156.200001 148.000001)
		(width 0.256)
		(layer "In7.Cu")
		(net 622)
	)
	(segment
		(start 192.01 129.803998)
		(end 191.803998 130.01)
		(width 0.256)
		(layer "In7.Cu")
		(net 622)
	)
	(segment
		(start 194.228578 139.9)
		(end 193.9 140.228578)
		(width 0.1)
		(layer "F.Cu")
		(net 623)
	)
	(segment
		(start 195.158578 138.9)
		(end 194.9 139.158578)
		(width 0.1)
		(layer "F.Cu")
		(net 623)
	)
	(segment
		(start 193.9 140.228578)
		(end 193.9 142.678578)
		(width 0.1)
		(layer "F.Cu")
		(net 623)
	)
	(segment
		(start 193.678578 142.9)
		(end 193.248578 142.9)
		(width 0.1)
		(layer "F.Cu")
		(net 623)
	)
	(segment
		(start 189.915001 149.985)
		(end 190.415001 149.485)
		(width 0.1)
		(layer "F.Cu")
		(net 623)
	)
	(segment
		(start 195.9 138.575)
		(end 195.9 138.733578)
		(width 0.1)
		(layer "F.Cu")
		(net 623)
	)
	(segment
		(start 193.248578 142.9)
		(end 192.9 143.248578)
		(width 0.1)
		(layer "F.Cu")
		(net 623)
	)
	(segment
		(start 190.415001 149.170001)
		(end 190.030001 148.785001)
		(width 0.1)
		(layer "F.Cu")
		(net 623)
	)
	(segment
		(start 195.5 138.5)
		(end 195.825 138.5)
		(width 0.1)
		(layer "F.Cu")
		(net 623)
	)
	(segment
		(start 193.9 142.678578)
		(end 193.678578 142.9)
		(width 0.1)
		(layer "F.Cu")
		(net 623)
	)
	(segment
		(start 195.9 138.733578)
		(end 195.733578 138.9)
		(width 0.1)
		(layer "F.Cu")
		(net 623)
	)
	(segment
		(start 195.733578 138.9)
		(end 195.158578 138.9)
		(width 0.1)
		(layer "F.Cu")
		(net 623)
	)
	(segment
		(start 190.415001 149.485)
		(end 190.415001 149.170001)
		(width 0.1)
		(layer "F.Cu")
		(net 623)
	)
	(segment
		(start 194.9 139.158578)
		(end 194.9 139.718578)
		(width 0.1)
		(layer "F.Cu")
		(net 623)
	)
	(segment
		(start 194.718578 139.9)
		(end 194.228578 139.9)
		(width 0.1)
		(layer "F.Cu")
		(net 623)
	)
	(segment
		(start 194.9 139.718578)
		(end 194.718578 139.9)
		(width 0.1)
		(layer "F.Cu")
		(net 623)
	)
	(segment
		(start 190.415001 148.400001)
		(end 190.030001 148.785001)
		(width 0.1)
		(layer "F.Cu")
		(net 623)
	)
	(segment
		(start 189.915001 150.085)
		(end 189.915001 149.985)
		(width 0.1)
		(layer "F.Cu")
		(net 623)
	)
	(segment
		(start 192.9 145.558578)
		(end 190.415001 148.043577)
		(width 0.1)
		(layer "F.Cu")
		(net 623)
	)
	(segment
		(start 192.9 143.248578)
		(end 192.9 145.558578)
		(width 0.1)
		(layer "F.Cu")
		(net 623)
	)
	(segment
		(start 195.825 138.5)
		(end 195.9 138.575)
		(width 0.1)
		(layer "F.Cu")
		(net 623)
	)
	(segment
		(start 190.415001 148.043577)
		(end 190.415001 148.400001)
		(width 0.1)
		(layer "F.Cu")
		(net 623)
	)
	(segment
		(start 190.615001 149.170001)
		(end 191.000001 148.785001)
		(width 0.1)
		(layer "F.Cu")
		(net 624)
	)
	(segment
		(start 195.1 139.241422)
		(end 195.1 139.801422)
		(width 0.1)
		(layer "F.Cu")
		(net 624)
	)
	(segment
		(start 195.816422 139.1)
		(end 195.241422 139.1)
		(width 0.1)
		(layer "F.Cu")
		(net 624)
	)
	(segment
		(start 192.223797 146.517628)
		(end 192.223798 146.517628)
		(width 0.1)
		(layer "F.Cu")
		(net 624)
	)
	(segment
		(start 192.480711 146.376205)
		(end 192.480712 146.376206)
		(width 0.1)
		(layer "F.Cu")
		(net 624)
	)
	(segment
		(start 193.761422 143.1)
		(end 193.331422 143.1)
		(width 0.1)
		(layer "F.Cu")
		(net 624)
	)
	(segment
		(start 192.480713 146.491699)
		(end 192.480711 146.4917)
		(width 0.1)
		(layer "F.Cu")
		(net 624)
	)
	(segment
		(start 192.197868 146.543555)
		(end 190.615001 148.126421)
		(width 0.1)
		(layer "F.Cu")
		(net 624)
	)
	(segment
		(start 192.339291 146.517627)
		(end 192.33929 146.517629)
		(width 0.1)
		(layer "F.Cu")
		(net 624)
	)
	(segment
		(start 195.1 139.801422)
		(end 194.801422 140.1)
		(width 0.1)
		(layer "F.Cu")
		(net 624)
	)
	(segment
		(start 193.331422 143.1)
		(end 193.1 143.331422)
		(width 0.1)
		(layer "F.Cu")
		(net 624)
	)
	(segment
		(start 195.241422 139.1)
		(end 195.1 139.241422)
		(width 0.1)
		(layer "F.Cu")
		(net 624)
	)
	(segment
		(start 194.311422 140.1)
		(end 194.1 140.311422)
		(width 0.1)
		(layer "F.Cu")
		(net 624)
	)
	(segment
		(start 193.1 143.331422)
		(end 193.1 145.641422)
		(width 0.1)
		(layer "F.Cu")
		(net 624)
	)
	(segment
		(start 196.1 138.575)
		(end 196.1 138.816422)
		(width 0.1)
		(layer "F.Cu")
		(net 624)
	)
	(segment
		(start 190.615001 149.485)
		(end 190.615001 149.170001)
		(width 0.1)
		(layer "F.Cu")
		(net 624)
	)
	(segment
		(start 194.1 142.761422)
		(end 193.761422 143.1)
		(width 0.1)
		(layer "F.Cu")
		(net 624)
	)
	(segment
		(start 196.1 138.816422)
		(end 195.816422 139.1)
		(width 0.1)
		(layer "F.Cu")
		(net 624)
	)
	(segment
		(start 190.615001 148.400001)
		(end 191.000001 148.785001)
		(width 0.1)
		(layer "F.Cu")
		(net 624)
	)
	(segment
		(start 192.480711 146.4917)
		(end 192.454784 146.517628)
		(width 0.1)
		(layer "F.Cu")
		(net 624)
	)
	(segment
		(start 193.1 145.641422)
		(end 192.480711 146.260711)
		(width 0.1)
		(layer "F.Cu")
		(net 624)
	)
	(segment
		(start 192.223798 146.517628)
		(end 192.197868 146.543555)
		(width 0.1)
		(layer "F.Cu")
		(net 624)
	)
	(segment
		(start 191.115001 150.085)
		(end 191.115001 149.985)
		(width 0.1)
		(layer "F.Cu")
		(net 624)
	)
	(segment
		(start 190.615001 148.126421)
		(end 190.615001 148.400001)
		(width 0.1)
		(layer "F.Cu")
		(net 624)
	)
	(segment
		(start 194.801422 140.1)
		(end 194.311422 140.1)
		(width 0.1)
		(layer "F.Cu")
		(net 624)
	)
	(segment
		(start 196.175 138.5)
		(end 196.1 138.575)
		(width 0.1)
		(layer "F.Cu")
		(net 624)
	)
	(segment
		(start 194.1 140.311422)
		(end 194.1 142.761422)
		(width 0.1)
		(layer "F.Cu")
		(net 624)
	)
	(segment
		(start 196.5 138.5)
		(end 196.175 138.5)
		(width 0.1)
		(layer "F.Cu")
		(net 624)
	)
	(segment
		(start 191.115001 149.985)
		(end 190.615001 149.485)
		(width 0.1)
		(layer "F.Cu")
		(net 624)
	)
	(arc
		(start 192.480712 146.376206)
		(mid 192.504632 146.433952)
		(end 192.480713 146.491699)
		(width 0.1)
		(layer "F.Cu")
		(net 624)
	)
	(arc
		(start 192.454784 146.517628)
		(mid 192.397037 146.541547)
		(end 192.339291 146.517627)
		(width 0.1)
		(layer "F.Cu")
		(net 624)
	)
	(arc
		(start 192.480711 146.260711)
		(mid 192.45679 146.318459)
		(end 192.480711 146.376205)
		(width 0.1)
		(layer "F.Cu")
		(net 624)
	)
	(arc
		(start 192.33929 146.517629)
		(mid 192.281544 146.493709)
		(end 192.223797 146.517628)
		(width 0.1)
		(layer "F.Cu")
		(net 624)
	)
	(segment
		(start 172.093201 84.533251)
		(end 171.146951 85.479501)
		(width 0.201)
		(layer "F.Cu")
		(net 627)
	)
	(segment
		(start 170.504001 85.548001)
		(end 170.572501 85.479501)
		(width 0.16)
		(layer "F.Cu")
		(net 627)
	)
	(segment
		(start 172.809251 84.533251)
		(end 172.093201 84.533251)
		(width 0.201)
		(layer "F.Cu")
		(net 627)
	)
	(segment
		(start 163.905001 85.045001)
		(end 164.408 85.548)
		(width 0.16)
		(layer "F.Cu")
		(net 627)
	)
	(segment
		(start 171.146951 85.479501)
		(end 170.572501 85.479501)
		(width 0.201)
		(layer "F.Cu")
		(net 627)
	)
	(segment
		(start 173.085001 84.257501)
		(end 172.809251 84.533251)
		(width 0.201)
		(layer "F.Cu")
		(net 627)
	)
	(segment
		(start 164.408 85.548)
		(end 170.504001 85.548001)
		(width 0.16)
		(layer "F.Cu")
		(net 627)
	)
	(segment
		(start 175.509811 84.930191)
		(end 175.333741 84.930191)
		(width 0.201)
		(layer "F.Cu")
		(net 628)
	)
	(segment
		(start 174.936801 84.533251)
		(end 174.330751 84.533251)
		(width 0.201)
		(layer "F.Cu")
		(net 628)
	)
	(segment
		(start 175.333741 84.930191)
		(end 174.936801 84.533251)
		(width 0.201)
		(layer "F.Cu")
		(net 628)
	)
	(segment
		(start 174.330751 84.533251)
		(end 174.055001 84.257501)
		(width 0.201)
		(layer "F.Cu")
		(net 628)
	)
	(via
		(at 175.509811 84.930191)
		(size 0.45)
		(drill 0.2)
		(layers "F.Cu" "B.Cu")
		(net 628)
	)
	(via
		(at 192.5 129.5)
		(size 0.45)
		(drill 0.2)
		(layers "F.Cu" "B.Cu")
		(net 628)
	)
	(segment
		(start 192.500001 129.500001)
		(end 192.210001 129.500001)
		(width 0.1)
		(layer "B.Cu")
		(net 628)
	)
	(segment
		(start 181.052561 128.799011)
		(end 183.34545 128.799011)
		(width 0.201)
		(layer "B.Cu")
		(net 628)
	)
	(segment
		(start 192.210001 129.500001)
		(end 192.0994 129.3894)
		(width 0.1)
		(layer "B.Cu")
		(net 628)
	)
	(segment
		(start 175.509811 85.106261)
		(end 175.720501 85.316951)
		(width 0.201)
		(layer "B.Cu")
		(net 628)
	)
	(segment
		(start 175.509811 84.930191)
		(end 175.509811 85.106261)
		(width 0.201)
		(layer "B.Cu")
		(net 628)
	)
	(segment
		(start 192.0994 129.3894)
		(end 192.0994 129.137977)
		(width 0.1)
		(layer "B.Cu")
		(net 628)
	)
	(segment
		(start 183.44644 128.900001)
		(end 183.34545 128.799011)
		(width 0.1)
		(layer "B.Cu")
		(net 628)
	)
	(segment
		(start 191.861424 128.900001)
		(end 183.44644 128.900001)
		(width 0.1)
		(layer "B.Cu")
		(net 628)
	)
	(segment
		(start 179.620501 127.366951)
		(end 181.052561 128.799011)
		(width 0.201)
		(layer "B.Cu")
		(net 628)
	)
	(segment
		(start 175.720501 85.316951)
		(end 175.720501 90.006951)
		(width 0.201)
		(layer "B.Cu")
		(net 628)
	)
	(segment
		(start 179.620501 93.906951)
		(end 179.620501 127.366951)
		(width 0.201)
		(layer "B.Cu")
		(net 628)
	)
	(segment
		(start 192.0994 129.137977)
		(end 191.861424 128.900001)
		(width 0.1)
		(layer "B.Cu")
		(net 628)
	)
	(segment
		(start 175.720501 90.006951)
		(end 179.620501 93.906951)
		(width 0.201)
		(layer "B.Cu")
		(net 628)
	)
	(segment
		(start 172.809251 84.934251)
		(end 172.259301 84.934251)
		(width 0.201)
		(layer "F.Cu")
		(net 629)
	)
	(segment
		(start 164.408 85.812002)
		(end 170.504001 85.812001)
		(width 0.16)
		(layer "F.Cu")
		(net 629)
	)
	(segment
		(start 170.504001 85.812001)
		(end 170.572501 85.880501)
		(width 0.16)
		(layer "F.Cu")
		(net 629)
	)
	(segment
		(start 171.313051 85.880501)
		(end 170.572501 85.880501)
		(width 0.201)
		(layer "F.Cu")
		(net 629)
	)
	(segment
		(start 172.259301 84.934251)
		(end 171.313051 85.880501)
		(width 0.201)
		(layer "F.Cu")
		(net 629)
	)
	(segment
		(start 163.905001 86.315001)
		(end 164.408 85.812002)
		(width 0.16)
		(layer "F.Cu")
		(net 629)
	)
	(segment
		(start 173.085001 85.210001)
		(end 172.809251 84.934251)
		(width 0.201)
		(layer "F.Cu")
		(net 629)
	)
	(segment
		(start 175.050191 85.389811)
		(end 175.050191 85.213741)
		(width 0.201)
		(layer "F.Cu")
		(net 630)
	)
	(segment
		(start 175.050191 85.213741)
		(end 174.770701 84.934251)
		(width 0.201)
		(layer "F.Cu")
		(net 630)
	)
	(segment
		(start 174.770701 84.934251)
		(end 174.330751 84.934251)
		(width 0.201)
		(layer "F.Cu")
		(net 630)
	)
	(segment
		(start 174.330751 84.934251)
		(end 174.055001 85.210001)
		(width 0.201)
		(layer "F.Cu")
		(net 630)
	)
	(via
		(at 191.5 129.5)
		(size 0.45)
		(drill 0.2)
		(layers "F.Cu" "B.Cu")
		(net 630)
	)
	(via
		(at 175.050191 85.389811)
		(size 0.45)
		(drill 0.2)
		(layers "F.Cu" "B.Cu")
		(net 630)
	)
	(segment
		(start 175.226261 85.389811)
		(end 175.319501 85.483051)
		(width 0.201)
		(layer "B.Cu")
		(net 630)
	)
	(segment
		(start 175.319501 85.483051)
		(end 175.319501 90.173051)
		(width 0.201)
		(layer "B.Cu")
		(net 630)
	)
	(segment
		(start 191.899399 129.430604)
		(end 191.8994 129.220821)
		(width 0.1)
		(layer "B.Cu")
		(net 630)
	)
	(segment
		(start 183.446376 129.100001)
		(end 183.346376 129.200001)
		(width 0.1)
		(layer "B.Cu")
		(net 630)
	)
	(segment
		(start 175.050191 85.389811)
		(end 175.226261 85.389811)
		(width 0.201)
		(layer "B.Cu")
		(net 630)
	)
	(segment
		(start 175.319501 90.173051)
		(end 179.219501 94.073051)
		(width 0.201)
		(layer "B.Cu")
		(net 630)
	)
	(segment
		(start 191.500001 129.500001)
		(end 191.830002 129.500001)
		(width 0.1)
		(layer "B.Cu")
		(net 630)
	)
	(segment
		(start 180.886451 129.200001)
		(end 183.346376 129.200001)
		(width 0.201)
		(layer "B.Cu")
		(net 630)
	)
	(segment
		(start 191.77858 129.100001)
		(end 183.446376 129.100001)
		(width 0.1)
		(layer "B.Cu")
		(net 630)
	)
	(segment
		(start 191.830002 129.500001)
		(end 191.899399 129.430604)
		(width 0.1)
		(layer "B.Cu")
		(net 630)
	)
	(segment
		(start 179.219501 94.073051)
		(end 179.219501 127.533051)
		(width 0.201)
		(layer "B.Cu")
		(net 630)
	)
	(segment
		(start 179.219501 127.533051)
		(end 180.886451 129.200001)
		(width 0.201)
		(layer "B.Cu")
		(net 630)
	)
	(segment
		(start 191.8994 129.220821)
		(end 191.77858 129.100001)
		(width 0.1)
		(layer "B.Cu")
		(net 630)
	)
	(segment
		(start 159.146804 120.102001)
		(end 158.825001 120.423804)
		(width 0.16)
		(layer "F.Cu")
		(net 634)
	)
	(segment
		(start 159.315002 120.102002)
		(end 159.460001 120.247001)
		(width 0.16)
		(layer "F.Cu")
		(net 634)
	)
	(segment
		(start 197.5 115.5)
		(end 197 115)
		(width 0.256)
		(layer "F.Cu")
		(net 634)
	)
	(segment
		(start 158.825001 120.423804)
		(end 158.825001 120.605001)
		(width 0.16)
		(layer "F.Cu")
		(net 634)
	)
	(segment
		(start 159.315002 120.102002)
		(end 159.146804 120.102001)
		(width 0.16)
		(layer "F.Cu")
		(net 634)
	)
	(via
		(at 177.100001 98.725001)
		(size 0.45)
		(drill 0.2)
		(layers "F.Cu" "B.Cu")
		(net 634)
	)
	(via
		(at 197 115)
		(size 0.45)
		(drill 0.2)
		(layers "F.Cu" "B.Cu")
		(net 634)
	)
	(via
		(at 159.460001 120.247001)
		(size 0.45)
		(drill 0.2)
		(layers "F.Cu" "B.Cu")
		(net 634)
	)
	(segment
		(start 178.253501 108.233501)
		(end 178.253501 106.466501)
		(width 0.114)
		(layer "In3.Cu")
		(net 634)
	)
	(segment
		(start 177.100001 98.962589)
		(end 177.100001 98.725001)
		(width 0.114)
		(layer "In3.Cu")
		(net 634)
	)
	(segment
		(start 175.691367 112.531565)
		(end 175.691369 112.531564)
		(width 0.114)
		(layer "In3.Cu")
		(net 634)
	)
	(segment
		(start 174.993454 113.521515)
		(end 176.078487 114.606549)
		(width 0.114)
		(layer "In3.Cu")
		(net 634)
	)
	(segment
		(start 178.253501 100.866501)
		(end 178.253501 100.116089)
		(width 0.114)
		(layer "In3.Cu")
		(net 634)
	)
	(segment
		(start 159.460001 120.247001)
		(end 159.593501 120.113501)
		(width 0.114)
		(layer "In3.Cu")
		(net 634)
	)
	(segment
		(start 177.316501 104.860001)
		(end 178.903501 104.860001)
		(width 0.114)
		(layer "In3.Cu")
		(net 634)
	)
	(segment
		(start 178.903501 108.440001)
		(end 178.460001 108.440001)
		(width 0.114)
		(layer "In3.Cu")
		(net 634)
	)
	(segment
		(start 174.793506 115.30147)
		(end 174.793505 115.30147)
		(width 0.114)
		(layer "In3.Cu")
		(net 634)
	)
	(segment
		(start 178.253501 111.549441)
		(end 178.253501 111.033501)
		(width 0.114)
		(layer "In3.Cu")
		(net 634)
	)
	(segment
		(start 178.903501 101.073001)
		(end 178.460001 101.073001)
		(width 0.114)
		(layer "In3.Cu")
		(net 634)
	)
	(segment
		(start 175.243931 114.356067)
		(end 175.243935 114.356068)
		(width 0.114)
		(layer "In3.Cu")
		(net 634)
	)
	(segment
		(start 176.776402 114.60655)
		(end 176.776402 114.606549)
		(width 0.114)
		(layer "In3.Cu")
		(net 634)
	)
	(segment
		(start 177.316501 102.060001)
		(end 178.903501 102.060001)
		(width 0.114)
		(layer "In3.Cu")
		(net 634)
	)
	(segment
		(start 177.316501 109.427001)
		(end 178.903501 109.427001)
		(width 0.114)
		(layer "In3.Cu")
		(net 634)
	)
	(segment
		(start 160.320561 120.663501)
		(end 161.439441 120.663501)
		(width 0.114)
		(layer "In3.Cu")
		(net 634)
	)
	(segment
		(start 175.243935 114.356068)
		(end 174.701417 113.813551)
		(width 0.114)
		(layer "In3.Cu")
		(net 634)
	)
	(segment
		(start 177.316501 103.873001)
		(end 178.903501 103.873001)
		(width 0.114)
		(layer "In3.Cu")
		(net 634)
	)
	(segment
		(start 176.97635 112.826595)
		(end 177.601982 112.20096)
		(width 0.114)
		(layer "In3.Cu")
		(net 634)
	)
	(segment
		(start 163.259441 118.843501)
		(end 170.959441 118.843501)
		(width 0.114)
		(layer "In3.Cu")
		(net 634)
	)
	(segment
		(start 177.316501 109.840001)
		(end 178.903501 109.840001)
		(width 0.114)
		(layer "In3.Cu")
		(net 634)
	)
	(segment
		(start 175.786449 114.898584)
		(end 175.786449 114.898585)
		(width 0.114)
		(layer "In3.Cu")
		(net 634)
	)
	(segment
		(start 176.776402 113.908633)
		(end 176.776402 113.908634)
		(width 0.114)
		(layer "In3.Cu")
		(net 634)
	)
	(segment
		(start 177.316501 103.460001)
		(end 178.903501 103.460001)
		(width 0.114)
		(layer "In3.Cu")
		(net 634)
	)
	(segment
		(start 177.601982 112.20096)
		(end 178.253501 111.549441)
		(width 0.114)
		(layer "In3.Cu")
		(net 634)
	)
	(segment
		(start 178.460001 106.260001)
		(end 178.903501 106.260001)
		(width 0.114)
		(layer "In3.Cu")
		(net 634)
	)
	(segment
		(start 177.316501 105.273001)
		(end 178.903501 105.273001)
		(width 0.114)
		(layer "In3.Cu")
		(net 634)
	)
	(segment
		(start 174.793505 115.30147)
		(end 175.088535 115.5965)
		(width 0.114)
		(layer "In3.Cu")
		(net 634)
	)
	(segment
		(start 177.316501 102.473001)
		(end 178.903501 102.473001)
		(width 0.114)
		(layer "In3.Cu")
		(net 634)
	)
	(segment
		(start 176.776402 113.908634)
		(end 175.691368 112.8236)
		(width 0.114)
		(layer "In3.Cu")
		(net 634)
	)
	(segment
		(start 161.439441 120.663501)
		(end 163.259441 118.843501)
		(width 0.114)
		(layer "In3.Cu")
		(net 634)
	)
	(segment
		(start 178.253501 100.116089)
		(end 177.100001 98.962589)
		(width 0.114)
		(layer "In3.Cu")
		(net 634)
	)
	(segment
		(start 159.593501 120.113501)
		(end 159.770561 120.113501)
		(width 0.114)
		(layer "In3.Cu")
		(net 634)
	)
	(segment
		(start 178.460001 110.827001)
		(end 178.903501 110.827001)
		(width 0.114)
		(layer "In3.Cu")
		(net 634)
	)
	(segment
		(start 175.786449 114.898585)
		(end 175.243931 114.356067)
		(width 0.114)
		(layer "In3.Cu")
		(net 634)
	)
	(segment
		(start 175.983405 112.531564)
		(end 176.278436 112.826595)
		(width 0.114)
		(layer "In3.Cu")
		(net 634)
	)
	(segment
		(start 159.770561 120.113501)
		(end 160.320561 120.663501)
		(width 0.114)
		(layer "In3.Cu")
		(net 634)
	)
	(segment
		(start 170.959441 118.843501)
		(end 174.50147 115.30147)
		(width 0.114)
		(layer "In3.Cu")
		(net 634)
	)
	(segment
		(start 174.701416 113.521516)
		(end 174.701418 113.521515)
		(width 0.114)
		(layer "In3.Cu")
		(net 634)
	)
	(arc
		(start 178.903501 104.860001)
		(mid 179.252458 104.715458)
		(end 179.397001 104.366501)
		(width 0.114)
		(layer "In3.Cu")
		(net 634)
	)
	(arc
		(start 178.253501 106.466501)
		(mid 178.313983 106.320483)
		(end 178.460001 106.260001)
		(width 0.114)
		(layer "In3.Cu")
		(net 634)
	)
	(arc
		(start 174.701417 113.813551)
		(mid 174.640934 113.667534)
		(end 174.701416 113.521516)
		(width 0.114)
		(layer "In3.Cu")
		(net 634)
	)
	(arc
		(start 176.278436 112.826595)
		(mid 176.627393 112.971138)
		(end 176.97635 112.826595)
		(width 0.114)
		(layer "In3.Cu")
		(net 634)
	)
	(arc
		(start 176.078487 114.606549)
		(mid 176.427444 114.751092)
		(end 176.776402 114.60655)
		(width 0.114)
		(layer "In3.Cu")
		(net 634)
	)
	(arc
		(start 179.397001 105.766501)
		(mid 179.252458 105.417544)
		(end 178.903501 105.273001)
		(width 0.114)
		(layer "In3.Cu")
		(net 634)
	)
	(arc
		(start 177.110001 102.266501)
		(mid 177.170483 102.120483)
		(end 177.316501 102.060001)
		(width 0.114)
		(layer "In3.Cu")
		(net 634)
	)
	(arc
		(start 179.397001 102.966501)
		(mid 179.252458 102.617544)
		(end 178.903501 102.473001)
		(width 0.114)
		(layer "In3.Cu")
		(net 634)
	)
	(arc
		(start 178.903501 110.827001)
		(mid 179.252458 110.682458)
		(end 179.397001 110.333501)
		(width 0.114)
		(layer "In3.Cu")
		(net 634)
	)
	(arc
		(start 179.397001 104.366501)
		(mid 179.252458 104.017544)
		(end 178.903501 103.873001)
		(width 0.114)
		(layer "In3.Cu")
		(net 634)
	)
	(arc
		(start 178.460001 108.440001)
		(mid 178.313983 108.379519)
		(end 178.253501 108.233501)
		(width 0.114)
		(layer "In3.Cu")
		(net 634)
	)
	(arc
		(start 178.253501 111.033501)
		(mid 178.313983 110.887483)
		(end 178.460001 110.827001)
		(width 0.114)
		(layer "In3.Cu")
		(net 634)
	)
	(arc
		(start 175.088535 115.5965)
		(mid 175.437492 115.741043)
		(end 175.786449 115.5965)
		(width 0.114)
		(layer "In3.Cu")
		(net 634)
	)
	(arc
		(start 178.903501 109.427001)
		(mid 179.252458 109.282458)
		(end 179.397001 108.933501)
		(width 0.114)
		(layer "In3.Cu")
		(net 634)
	)
	(arc
		(start 175.691368 112.8236)
		(mid 175.630885 112.677583)
		(end 175.691367 112.531565)
		(width 0.114)
		(layer "In3.Cu")
		(net 634)
	)
	(arc
		(start 177.110001 105.066501)
		(mid 177.170483 104.920483)
		(end 177.316501 104.860001)
		(width 0.114)
		(layer "In3.Cu")
		(net 634)
	)
	(arc
		(start 177.110001 103.666501)
		(mid 177.170483 103.520483)
		(end 177.316501 103.460001)
		(width 0.114)
		(layer "In3.Cu")
		(net 634)
	)
	(arc
		(start 177.110001 109.633501)
		(mid 177.170483 109.487483)
		(end 177.316501 109.427001)
		(width 0.114)
		(layer "In3.Cu")
		(net 634)
	)
	(arc
		(start 177.316501 105.273001)
		(mid 177.170483 105.212519)
		(end 177.110001 105.066501)
		(width 0.114)
		(layer "In3.Cu")
		(net 634)
	)
	(arc
		(start 177.316501 102.473001)
		(mid 177.170483 102.412519)
		(end 177.110001 102.266501)
		(width 0.114)
		(layer "In3.Cu")
		(net 634)
	)
	(arc
		(start 178.460001 101.073001)
		(mid 178.313983 101.012519)
		(end 178.253501 100.866501)
		(width 0.114)
		(layer "In3.Cu")
		(net 634)
	)
	(arc
		(start 178.903501 103.460001)
		(mid 179.252458 103.315458)
		(end 179.397001 102.966501)
		(width 0.114)
		(layer "In3.Cu")
		(net 634)
	)
	(arc
		(start 176.776402 114.606549)
		(mid 176.920945 114.257591)
		(end 176.776402 113.908633)
		(width 0.114)
		(layer "In3.Cu")
		(net 634)
	)
	(arc
		(start 175.786449 115.5965)
		(mid 175.930992 115.247542)
		(end 175.786449 114.898584)
		(width 0.114)
		(layer "In3.Cu")
		(net 634)
	)
	(arc
		(start 179.397001 101.566501)
		(mid 179.252458 101.217544)
		(end 178.903501 101.073001)
		(width 0.114)
		(layer "In3.Cu")
		(net 634)
	)
	(arc
		(start 178.903501 106.260001)
		(mid 179.252458 106.115458)
		(end 179.397001 105.766501)
		(width 0.114)
		(layer "In3.Cu")
		(net 634)
	)
	(arc
		(start 178.903501 102.060001)
		(mid 179.252458 101.915458)
		(end 179.397001 101.566501)
		(width 0.114)
		(layer "In3.Cu")
		(net 634)
	)
	(arc
		(start 177.316501 103.873001)
		(mid 177.170483 103.812519)
		(end 177.110001 103.666501)
		(width 0.114)
		(layer "In3.Cu")
		(net 634)
	)
	(arc
		(start 177.316501 109.840001)
		(mid 177.170483 109.779519)
		(end 177.110001 109.633501)
		(width 0.114)
		(layer "In3.Cu")
		(net 634)
	)
	(arc
		(start 174.701418 113.521515)
		(mid 174.847435 113.461033)
		(end 174.993454 113.521515)
		(width 0.114)
		(layer "In3.Cu")
		(net 634)
	)
	(arc
		(start 174.50147 115.30147)
		(mid 174.647488 115.240987)
		(end 174.793506 115.30147)
		(width 0.114)
		(layer "In3.Cu")
		(net 634)
	)
	(arc
		(start 175.691369 112.531564)
		(mid 175.837386 112.471082)
		(end 175.983405 112.531564)
		(width 0.114)
		(layer "In3.Cu")
		(net 634)
	)
	(arc
		(start 179.397001 110.333501)
		(mid 179.252458 109.984544)
		(end 178.903501 109.840001)
		(width 0.114)
		(layer "In3.Cu")
		(net 634)
	)
	(arc
		(start 179.397001 108.933501)
		(mid 179.252458 108.584544)
		(end 178.903501 108.440001)
		(width 0.114)
		(layer "In3.Cu")
		(net 634)
	)
	(segment
		(start 196.600001 115.400001)
		(end 194.791423 115.400001)
		(width 0.1)
		(layer "In5.Cu")
		(net 634)
	)
	(segment
		(start 194.791423 115.400001)
		(end 194.600001 115.208579)
		(width 0.1)
		(layer "In5.Cu")
		(net 634)
	)
	(segment
		(start 181.734441 99.456501)
		(end 177.593913 99.456501)
		(width 0.114)
		(layer "In5.Cu")
		(net 634)
	)
	(segment
		(start 197.000001 115.000001)
		(end 196.600001 115.400001)
		(width 0.1)
		(layer "In5.Cu")
		(net 634)
	)
	(segment
		(start 194.643501 113.405001)
		(end 194.643501 112.365561)
		(width 0.114)
		(layer "In5.Cu")
		(net 634)
	)
	(segment
		(start 194.600001 115.208579)
		(end 194.600001 113.448501)
		(width 0.1)
		(layer "In5.Cu")
		(net 634)
	)
	(segment
		(start 194.643501 112.365561)
		(end 181.734441 99.456501)
		(width 0.114)
		(layer "In5.Cu")
		(net 634)
	)
	(segment
		(start 177.593913 99.456501)
		(end 177.100001 98.962589)
		(width 0.114)
		(layer "In5.Cu")
		(net 634)
	)
	(segment
		(start 177.100001 98.962589)
		(end 177.100001 98.725001)
		(width 0.114)
		(layer "In5.Cu")
		(net 634)
	)
	(segment
		(start 194.600001 113.448501)
		(end 194.643501 113.405001)
		(width 0.1)
		(layer "In5.Cu")
		(net 634)
	)
	(segment
		(start 254.3 97.55)
		(end 254.3 96.115)
		(width 0.182)
		(layer "F.Cu")
		(net 637)
	)
	(segment
		(start 254.3 96.115)
		(end 254.415 96)
		(width 0.182)
		(layer "F.Cu")
		(net 637)
	)
	(segment
		(start 235.030665 147.912823)
		(end 234.743488 148.2)
		(width 0.182)
		(layer "F.Cu")
		(net 639)
	)
	(segment
		(start 234.743488 148.2)
		(end 234.5 148.2)
		(width 0.182)
		(layer "F.Cu")
		(net 639)
	)
	(segment
		(start 235.030665 147.4)
		(end 235.030665 147.912823)
		(width 0.182)
		(layer "F.Cu")
		(net 639)
	)
	(segment
		(start 201.5 142.5)
		(end 202 143)
		(width 0.256)
		(layer "F.Cu")
		(net 639)
	)
	(via
		(at 235.030665 147.4)
		(size 0.45)
		(drill 0.2)
		(layers "F.Cu" "B.Cu")
		(net 639)
	)
	(via
		(at 202 143)
		(size 0.45)
		(drill 0.2)
		(layers "F.Cu" "B.Cu")
		(net 639)
	)
	(segment
		(start 235.5 146.930665)
		(end 235.5 145.5)
		(width 0.1)
		(layer "In7.Cu")
		(net 639)
	)
	(segment
		(start 235.5 145.5)
		(end 233.4 143.4)
		(width 0.1)
		(layer "In7.Cu")
		(net 639)
	)
	(segment
		(start 233.4 143.4)
		(end 202.4 143.4)
		(width 0.1)
		(layer "In7.Cu")
		(net 639)
	)
	(segment
		(start 235.030665 147.4)
		(end 235.5 146.930665)
		(width 0.1)
		(layer "In7.Cu")
		(net 639)
	)
	(segment
		(start 202.4 143.4)
		(end 202 143)
		(width 0.1)
		(layer "In7.Cu")
		(net 639)
	)
	(segment
		(start 189.43 152.885001)
		(end 188.985001 152.885001)
		(width 0.4)
		(layer "F.Cu")
		(net 640)
	)
	(segment
		(start 193.5 138.5)
		(end 193 139)
		(width 0.256)
		(layer "F.Cu")
		(net 640)
	)
	(segment
		(start 189.85 153.825)
		(end 191.125 153.825)
		(width 0.1)
		(layer "F.Cu")
		(net 640)
	)
	(segment
		(start 189.43 153.405)
		(end 189.85 153.825)
		(width 0.1)
		(layer "F.Cu")
		(net 640)
	)
	(segment
		(start 188.715001 152.615001)
		(end 188.715001 151.685)
		(width 0.4)
		(layer "F.Cu")
		(net 640)
	)
	(segment
		(start 189.43 152.885001)
		(end 189.43 153.405)
		(width 0.1)
		(layer "F.Cu")
		(net 640)
	)
	(segment
		(start 188.985001 152.885001)
		(end 188.715001 152.615001)
		(width 0.4)
		(layer "F.Cu")
		(net 640)
	)
	(via
		(at 191.125 153.825)
		(size 0.45)
		(drill 0.2)
		(layers "F.Cu" "B.Cu")
		(net 640)
	)
	(via
		(at 193 139)
		(size 0.45)
		(drill 0.2)
		(layers "F.Cu" "B.Cu")
		(net 640)
	)
	(segment
		(start 166.35 153.825)
		(end 157.275 144.75)
		(width 0.1)
		(layer "In7.Cu")
		(net 640)
	)
	(segment
		(start 186.025 133.975)
		(end 188.1 136.05)
		(width 0.1)
		(layer "In7.Cu")
		(net 640)
	)
	(segment
		(start 157.275 144.75)
		(end 157.275 140.575)
		(width 0.1)
		(layer "In7.Cu")
		(net 640)
	)
	(segment
		(start 155.1 138.4)
		(end 155.1 135.825)
		(width 0.1)
		(layer "In7.Cu")
		(net 640)
	)
	(segment
		(start 188.1 136.05)
		(end 191.025 136.05)
		(width 0.1)
		(layer "In7.Cu")
		(net 640)
	)
	(segment
		(start 168.125 133.975)
		(end 186.025 133.975)
		(width 0.1)
		(layer "In7.Cu")
		(net 640)
	)
	(segment
		(start 193.475 138.525)
		(end 193 139)
		(width 0.1)
		(layer "In7.Cu")
		(net 640)
	)
	(segment
		(start 193.2 136.55)
		(end 193.475 136.825)
		(width 0.1)
		(layer "In7.Cu")
		(net 640)
	)
	(segment
		(start 191.525 136.55)
		(end 193.2 136.55)
		(width 0.1)
		(layer "In7.Cu")
		(net 640)
	)
	(segment
		(start 191.025 136.05)
		(end 191.525 136.55)
		(width 0.1)
		(layer "In7.Cu")
		(net 640)
	)
	(segment
		(start 157.275 140.575)
		(end 155.1 138.4)
		(width 0.1)
		(layer "In7.Cu")
		(net 640)
	)
	(segment
		(start 161.1 133.75)
		(end 161.75 134.4)
		(width 0.1)
		(layer "In7.Cu")
		(net 640)
	)
	(segment
		(start 155.1 135.825)
		(end 157.175 133.75)
		(width 0.1)
		(layer "In7.Cu")
		(net 640)
	)
	(segment
		(start 193.475 136.825)
		(end 193.475 138.525)
		(width 0.1)
		(layer "In7.Cu")
		(net 640)
	)
	(segment
		(start 161.75 134.4)
		(end 167.7 134.4)
		(width 0.1)
		(layer "In7.Cu")
		(net 640)
	)
	(segment
		(start 191.125 153.825)
		(end 166.35 153.825)
		(width 0.1)
		(layer "In7.Cu")
		(net 640)
	)
	(segment
		(start 157.175 133.75)
		(end 161.1 133.75)
		(width 0.1)
		(layer "In7.Cu")
		(net 640)
	)
	(segment
		(start 167.7 134.4)
		(end 168.125 133.975)
		(width 0.1)
		(layer "In7.Cu")
		(net 640)
	)
	(segment
		(start 157.876804 88.352001)
		(end 157.555001 88.673804)
		(width 0.16)
		(layer "F.Cu")
		(net 641)
	)
	(segment
		(start 157.555001 88.673804)
		(end 157.555001 88.855001)
		(width 0.16)
		(layer "F.Cu")
		(net 641)
	)
	(segment
		(start 196.5 116.5)
		(end 196 116)
		(width 0.256)
		(layer "F.Cu")
		(net 641)
	)
	(segment
		(start 158.045002 88.352002)
		(end 158.190001 88.497001)
		(width 0.16)
		(layer "F.Cu")
		(net 641)
	)
	(segment
		(start 158.045002 88.352002)
		(end 157.876804 88.352001)
		(width 0.16)
		(layer "F.Cu")
		(net 641)
	)
	(via
		(at 158.190001 88.497001)
		(size 0.45)
		(drill 0.2)
		(layers "F.Cu" "B.Cu")
		(net 641)
	)
	(via
		(at 177.100001 100.250001)
		(size 0.45)
		(drill 0.2)
		(layers "F.Cu" "B.Cu")
		(net 641)
	)
	(via
		(at 196 116)
		(size 0.45)
		(drill 0.2)
		(layers "F.Cu" "B.Cu")
		(net 641)
	)
	(segment
		(start 158.190001 88.497001)
		(end 158.056501 88.363501)
		(width 0.114)
		(layer "In3.Cu")
		(net 641)
	)
	(segment
		(start 158.089441 89.986501)
		(end 158.461501 89.986501)
		(width 0.114)
		(layer "In3.Cu")
		(net 641)
	)
	(segment
		(start 158.056501 88.363501)
		(end 157.839441 88.363501)
		(width 0.114)
		(layer "In3.Cu")
		(net 641)
	)
	(segment
		(start 157.839441 88.363501)
		(end 157.682497 88.520445)
		(width 0.114)
		(layer "In3.Cu")
		(net 641)
	)
	(segment
		(start 159.361501 89.475033)
		(end 159.361501 89.686501)
		(width 0.114)
		(layer "In3.Cu")
		(net 641)
	)
	(segment
		(start 171.539441 89.986501)
		(end 174.668501 93.115561)
		(width 0.114)
		(layer "In3.Cu")
		(net 641)
	)
	(segment
		(start 174.668501 98.056089)
		(end 176.862413 100.250001)
		(width 0.114)
		(layer "In3.Cu")
		(net 641)
	)
	(segment
		(start 157.682497 88.520445)
		(end 157.682497 89.579557)
		(width 0.114)
		(layer "In3.Cu")
		(net 641)
	)
	(segment
		(start 176.862413 100.250001)
		(end 177.100001 100.250001)
		(width 0.114)
		(layer "In3.Cu")
		(net 641)
	)
	(segment
		(start 158.761501 89.686501)
		(end 158.761501 89.475033)
		(width 0.114)
		(layer "In3.Cu")
		(net 641)
	)
	(segment
		(start 157.682497 89.579557)
		(end 158.089441 89.986501)
		(width 0.114)
		(layer "In3.Cu")
		(net 641)
	)
	(segment
		(start 159.661501 89.986501)
		(end 159.711501 89.986501)
		(width 0.114)
		(layer "In3.Cu")
		(net 641)
	)
	(segment
		(start 174.668501 93.115561)
		(end 174.668501 98.056089)
		(width 0.114)
		(layer "In3.Cu")
		(net 641)
	)
	(segment
		(start 159.711501 89.986501)
		(end 171.539441 89.986501)
		(width 0.114)
		(layer "In3.Cu")
		(net 641)
	)
	(arc
		(start 158.461501 89.986501)
		(mid 158.673633 89.898633)
		(end 158.761501 89.686501)
		(width 0.114)
		(layer "In3.Cu")
		(net 641)
	)
	(arc
		(start 158.761501 89.475033)
		(mid 158.849369 89.262901)
		(end 159.061501 89.175033)
		(width 0.114)
		(layer "In3.Cu")
		(net 641)
	)
	(arc
		(start 159.061501 89.175033)
		(mid 159.273633 89.262901)
		(end 159.361501 89.475033)
		(width 0.114)
		(layer "In3.Cu")
		(net 641)
	)
	(arc
		(start 159.361501 89.686501)
		(mid 159.449369 89.898633)
		(end 159.661501 89.986501)
		(width 0.114)
		(layer "In3.Cu")
		(net 641)
	)
	(segment
		(start 184.183198 104.466546)
		(end 184.183199 104.466546)
		(width 0.114)
		(layer "In5.Cu")
		(net 641)
	)
	(segment
		(start 193.500001 116.158579)
		(end 193.500001 113.448501)
		(width 0.1)
		(layer "In5.Cu")
		(net 641)
	)
	(segment
		(start 184.475234 104.466545)
		(end 184.475234 104.466546)
		(width 0.114)
		(layer "In5.Cu")
		(net 641)
	)
	(segment
		(start 195.600001 116.400001)
		(end 193.741423 116.400001)
		(width 0.1)
		(layer "In5.Cu")
		(net 641)
	)
	(segment
		(start 182.2033 102.486648)
		(end 182.203301 102.486648)
		(width 0.114)
		(layer "In5.Cu")
		(net 641)
	)
	(segment
		(start 184.381367 103.278428)
		(end 184.381368 103.278428)
		(width 0.114)
		(layer "In5.Cu")
		(net 641)
	)
	(segment
		(start 183.193249 103.476597)
		(end 183.19325 103.476597)
		(width 0.114)
		(layer "In5.Cu")
		(net 641)
	)
	(segment
		(start 183.391419 102.986394)
		(end 183.19325 103.184562)
		(width 0.114)
		(layer "In5.Cu")
		(net 641)
	)
	(segment
		(start 182.495336 102.486647)
		(end 182.495336 102.486648)
		(width 0.114)
		(layer "In5.Cu")
		(net 641)
	)
	(segment
		(start 184.475234 104.466546)
		(end 184.673402 104.268377)
		(width 0.114)
		(layer "In5.Cu")
		(net 641)
	)
	(segment
		(start 183.391418 102.288479)
		(end 183.391419 102.288479)
		(width 0.114)
		(layer "In5.Cu")
		(net 641)
	)
	(segment
		(start 177.343913 100.731501)
		(end 181.834441 100.731501)
		(width 0.114)
		(layer "In5.Cu")
		(net 641)
	)
	(segment
		(start 177.100001 100.250001)
		(end 177.100001 100.487589)
		(width 0.114)
		(layer "In5.Cu")
		(net 641)
	)
	(segment
		(start 185.371317 104.268377)
		(end 193.543501 112.440561)
		(width 0.114)
		(layer "In5.Cu")
		(net 641)
	)
	(segment
		(start 185.371316 104.268377)
		(end 185.371317 104.268377)
		(width 0.114)
		(layer "In5.Cu")
		(net 641)
	)
	(segment
		(start 183.485285 103.476596)
		(end 183.485285 103.476597)
		(width 0.114)
		(layer "In5.Cu")
		(net 641)
	)
	(segment
		(start 193.741423 116.400001)
		(end 193.500001 116.158579)
		(width 0.1)
		(layer "In5.Cu")
		(net 641)
	)
	(segment
		(start 177.100001 100.487589)
		(end 177.343913 100.731501)
		(width 0.114)
		(layer "In5.Cu")
		(net 641)
	)
	(segment
		(start 184.381368 103.976343)
		(end 184.183199 104.174511)
		(width 0.114)
		(layer "In5.Cu")
		(net 641)
	)
	(segment
		(start 183.485285 103.476597)
		(end 183.683453 103.278428)
		(width 0.114)
		(layer "In5.Cu")
		(net 641)
	)
	(segment
		(start 196.000001 116.000001)
		(end 195.600001 116.400001)
		(width 0.1)
		(layer "In5.Cu")
		(net 641)
	)
	(segment
		(start 182.495336 102.486648)
		(end 182.693504 102.288479)
		(width 0.114)
		(layer "In5.Cu")
		(net 641)
	)
	(segment
		(start 193.500001 113.448501)
		(end 193.543501 113.405001)
		(width 0.1)
		(layer "In5.Cu")
		(net 641)
	)
	(segment
		(start 181.834441 100.731501)
		(end 182.40147 101.298531)
		(width 0.114)
		(layer "In5.Cu")
		(net 641)
	)
	(segment
		(start 193.543501 112.440561)
		(end 193.543501 113.405001)
		(width 0.114)
		(layer "In5.Cu")
		(net 641)
	)
	(segment
		(start 182.40147 101.996445)
		(end 182.203301 102.194613)
		(width 0.114)
		(layer "In5.Cu")
		(net 641)
	)
	(arc
		(start 182.40147 101.298531)
		(mid 182.546013 101.647488)
		(end 182.40147 101.996445)
		(width 0.114)
		(layer "In5.Cu")
		(net 641)
	)
	(arc
		(start 183.683453 103.278428)
		(mid 184.03241 103.133885)
		(end 184.381367 103.278428)
		(width 0.114)
		(layer "In5.Cu")
		(net 641)
	)
	(arc
		(start 183.391419 102.28848)
		(mid 183.535962 102.637437)
		(end 183.391419 102.986394)
		(width 0.114)
		(layer "In5.Cu")
		(net 641)
	)
	(arc
		(start 182.693504 102.288479)
		(mid 183.042461 102.143936)
		(end 183.391418 102.288479)
		(width 0.114)
		(layer "In5.Cu")
		(net 641)
	)
	(arc
		(start 183.19325 103.184562)
		(mid 183.132767 103.330579)
		(end 183.193249 103.476597)
		(width 0.114)
		(layer "In5.Cu")
		(net 641)
	)
	(arc
		(start 184.183199 104.174511)
		(mid 184.122716 104.320528)
		(end 184.183198 104.466546)
		(width 0.114)
		(layer "In5.Cu")
		(net 641)
	)
	(arc
		(start 184.381368 103.278429)
		(mid 184.525911 103.627386)
		(end 184.381368 103.976343)
		(width 0.114)
		(layer "In5.Cu")
		(net 641)
	)
	(arc
		(start 183.19325 103.476597)
		(mid 183.339268 103.537079)
		(end 183.485285 103.476596)
		(width 0.114)
		(layer "In5.Cu")
		(net 641)
	)
	(arc
		(start 182.203301 102.194613)
		(mid 182.142818 102.34063)
		(end 182.2033 102.486648)
		(width 0.114)
		(layer "In5.Cu")
		(net 641)
	)
	(arc
		(start 184.183199 104.466546)
		(mid 184.329217 104.527028)
		(end 184.475234 104.466545)
		(width 0.114)
		(layer "In5.Cu")
		(net 641)
	)
	(arc
		(start 184.673402 104.268377)
		(mid 185.022359 104.123834)
		(end 185.371316 104.268377)
		(width 0.114)
		(layer "In5.Cu")
		(net 641)
	)
	(arc
		(start 182.203301 102.486648)
		(mid 182.349319 102.54713)
		(end 182.495336 102.486647)
		(width 0.114)
		(layer "In5.Cu")
		(net 641)
	)
	(segment
		(start 197.5 116.5)
		(end 197 116)
		(width 0.256)
		(layer "F.Cu")
		(net 642)
	)
	(segment
		(start 158.825001 119.516198)
		(end 159.146804 119.838001)
		(width 0.16)
		(layer "F.Cu")
		(net 642)
	)
	(segment
		(start 159.315002 119.838)
		(end 159.460001 119.693001)
		(width 0.16)
		(layer "F.Cu")
		(net 642)
	)
	(segment
		(start 158.825001 119.335001)
		(end 158.825001 119.516198)
		(width 0.16)
		(layer "F.Cu")
		(net 642)
	)
	(segment
		(start 159.315002 119.838)
		(end 159.146804 119.838001)
		(width 0.16)
		(layer "F.Cu")
		(net 642)
	)
	(via
		(at 159.460001 119.693001)
		(size 0.45)
		(drill 0.2)
		(layers "F.Cu" "B.Cu")
		(net 642)
	)
	(via
		(at 197 116)
		(size 0.45)
		(drill 0.2)
		(layers "F.Cu" "B.Cu")
		(net 642)
	)
	(via
		(at 176.659473 99.165529)
		(size 0.45)
		(drill 0.2)
		(layers "F.Cu" "B.Cu")
		(net 642)
	)
	(segment
		(start 175.196394 113.318575)
		(end 175.196392 113.318576)
		(width 0.114)
		(layer "In3.Cu")
		(net 642)
	)
	(segment
		(start 176.773409 112.623655)
		(end 176.77341 112.623655)
		(width 0.114)
		(layer "In3.Cu")
		(net 642)
	)
	(segment
		(start 177.316501 105.560001)
		(end 178.903501 105.560001)
		(width 0.114)
		(layer "In3.Cu")
		(net 642)
	)
	(segment
		(start 176.897061 99.165529)
		(end 176.659473 99.165529)
		(width 0.114)
		(layer "In3.Cu")
		(net 642)
	)
	(segment
		(start 161.452066 119.23325)
		(end 161.452068 119.233249)
		(width 0.114)
		(layer "In3.Cu")
		(net 642)
	)
	(segment
		(start 174.996445 115.098531)
		(end 175.291475 115.393561)
		(width 0.114)
		(layer "In3.Cu")
		(net 642)
	)
	(segment
		(start 174.498477 114.016491)
		(end 175.58351 115.101525)
		(width 0.114)
		(layer "In3.Cu")
		(net 642)
	)
	(segment
		(start 159.889441 119.826501)
		(end 160.439441 120.376501)
		(width 0.114)
		(layer "In3.Cu")
		(net 642)
	)
	(segment
		(start 177.316501 109.140001)
		(end 178.903501 109.140001)
		(width 0.114)
		(layer "In3.Cu")
		(net 642)
	)
	(segment
		(start 175.488428 113.02654)
		(end 176.573462 114.111573)
		(width 0.114)
		(layer "In3.Cu")
		(net 642)
	)
	(segment
		(start 161.320561 120.376501)
		(end 161.569031 120.128031)
		(width 0.114)
		(layer "In3.Cu")
		(net 642)
	)
	(segment
		(start 177.966501 111.430561)
		(end 177.966501 111.033501)
		(width 0.114)
		(layer "In3.Cu")
		(net 642)
	)
	(segment
		(start 175.196392 113.318576)
		(end 176.281427 114.403609)
		(width 0.114)
		(layer "In3.Cu")
		(net 642)
	)
	(segment
		(start 177.966501 100.234969)
		(end 176.897061 99.165529)
		(width 0.114)
		(layer "In3.Cu")
		(net 642)
	)
	(segment
		(start 175.488427 112.328625)
		(end 175.488429 112.328624)
		(width 0.114)
		(layer "In3.Cu")
		(net 642)
	)
	(segment
		(start 176.573462 114.40361)
		(end 176.573462 114.403609)
		(width 0.114)
		(layer "In3.Cu")
		(net 642)
	)
	(segment
		(start 177.316501 110.127001)
		(end 178.903501 110.127001)
		(width 0.114)
		(layer "In3.Cu")
		(net 642)
	)
	(segment
		(start 160.439441 120.376501)
		(end 161.320561 120.376501)
		(width 0.114)
		(layer "In3.Cu")
		(net 642)
	)
	(segment
		(start 161.840978 119.233249)
		(end 161.840976 119.23325)
		(width 0.114)
		(layer "In3.Cu")
		(net 642)
	)
	(segment
		(start 177.316501 102.760001)
		(end 178.903501 102.760001)
		(width 0.114)
		(layer "In3.Cu")
		(net 642)
	)
	(segment
		(start 177.316501 101.773001)
		(end 178.903501 101.773001)
		(width 0.114)
		(layer "In3.Cu")
		(net 642)
	)
	(segment
		(start 177.966501 108.233501)
		(end 177.966501 106.466501)
		(width 0.114)
		(layer "In3.Cu")
		(net 642)
	)
	(segment
		(start 178.460001 110.540001)
		(end 178.903501 110.540001)
		(width 0.114)
		(layer "In3.Cu")
		(net 642)
	)
	(segment
		(start 177.966501 100.866501)
		(end 177.966501 100.234969)
		(width 0.114)
		(layer "In3.Cu")
		(net 642)
	)
	(segment
		(start 174.498476 113.318576)
		(end 174.498478 113.318575)
		(width 0.114)
		(layer "In3.Cu")
		(net 642)
	)
	(segment
		(start 177.316501 103.173001)
		(end 178.903501 103.173001)
		(width 0.114)
		(layer "In3.Cu")
		(net 642)
	)
	(segment
		(start 178.460001 105.973001)
		(end 178.903501 105.973001)
		(width 0.114)
		(layer "In3.Cu")
		(net 642)
	)
	(segment
		(start 159.593501 119.826501)
		(end 159.889441 119.826501)
		(width 0.114)
		(layer "In3.Cu")
		(net 642)
	)
	(segment
		(start 161.840976 119.23325)
		(end 161.957941 119.350215)
		(width 0.114)
		(layer "In3.Cu")
		(net 642)
	)
	(segment
		(start 177.316501 104.160001)
		(end 178.903501 104.160001)
		(width 0.114)
		(layer "In3.Cu")
		(net 642)
	)
	(segment
		(start 175.58351 115.39356)
		(end 175.58351 115.393561)
		(width 0.114)
		(layer "In3.Cu")
		(net 642)
	)
	(segment
		(start 177.316501 104.573001)
		(end 178.903501 104.573001)
		(width 0.114)
		(layer "In3.Cu")
		(net 642)
	)
	(segment
		(start 163.140561 118.556501)
		(end 170.840561 118.556501)
		(width 0.114)
		(layer "In3.Cu")
		(net 642)
	)
	(segment
		(start 159.460001 119.693001)
		(end 159.593501 119.826501)
		(width 0.114)
		(layer "In3.Cu")
		(net 642)
	)
	(segment
		(start 161.569031 119.739123)
		(end 161.452067 119.622159)
		(width 0.114)
		(layer "In3.Cu")
		(net 642)
	)
	(segment
		(start 176.186345 112.328624)
		(end 176.186343 112.328625)
		(width 0.114)
		(layer "In3.Cu")
		(net 642)
	)
	(segment
		(start 178.903501 108.727001)
		(end 178.460001 108.727001)
		(width 0.114)
		(layer "In3.Cu")
		(net 642)
	)
	(segment
		(start 176.77341 112.623655)
		(end 177.966501 111.430561)
		(width 0.114)
		(layer "In3.Cu")
		(net 642)
	)
	(segment
		(start 170.840561 118.556501)
		(end 174.298531 115.098531)
		(width 0.114)
		(layer "In3.Cu")
		(net 642)
	)
	(segment
		(start 176.186343 112.328625)
		(end 176.481374 112.623656)
		(width 0.114)
		(layer "In3.Cu")
		(net 642)
	)
	(segment
		(start 178.903501 101.360001)
		(end 178.460001 101.360001)
		(width 0.114)
		(layer "In3.Cu")
		(net 642)
	)
	(segment
		(start 162.34685 119.350216)
		(end 163.140561 118.556501)
		(width 0.114)
		(layer "In3.Cu")
		(net 642)
	)
	(arc
		(start 179.110001 108.933501)
		(mid 179.049519 108.787483)
		(end 178.903501 108.727001)
		(width 0.114)
		(layer "In3.Cu")
		(net 642)
	)
	(arc
		(start 175.488428 113.02654)
		(mid 175.343885 112.677583)
		(end 175.488427 112.328625)
		(width 0.114)
		(layer "In3.Cu")
		(net 642)
	)
	(arc
		(start 179.110001 105.766501)
		(mid 179.049519 105.620483)
		(end 178.903501 105.560001)
		(width 0.114)
		(layer "In3.Cu")
		(net 642)
	)
	(arc
		(start 174.498477 114.016491)
		(mid 174.353934 113.667534)
		(end 174.498476 113.318576)
		(width 0.114)
		(layer "In3.Cu")
		(net 642)
	)
	(arc
		(start 178.460001 108.727001)
		(mid 178.111044 108.582458)
		(end 177.966501 108.233501)
		(width 0.114)
		(layer "In3.Cu")
		(net 642)
	)
	(arc
		(start 177.966501 111.033501)
		(mid 178.111044 110.684544)
		(end 178.460001 110.540001)
		(width 0.114)
		(layer "In3.Cu")
		(net 642)
	)
	(arc
		(start 161.957941 119.350215)
		(mid 162.152395 119.430761)
		(end 162.34685 119.350216)
		(width 0.114)
		(layer "In3.Cu")
		(net 642)
	)
	(arc
		(start 174.298531 115.098531)
		(mid 174.647488 114.953988)
		(end 174.996445 115.098531)
		(width 0.114)
		(layer "In3.Cu")
		(net 642)
	)
	(arc
		(start 161.452067 119.622159)
		(mid 161.371521 119.427705)
		(end 161.452066 119.23325)
		(width 0.114)
		(layer "In3.Cu")
		(net 642)
	)
	(arc
		(start 176.281427 114.403609)
		(mid 176.427444 114.464092)
		(end 176.573462 114.40361)
		(width 0.114)
		(layer "In3.Cu")
		(net 642)
	)
	(arc
		(start 176.823001 109.633501)
		(mid 176.967544 109.284544)
		(end 177.316501 109.140001)
		(width 0.114)
		(layer "In3.Cu")
		(net 642)
	)
	(arc
		(start 178.903501 110.540001)
		(mid 179.049519 110.479519)
		(end 179.110001 110.333501)
		(width 0.114)
		(layer "In3.Cu")
		(net 642)
	)
	(arc
		(start 175.291475 115.393561)
		(mid 175.437493 115.454043)
		(end 175.58351 115.39356)
		(width 0.114)
		(layer "In3.Cu")
		(net 642)
	)
	(arc
		(start 175.58351 115.393561)
		(mid 175.643993 115.247543)
		(end 175.58351 115.101525)
		(width 0.114)
		(layer "In3.Cu")
		(net 642)
	)
	(arc
		(start 176.823001 102.266501)
		(mid 176.967544 101.917544)
		(end 177.316501 101.773001)
		(width 0.114)
		(layer "In3.Cu")
		(net 642)
	)
	(arc
		(start 179.110001 102.966501)
		(mid 179.049519 102.820483)
		(end 178.903501 102.760001)
		(width 0.114)
		(layer "In3.Cu")
		(net 642)
	)
	(arc
		(start 161.569031 120.128031)
		(mid 161.649577 119.933576)
		(end 161.569031 119.739123)
		(width 0.114)
		(layer "In3.Cu")
		(net 642)
	)
	(arc
		(start 176.573462 114.403609)
		(mid 176.633945 114.257591)
		(end 176.573462 114.111573)
		(width 0.114)
		(layer "In3.Cu")
		(net 642)
	)
	(arc
		(start 178.903501 109.140001)
		(mid 179.049519 109.079519)
		(end 179.110001 108.933501)
		(width 0.114)
		(layer "In3.Cu")
		(net 642)
	)
	(arc
		(start 179.110001 101.566501)
		(mid 179.049519 101.420483)
		(end 178.903501 101.360001)
		(width 0.114)
		(layer "In3.Cu")
		(net 642)
	)
	(arc
		(start 177.316501 102.760001)
		(mid 176.967544 102.615458)
		(end 176.823001 102.266501)
		(width 0.114)
		(layer "In3.Cu")
		(net 642)
	)
	(arc
		(start 176.823001 105.066501)
		(mid 176.967544 104.717544)
		(end 177.316501 104.573001)
		(width 0.114)
		(layer "In3.Cu")
		(net 642)
	)
	(arc
		(start 175.488429 112.328624)
		(mid 175.837386 112.184082)
		(end 176.186345 112.328624)
		(width 0.114)
		(layer "In3.Cu")
		(net 642)
	)
	(arc
		(start 176.823001 103.666501)
		(mid 176.967544 103.317544)
		(end 177.316501 103.173001)
		(width 0.114)
		(layer "In3.Cu")
		(net 642)
	)
	(arc
		(start 178.903501 103.173001)
		(mid 179.049519 103.112519)
		(end 179.110001 102.966501)
		(width 0.114)
		(layer "In3.Cu")
		(net 642)
	)
	(arc
		(start 161.452068 119.233249)
		(mid 161.646522 119.152704)
		(end 161.840978 119.233249)
		(width 0.114)
		(layer "In3.Cu")
		(net 642)
	)
	(arc
		(start 174.498478 113.318575)
		(mid 174.847435 113.174033)
		(end 175.196394 113.318575)
		(width 0.114)
		(layer "In3.Cu")
		(net 642)
	)
	(arc
		(start 177.316501 110.127001)
		(mid 176.967544 109.982458)
		(end 176.823001 109.633501)
		(width 0.114)
		(layer "In3.Cu")
		(net 642)
	)
	(arc
		(start 178.903501 105.973001)
		(mid 179.049519 105.912519)
		(end 179.110001 105.766501)
		(width 0.114)
		(layer "In3.Cu")
		(net 642)
	)
	(arc
		(start 176.481374 112.623656)
		(mid 176.627392 112.684138)
		(end 176.773409 112.623655)
		(width 0.114)
		(layer "In3.Cu")
		(net 642)
	)
	(arc
		(start 178.460001 101.360001)
		(mid 178.111044 101.215458)
		(end 177.966501 100.866501)
		(width 0.114)
		(layer "In3.Cu")
		(net 642)
	)
	(arc
		(start 177.316501 105.560001)
		(mid 176.967544 105.415458)
		(end 176.823001 105.066501)
		(width 0.114)
		(layer "In3.Cu")
		(net 642)
	)
	(arc
		(start 177.316501 104.160001)
		(mid 176.967544 104.015458)
		(end 176.823001 103.666501)
		(width 0.114)
		(layer "In3.Cu")
		(net 642)
	)
	(arc
		(start 177.966501 106.466501)
		(mid 178.111044 106.117544)
		(end 178.460001 105.973001)
		(width 0.114)
		(layer "In3.Cu")
		(net 642)
	)
	(arc
		(start 179.110001 104.366501)
		(mid 179.049519 104.220483)
		(end 178.903501 104.160001)
		(width 0.114)
		(layer "In3.Cu")
		(net 642)
	)
	(arc
		(start 179.110001 110.333501)
		(mid 179.049519 110.187483)
		(end 178.903501 110.127001)
		(width 0.114)
		(layer "In3.Cu")
		(net 642)
	)
	(arc
		(start 178.903501 101.773001)
		(mid 179.049519 101.712519)
		(end 179.110001 101.566501)
		(width 0.114)
		(layer "In3.Cu")
		(net 642)
	)
	(arc
		(start 178.903501 104.573001)
		(mid 179.049519 104.512519)
		(end 179.110001 104.366501)
		(width 0.114)
		(layer "In3.Cu")
		(net 642)
	)
	(segment
		(start 194.356501 112.484441)
		(end 181.615561 99.743501)
		(width 0.114)
		(layer "In5.Cu")
		(net 642)
	)
	(segment
		(start 197.000001 116.000001)
		(end 196.600001 115.600001)
		(width 0.1)
		(layer "In5.Cu")
		(net 642)
	)
	(segment
		(start 194.400001 115.291423)
		(end 194.400001 113.448501)
		(width 0.1)
		(layer "In5.Cu")
		(net 642)
	)
	(segment
		(start 194.708579 115.600001)
		(end 194.400001 115.291423)
		(width 0.1)
		(layer "In5.Cu")
		(net 642)
	)
	(segment
		(start 181.615561 99.743501)
		(end 177.475033 99.743501)
		(width 0.114)
		(layer "In5.Cu")
		(net 642)
	)
	(segment
		(start 194.400001 113.448501)
		(end 194.356501 113.405001)
		(width 0.1)
		(layer "In5.Cu")
		(net 642)
	)
	(segment
		(start 194.356501 113.405001)
		(end 194.356501 112.484441)
		(width 0.114)
		(layer "In5.Cu")
		(net 642)
	)
	(segment
		(start 196.600001 115.600001)
		(end 194.708579 115.600001)
		(width 0.1)
		(layer "In5.Cu")
		(net 642)
	)
	(segment
		(start 176.897061 99.165529)
		(end 176.659473 99.165529)
		(width 0.114)
		(layer "In5.Cu")
		(net 642)
	)
	(segment
		(start 177.475033 99.743501)
		(end 176.897061 99.165529)
		(width 0.114)
		(layer "In5.Cu")
		(net 642)
	)
	(segment
		(start 157.555001 87.766198)
		(end 157.876804 88.088001)
		(width 0.16)
		(layer "F.Cu")
		(net 643)
	)
	(segment
		(start 196.5 117.5)
		(end 196 117)
		(width 0.256)
		(layer "F.Cu")
		(net 643)
	)
	(segment
		(start 158.045002 88.088)
		(end 157.876804 88.088001)
		(width 0.16)
		(layer "F.Cu")
		(net 643)
	)
	(segment
		(start 157.555001 87.585001)
		(end 157.555001 87.766198)
		(width 0.16)
		(layer "F.Cu")
		(net 643)
	)
	(segment
		(start 158.045002 88.088)
		(end 158.190001 87.943001)
		(width 0.16)
		(layer "F.Cu")
		(net 643)
	)
	(via
		(at 196 117)
		(size 0.45)
		(drill 0.2)
		(layers "F.Cu" "B.Cu")
		(net 643)
	)
	(via
		(at 176.659473 100.690529)
		(size 0.45)
		(drill 0.2)
		(layers "F.Cu" "B.Cu")
		(net 643)
	)
	(via
		(at 158.190001 87.943001)
		(size 0.45)
		(drill 0.2)
		(layers "F.Cu" "B.Cu")
		(net 643)
	)
	(segment
		(start 158.056501 88.076501)
		(end 157.720561 88.076501)
		(width 0.114)
		(layer "In3.Cu")
		(net 643)
	)
	(segment
		(start 174.381501 98.174969)
		(end 176.659473 100.452941)
		(width 0.114)
		(layer "In3.Cu")
		(net 643)
	)
	(segment
		(start 158.190001 87.943001)
		(end 158.056501 88.076501)
		(width 0.114)
		(layer "In3.Cu")
		(net 643)
	)
	(segment
		(start 157.395497 88.401565)
		(end 157.395497 89.698437)
		(width 0.114)
		(layer "In3.Cu")
		(net 643)
	)
	(segment
		(start 157.395497 89.698437)
		(end 157.970561 90.273501)
		(width 0.114)
		(layer "In3.Cu")
		(net 643)
	)
	(segment
		(start 157.720561 88.076501)
		(end 157.395497 88.401565)
		(width 0.114)
		(layer "In3.Cu")
		(net 643)
	)
	(segment
		(start 176.659473 100.452941)
		(end 176.659473 100.690529)
		(width 0.114)
		(layer "In3.Cu")
		(net 643)
	)
	(segment
		(start 174.381501 93.234441)
		(end 174.381501 98.174969)
		(width 0.114)
		(layer "In3.Cu")
		(net 643)
	)
	(segment
		(start 157.970561 90.273501)
		(end 171.420561 90.273501)
		(width 0.114)
		(layer "In3.Cu")
		(net 643)
	)
	(segment
		(start 171.420561 90.273501)
		(end 174.381501 93.234441)
		(width 0.114)
		(layer "In3.Cu")
		(net 643)
	)
	(segment
		(start 184.678174 104.669486)
		(end 184.876342 104.471317)
		(width 0.114)
		(layer "In5.Cu")
		(net 643)
	)
	(segment
		(start 184.178429 103.773404)
		(end 184.178429 103.773403)
		(width 0.114)
		(layer "In5.Cu")
		(net 643)
	)
	(segment
		(start 184.178428 103.481367)
		(end 184.178428 103.481368)
		(width 0.114)
		(layer "In5.Cu")
		(net 643)
	)
	(segment
		(start 184.178429 103.773403)
		(end 183.98026 103.971571)
		(width 0.114)
		(layer "In5.Cu")
		(net 643)
	)
	(segment
		(start 185.168377 104.471316)
		(end 185.168377 104.471317)
		(width 0.114)
		(layer "In5.Cu")
		(net 643)
	)
	(segment
		(start 182.000362 102.689587)
		(end 182.000362 102.689588)
		(width 0.114)
		(layer "In5.Cu")
		(net 643)
	)
	(segment
		(start 182.198531 101.793506)
		(end 182.198531 101.793505)
		(width 0.114)
		(layer "In5.Cu")
		(net 643)
	)
	(segment
		(start 184.678175 104.669485)
		(end 184.678174 104.669486)
		(width 0.114)
		(layer "In5.Cu")
		(net 643)
	)
	(segment
		(start 193.300001 113.448501)
		(end 193.256501 113.405001)
		(width 0.1)
		(layer "In5.Cu")
		(net 643)
	)
	(segment
		(start 195.600001 116.600001)
		(end 193.658579 116.600001)
		(width 0.1)
		(layer "In5.Cu")
		(net 643)
	)
	(segment
		(start 176.659473 100.690529)
		(end 176.897061 100.690529)
		(width 0.114)
		(layer "In5.Cu")
		(net 643)
	)
	(segment
		(start 183.18848 102.783455)
		(end 183.18848 102.783454)
		(width 0.114)
		(layer "In5.Cu")
		(net 643)
	)
	(segment
		(start 182.198531 101.793505)
		(end 182.000362 101.991673)
		(width 0.114)
		(layer "In5.Cu")
		(net 643)
	)
	(segment
		(start 177.225033 101.018501)
		(end 181.715561 101.018501)
		(width 0.114)
		(layer "In5.Cu")
		(net 643)
	)
	(segment
		(start 182.698276 102.689588)
		(end 182.896444 102.491419)
		(width 0.114)
		(layer "In5.Cu")
		(net 643)
	)
	(segment
		(start 196.000001 117.000001)
		(end 195.600001 116.600001)
		(width 0.1)
		(layer "In5.Cu")
		(net 643)
	)
	(segment
		(start 183.688226 103.679536)
		(end 183.688225 103.679537)
		(width 0.114)
		(layer "In5.Cu")
		(net 643)
	)
	(segment
		(start 183.188479 102.491418)
		(end 183.188479 102.491419)
		(width 0.114)
		(layer "In5.Cu")
		(net 643)
	)
	(segment
		(start 193.658579 116.600001)
		(end 193.300001 116.241423)
		(width 0.1)
		(layer "In5.Cu")
		(net 643)
	)
	(segment
		(start 183.18848 102.783454)
		(end 182.990311 102.981622)
		(width 0.114)
		(layer "In5.Cu")
		(net 643)
	)
	(segment
		(start 183.98026 104.669485)
		(end 183.98026 104.669486)
		(width 0.114)
		(layer "In5.Cu")
		(net 643)
	)
	(segment
		(start 193.300001 116.241423)
		(end 193.300001 113.448501)
		(width 0.1)
		(layer "In5.Cu")
		(net 643)
	)
	(segment
		(start 183.688225 103.679537)
		(end 183.886393 103.481368)
		(width 0.114)
		(layer "In5.Cu")
		(net 643)
	)
	(segment
		(start 182.990311 103.679536)
		(end 182.990311 103.679537)
		(width 0.114)
		(layer "In5.Cu")
		(net 643)
	)
	(segment
		(start 181.715561 101.018501)
		(end 182.198531 101.50147)
		(width 0.114)
		(layer "In5.Cu")
		(net 643)
	)
	(segment
		(start 176.897061 100.690529)
		(end 177.225033 101.018501)
		(width 0.114)
		(layer "In5.Cu")
		(net 643)
	)
	(segment
		(start 182.698277 102.689587)
		(end 182.698276 102.689588)
		(width 0.114)
		(layer "In5.Cu")
		(net 643)
	)
	(segment
		(start 193.256501 112.559441)
		(end 193.256501 113.405001)
		(width 0.114)
		(layer "In5.Cu")
		(net 643)
	)
	(segment
		(start 185.168377 104.471317)
		(end 193.256501 112.559441)
		(width 0.114)
		(layer "In5.Cu")
		(net 643)
	)
	(arc
		(start 183.18848 102.491419)
		(mid 183.248963 102.637437)
		(end 183.18848 102.783455)
		(width 0.114)
		(layer "In5.Cu")
		(net 643)
	)
	(arc
		(start 182.990311 102.981622)
		(mid 182.845768 103.330579)
		(end 182.990311 103.679536)
		(width 0.114)
		(layer "In5.Cu")
		(net 643)
	)
	(arc
		(start 183.886393 103.481368)
		(mid 184.03241 103.420885)
		(end 184.178428 103.481367)
		(width 0.114)
		(layer "In5.Cu")
		(net 643)
	)
	(arc
		(start 182.000362 102.689588)
		(mid 182.34932 102.83413)
		(end 182.698277 102.689587)
		(width 0.114)
		(layer "In5.Cu")
		(net 643)
	)
	(arc
		(start 182.990311 103.679537)
		(mid 183.339269 103.824079)
		(end 183.688226 103.679536)
		(width 0.114)
		(layer "In5.Cu")
		(net 643)
	)
	(arc
		(start 184.178429 103.481368)
		(mid 184.238912 103.627386)
		(end 184.178429 103.773404)
		(width 0.114)
		(layer "In5.Cu")
		(net 643)
	)
	(arc
		(start 183.98026 103.971571)
		(mid 183.835717 104.320528)
		(end 183.98026 104.669485)
		(width 0.114)
		(layer "In5.Cu")
		(net 643)
	)
	(arc
		(start 182.896444 102.491419)
		(mid 183.042461 102.430936)
		(end 183.188479 102.491418)
		(width 0.114)
		(layer "In5.Cu")
		(net 643)
	)
	(arc
		(start 184.876342 104.471317)
		(mid 185.022359 104.410834)
		(end 185.168377 104.471316)
		(width 0.114)
		(layer "In5.Cu")
		(net 643)
	)
	(arc
		(start 182.000362 101.991673)
		(mid 181.855819 102.34063)
		(end 182.000362 102.689587)
		(width 0.114)
		(layer "In5.Cu")
		(net 643)
	)
	(arc
		(start 183.98026 104.669486)
		(mid 184.329218 104.814028)
		(end 184.678175 104.669485)
		(width 0.114)
		(layer "In5.Cu")
		(net 643)
	)
	(arc
		(start 182.198531 101.50147)
		(mid 182.259014 101.647488)
		(end 182.198531 101.793506)
		(width 0.114)
		(layer "In5.Cu")
		(net 643)
	)
	(segment
		(start 199.5 130.5)
		(end 199 131)
		(width 0.256)
		(layer "F.Cu")
		(net 649)
	)
	(segment
		(start 161.166422 141.675)
		(end 160.425 141.675)
		(width 0.1)
		(layer "F.Cu")
		(net 649)
	)
	(segment
		(start 161.591422 145.6)
		(end 162 145.191422)
		(width 0.1)
		(layer "F.Cu")
		(net 649)
	)
	(segment
		(start 160.425 141.675)
		(end 160.25 141.5)
		(width 0.1)
		(layer "F.Cu")
		(net 649)
	)
	(segment
		(start 161 145.6)
		(end 161.591422 145.6)
		(width 0.1)
		(layer "F.Cu")
		(net 649)
	)
	(segment
		(start 162 142.508578)
		(end 161.166422 141.675)
		(width 0.1)
		(layer "F.Cu")
		(net 649)
	)
	(segment
		(start 160.9 145.7)
		(end 161 145.6)
		(width 0.1)
		(layer "F.Cu")
		(net 649)
	)
	(segment
		(start 162 145.191422)
		(end 162 142.508578)
		(width 0.1)
		(layer "F.Cu")
		(net 649)
	)
	(via
		(at 160.25 141.5)
		(size 0.45)
		(drill 0.2)
		(layers "F.Cu" "B.Cu")
		(net 649)
	)
	(via
		(at 199 131)
		(size 0.45)
		(drill 0.2)
		(layers "F.Cu" "B.Cu")
		(net 649)
	)
	(segment
		(start 198.87 131.442)
		(end 198.87 131.13)
		(width 0.4)
		(layer "B.Cu")
		(net 649)
	)
	(segment
		(start 198.87 131.13)
		(end 199 131)
		(width 0.4)
		(layer "B.Cu")
		(net 649)
	)
	(segment
		(start 199 131)
		(end 198.75 131)
		(width 0.1)
		(layer "In5.Cu")
		(net 649)
	)
	(segment
		(start 191.925 133.316422)
		(end 191.708578 133.1)
		(width 0.1)
		(layer "In5.Cu")
		(net 649)
	)
	(segment
		(start 172.933578 133.95)
		(end 172.308578 133.325)
		(width 0.1)
		(layer "In5.Cu")
		(net 649)
	)
	(segment
		(start 183.166422 133.1)
		(end 182.316422 133.95)
		(width 0.1)
		(layer "In5.Cu")
		(net 649)
	)
	(segment
		(start 163.008578 132.075)
		(end 159.391422 132.075)
		(width 0.1)
		(layer "In5.Cu")
		(net 649)
	)
	(segment
		(start 198.6 131.366422)
		(end 198.366422 131.6)
		(width 0.1)
		(layer "In5.Cu")
		(net 649)
	)
	(segment
		(start 198.366422 131.6)
		(end 197.866422 131.6)
		(width 0.1)
		(layer "In5.Cu")
		(net 649)
	)
	(segment
		(start 182.316422 133.95)
		(end 172.933578 133.95)
		(width 0.1)
		(layer "In5.Cu")
		(net 649)
	)
	(segment
		(start 172.308578 133.325)
		(end 164.258578 133.325)
		(width 0.1)
		(layer "In5.Cu")
		(net 649)
	)
	(segment
		(start 191.925 135.016422)
		(end 191.925 133.316422)
		(width 0.1)
		(layer "In5.Cu")
		(net 649)
	)
	(segment
		(start 193.6 132.791422)
		(end 193.6 134.666422)
		(width 0.1)
		(layer "In5.Cu")
		(net 649)
	)
	(segment
		(start 156.275 135.191422)
		(end 156.275 139.508578)
		(width 0.1)
		(layer "In5.Cu")
		(net 649)
	)
	(segment
		(start 197.866422 131.6)
		(end 197.6 131.866422)
		(width 0.1)
		(layer "In5.Cu")
		(net 649)
	)
	(segment
		(start 164.258578 133.325)
		(end 163.008578 132.075)
		(width 0.1)
		(layer "In5.Cu")
		(net 649)
	)
	(segment
		(start 193.766422 132.625)
		(end 193.6 132.791422)
		(width 0.1)
		(layer "In5.Cu")
		(net 649)
	)
	(segment
		(start 193.6 134.666422)
		(end 192.966422 135.3)
		(width 0.1)
		(layer "In5.Cu")
		(net 649)
	)
	(segment
		(start 198.75 131)
		(end 198.6 131.15)
		(width 0.1)
		(layer "In5.Cu")
		(net 649)
	)
	(segment
		(start 159.391422 132.075)
		(end 156.275 135.191422)
		(width 0.1)
		(layer "In5.Cu")
		(net 649)
	)
	(segment
		(start 191.708578 133.1)
		(end 183.166422 133.1)
		(width 0.1)
		(layer "In5.Cu")
		(net 649)
	)
	(segment
		(start 156.275 139.508578)
		(end 158.441422 141.675)
		(width 0.1)
		(layer "In5.Cu")
		(net 649)
	)
	(segment
		(start 158.441422 141.675)
		(end 160.075 141.675)
		(width 0.1)
		(layer "In5.Cu")
		(net 649)
	)
	(segment
		(start 192.208578 135.3)
		(end 191.925 135.016422)
		(width 0.1)
		(layer "In5.Cu")
		(net 649)
	)
	(segment
		(start 197.291422 132.625)
		(end 193.766422 132.625)
		(width 0.1)
		(layer "In5.Cu")
		(net 649)
	)
	(segment
		(start 160.075 141.675)
		(end 160.25 141.5)
		(width 0.1)
		(layer "In5.Cu")
		(net 649)
	)
	(segment
		(start 197.6 131.866422)
		(end 197.6 132.316422)
		(width 0.1)
		(layer "In5.Cu")
		(net 649)
	)
	(segment
		(start 192.966422 135.3)
		(end 192.208578 135.3)
		(width 0.1)
		(layer "In5.Cu")
		(net 649)
	)
	(segment
		(start 197.6 132.316422)
		(end 197.291422 132.625)
		(width 0.1)
		(layer "In5.Cu")
		(net 649)
	)
	(segment
		(start 198.6 131.15)
		(end 198.6 131.366422)
		(width 0.1)
		(layer "In5.Cu")
		(net 649)
	)
	(segment
		(start 201.5 132.5)
		(end 202 133)
		(width 0.4)
		(layer "F.Cu")
		(net 650)
	)
	(segment
		(start 200.5 127.5)
		(end 201 127)
		(width 0.4)
		(layer "F.Cu")
		(net 650)
	)
	(segment
		(start 199.5 126.5)
		(end 199 126)
		(width 0.4)
		(layer "F.Cu")
		(net 650)
	)
	(segment
		(start 202.5 131.5)
		(end 203 132)
		(width 0.4)
		(layer "F.Cu")
		(net 650)
	)
	(segment
		(start 200.5 131.5)
		(end 201 132)
		(width 0.4)
		(layer "F.Cu")
		(net 650)
	)
	(segment
		(start 201.5 130.5)
		(end 202 131)
		(width 0.4)
		(layer "F.Cu")
		(net 650)
	)
	(segment
		(start 197.5 126.5)
		(end 197 126)
		(width 0.4)
		(layer "F.Cu")
		(net 650)
	)
	(segment
		(start 202.5 127.5)
		(end 203 127)
		(width 0.4)
		(layer "F.Cu")
		(net 650)
	)
	(segment
		(start 201.5 128.5)
		(end 202 128)
		(width 0.4)
		(layer "F.Cu")
		(net 650)
	)
	(segment
		(start 196.5 129.5)
		(end 196 129)
		(width 0.4)
		(layer "F.Cu")
		(net 650)
	)
	(segment
		(start 194.5 127.5)
		(end 194 127)
		(width 0.4)
		(layer "F.Cu")
		(net 650)
	)
	(segment
		(start 202.5 129.5)
		(end 203 129)
		(width 0.4)
		(layer "F.Cu")
		(net 650)
	)
	(segment
		(start 200.5 129.5)
		(end 201 129)
		(width 0.4)
		(layer "F.Cu")
		(net 650)
	)
	(segment
		(start 194.5 129.5)
		(end 194 129)
		(width 0.4)
		(layer "F.Cu")
		(net 650)
	)
	(segment
		(start 195.5 130.5)
		(end 195 131)
		(width 0.4)
		(layer "F.Cu")
		(net 650)
	)
	(segment
		(start 196.5 127.5)
		(end 196 127)
		(width 0.4)
		(layer "F.Cu")
		(net 650)
	)
	(segment
		(start 195.5 126.5)
		(end 195 126)
		(width 0.4)
		(layer "F.Cu")
		(net 650)
	)
	(segment
		(start 194.5 131.5)
		(end 194 132)
		(width 0.4)
		(layer "F.Cu")
		(net 650)
	)
	(segment
		(start 202.5 133.5)
		(end 203 134)
		(width 0.4)
		(layer "F.Cu")
		(net 650)
	)
	(segment
		(start 195.5 128.5)
		(end 195 128)
		(width 0.4)
		(layer "F.Cu")
		(net 650)
	)
	(segment
		(start 196.5 131.5)
		(end 196 132)
		(width 0.4)
		(layer "F.Cu")
		(net 650)
	)
	(segment
		(start 201.5 126.5)
		(end 202 126)
		(width 0.4)
		(layer "F.Cu")
		(net 650)
	)
	(segment
		(start 198.5 127.5)
		(end 198 127)
		(width 0.4)
		(layer "F.Cu")
		(net 650)
	)
	(segment
		(start 200.5 133.5)
		(end 201 134)
		(width 0.4)
		(layer "F.Cu")
		(net 650)
	)
	(via
		(at 207 130)
		(size 0.45)
		(drill 0.2)
		(layers "F.Cu" "B.Cu")
		(net 650)
	)
	(via
		(at 202 131)
		(size 0.45)
		(drill 0.2)
		(layers "F.Cu" "B.Cu")
		(net 650)
	)
	(via
		(at 203 132)
		(size 0.45)
		(drill 0.2)
		(layers "F.Cu" "B.Cu")
		(net 650)
	)
	(via
		(at 195 131)
		(size 0.45)
		(drill 0.2)
		(layers "F.Cu" "B.Cu")
		(net 650)
	)
	(via
		(at 201 127)
		(size 0.45)
		(drill 0.2)
		(layers "F.Cu" "B.Cu")
		(net 650)
	)
	(via
		(at 200 132)
		(size 0.45)
		(drill 0.2)
		(layers "F.Cu" "B.Cu")
		(net 650)
	)
	(via
		(at 199.4 152.2)
		(size 0.45)
		(drill 0.2)
		(layers "F.Cu" "B.Cu")
		(free yes)
		(net 650)
	)
	(via
		(at 200 141)
		(size 0.45)
		(drill 0.2)
		(layers "F.Cu" "B.Cu")
		(net 650)
	)
	(via
		(at 196 127)
		(size 0.45)
		(drill 0.2)
		(layers "F.Cu" "B.Cu")
		(net 650)
	)
	(via
		(at 201 134)
		(size 0.45)
		(drill 0.2)
		(layers "F.Cu" "B.Cu")
		(net 650)
	)
	(via
		(at 200.2 151.6)
		(size 0.45)
		(drill 0.2)
		(layers "F.Cu" "B.Cu")
		(free yes)
		(net 650)
	)
	(via
		(at 200 129)
		(size 0.45)
		(drill 0.2)
		(layers "F.Cu" "B.Cu")
		(net 650)
	)
	(via
		(at 201.6 153.4)
		(size 0.45)
		(drill 0.2)
		(layers "F.Cu" "B.Cu")
		(free yes)
		(net 650)
	)
	(via
		(at 199.2 151)
		(size 0.45)
		(drill 0.2)
		(layers "F.Cu" "B.Cu")
		(free yes)
		(net 650)
	)
	(via
		(at 199 151.6)
		(size 0.45)
		(drill 0.2)
		(layers "F.Cu" "B.Cu")
		(free yes)
		(net 650)
	)
	(via
		(at 200 136)
		(size 0.45)
		(drill 0.2)
		(layers "F.Cu" "B.Cu")
		(net 650)
	)
	(via
		(at 196 132)
		(size 0.45)
		(drill 0.2)
		(layers "F.Cu" "B.Cu")
		(net 650)
	)
	(via
		(at 203 129)
		(size 0.45)
		(drill 0.2)
		(layers "F.Cu" "B.Cu")
		(net 650)
	)
	(via
		(at 205.075 150.375)
		(size 0.45)
		(drill 0.2)
		(layers "F.Cu" "B.Cu")
		(net 650)
	)
	(via
		(at 194 132)
		(size 0.45)
		(drill 0.2)
		(layers "F.Cu" "B.Cu")
		(net 650)
	)
	(via
		(at 199 149.4)
		(size 0.45)
		(drill 0.2)
		(layers "F.Cu" "B.Cu")
		(net 650)
	)
	(via
		(at 200.4 153.4)
		(size 0.45)
		(drill 0.2)
		(layers "F.Cu" "B.Cu")
		(free yes)
		(net 650)
	)
	(via
		(at 201 153.4)
		(size 0.45)
		(drill 0.2)
		(layers "F.Cu" "B.Cu")
		(free yes)
		(net 650)
	)
	(via
		(at 204.125 151.925)
		(size 0.45)
		(drill 0.2)
		(layers "F.Cu" "B.Cu")
		(net 650)
	)
	(via
		(at 200.2 152.8)
		(size 0.45)
		(drill 0.2)
		(layers "F.Cu" "B.Cu")
		(free yes)
		(net 650)
	)
	(via
		(at 203 127)
		(size 0.45)
		(drill 0.2)
		(layers "F.Cu" "B.Cu")
		(net 650)
	)
	(via
		(at 201 129)
		(size 0.45)
		(drill 0.2)
		(layers "F.Cu" "B.Cu")
		(net 650)
	)
	(via
		(at 200 127)
		(size 0.45)
		(drill 0.2)
		(layers "F.Cu" "B.Cu")
		(net 650)
	)
	(via
		(at 203 134)
		(size 0.45)
		(drill 0.2)
		(layers "F.Cu" "B.Cu")
		(net 650)
	)
	(via
		(at 200 124)
		(size 0.45)
		(drill 0.2)
		(layers "F.Cu" "B.Cu")
		(net 650)
	)
	(via
		(at 194 148.4)
		(size 0.45)
		(drill 0.2)
		(layers "F.Cu" "B.Cu")
		(net 650)
	)
	(via
		(at 202 133)
		(size 0.45)
		(drill 0.2)
		(layers "F.Cu" "B.Cu")
		(net 650)
	)
	(via
		(at 194 129)
		(size 0.45)
		(drill 0.2)
		(layers "F.Cu" "B.Cu")
		(net 650)
	)
	(via
		(at 199 130)
		(size 0.45)
		(drill 0.2)
		(layers "F.Cu" "B.Cu")
		(net 650)
	)
	(via
		(at 195 126)
		(size 0.45)
		(drill 0.2)
		(layers "F.Cu" "B.Cu")
		(net 650)
	)
	(via
		(at 199.6 151.6)
		(size 0.45)
		(drill 0.2)
		(layers "F.Cu" "B.Cu")
		(free yes)
		(net 650)
	)
	(via
		(at 199 150.4)
		(size 0.45)
		(drill 0.2)
		(layers "F.Cu" "B.Cu")
		(net 650)
	)
	(via
		(at 194 150.4)
		(size 0.45)
		(drill 0.2)
		(layers "F.Cu" "B.Cu")
		(net 650)
	)
	(via
		(at 200 133)
		(size 0.45)
		(drill 0.2)
		(layers "F.Cu" "B.Cu")
		(net 650)
	)
	(via
		(at 194 127)
		(size 0.45)
		(drill 0.2)
		(layers "F.Cu" "B.Cu")
		(net 650)
	)
	(via
		(at 199.8 151)
		(size 0.45)
		(drill 0.2)
		(layers "F.Cu" "B.Cu")
		(free yes)
		(net 650)
	)
	(via
		(at 202 128)
		(size 0.45)
		(drill 0.2)
		(layers "F.Cu" "B.Cu")
		(net 650)
	)
	(via
		(at 197 126)
		(size 0.45)
		(drill 0.2)
		(layers "F.Cu" "B.Cu")
		(net 650)
	)
	(via
		(at 200.8 152.8)
		(size 0.45)
		(drill 0.2)
		(layers "F.Cu" "B.Cu")
		(free yes)
		(net 650)
	)
	(via
		(at 196 129)
		(size 0.45)
		(drill 0.2)
		(layers "F.Cu" "B.Cu")
		(net 650)
	)
	(via
		(at 199 126)
		(size 0.45)
		(drill 0.2)
		(layers "F.Cu" "B.Cu")
		(net 650)
	)
	(via
		(at 204.125 150.375)
		(size 0.45)
		(drill 0.2)
		(layers "F.Cu" "B.Cu")
		(net 650)
	)
	(via
		(at 201 132)
		(size 0.45)
		(drill 0.2)
		(layers "F.Cu" "B.Cu")
		(net 650)
	)
	(via
		(at 202 126)
		(size 0.45)
		(drill 0.2)
		(layers "F.Cu" "B.Cu")
		(net 650)
	)
	(via
		(at 204 130)
		(size 0.45)
		(drill 0.2)
		(layers "F.Cu" "B.Cu")
		(net 650)
	)
	(via
		(at 201.4 152.8)
		(size 0.45)
		(drill 0.2)
		(layers "F.Cu" "B.Cu")
		(free yes)
		(net 650)
	)
	(via
		(at 198 127)
		(size 0.45)
		(drill 0.2)
		(layers "F.Cu" "B.Cu")
		(net 650)
	)
	(via
		(at 194 149.4)
		(size 0.45)
		(drill 0.2)
		(layers "F.Cu" "B.Cu")
		(net 650)
	)
	(via
		(at 199 148.4)
		(size 0.45)
		(drill 0.2)
		(layers "F.Cu" "B.Cu")
		(net 650)
	)
	(via
		(at 198.6 151)
		(size 0.45)
		(drill 0.2)
		(layers "F.Cu" "B.Cu")
		(free yes)
		(net 650)
	)
	(via
		(at 195 128)
		(size 0.45)
		(drill 0.2)
		(layers "F.Cu" "B.Cu")
		(net 650)
	)
	(via
		(at 200.6 152.2)
		(size 0.45)
		(drill 0.2)
		(layers "F.Cu" "B.Cu")
		(free yes)
		(net 650)
	)
	(via
		(at 200 152.2)
		(size 0.45)
		(drill 0.2)
		(layers "F.Cu" "B.Cu")
		(free yes)
		(net 650)
	)
	(via
		(at 205.075 151.925)
		(size 0.45)
		(drill 0.2)
		(layers "F.Cu" "B.Cu")
		(net 650)
	)
	(segment
		(start 203.67 130)
		(end 204 130)
		(width 0.4)
		(layer "B.Cu")
		(net 650)
	)
	(segment
		(start 203.27 127)
		(end 203 127)
		(width 0.4)
		(layer "B.Cu")
		(net 650)
	)
	(segment
		(start 201 129.47)
		(end 201 129)
		(width 0.4)
		(layer "B.Cu")
		(net 650)
	)
	(segment
		(start 201.18 133.65)
		(end 201 133.83)
		(width 0.4)
		(layer "B.Cu")
		(net 650)
	)
	(segment
		(start 202 125.83)
		(end 202 126)
		(width 0.4)
		(layer "B.Cu")
		(net 650)
	)
	(segment
		(start 201.82 131.18)
		(end 202 131)
		(width 0.4)
		(layer "B.Cu")
		(net 650)
	)
	(segment
		(start 203.45 126.82)
		(end 203.27 127)
		(width 0.4)
		(layer "B.Cu")
		(net 650)
	)
	(segment
		(start 201.18 128.85)
		(end 201.15 128.85)
		(width 0.4)
		(layer "B.Cu")
		(net 650)
	)
	(segment
		(start 202.83 129)
		(end 203 129)
		(width 0.4)
		(layer "B.Cu")
		(net 650)
	)
	(segment
		(start 202.65 126.82)
		(end 202.83 127)
		(width 0.4)
		(layer "B.Cu")
		(net 650)
	)
	(segment
		(start 202.68 130.45)
		(end 202.13 131)
		(width 0.4)
		(layer "B.Cu")
		(net 650)
	)
	(segment
		(start 201.18 127.25)
		(end 201.18 127.18)
		(width 0.4)
		(layer "B.Cu")
		(net 650)
	)
	(segment
		(start 203.45 131.92)
		(end 203.37 132)
		(width 0.4)
		(layer "B.Cu")
		(net 650)
	)
	(segment
		(start 203.45 128.82)
		(end 203.27 129)
		(width 0.4)
		(layer "B.Cu")
		(net 650)
	)
	(segment
		(start 201.82 128.05)
		(end 201.95 128.05)
		(width 0.4)
		(layer "B.Cu")
		(net 650)
	)
	(segment
		(start 202.13 131)
		(end 202 131)
		(width 0.4)
		(layer "B.Cu")
		(net 650)
	)
	(segment
		(start 202 126.27)
		(end 202 126)
		(width 0.4)
		(layer "B.Cu")
		(net 650)
	)
	(segment
		(start 201.82 132.85)
		(end 201.85 132.85)
		(width 0.4)
		(layer "B.Cu")
		(net 650)
	)
	(segment
		(start 201.82 130.45)
		(end 201.82 130.82)
		(width 0.4)
		(layer "B.Cu")
		(net 650)
	)
	(segment
		(start 201.18 127.18)
		(end 201 127)
		(width 0.4)
		(layer "B.Cu")
		(net 650)
	)
	(segment
		(start 201.82 126.45)
		(end 202 126.27)
		(width 0.4)
		(layer "B.Cu")
		(net 650)
	)
	(segment
		(start 201 134.27)
		(end 201 134)
		(width 0.4)
		(layer "B.Cu")
		(net 650)
	)
	(segment
		(start 201.95 128.05)
		(end 202 128)
		(width 0.4)
		(layer "B.Cu")
		(net 650)
	)
	(segment
		(start 201 133.83)
		(end 201 134)
		(width 0.4)
		(layer "B.Cu")
		(net 650)
	)
	(segment
		(start 201.82 130.82)
		(end 202 131)
		(width 0.4)
		(layer "B.Cu")
		(net 650)
	)
	(segment
		(start 203.37 132)
		(end 203 132)
		(width 0.4)
		(layer "B.Cu")
		(net 650)
	)
	(segment
		(start 201.82 131.25)
		(end 201.82 131.18)
		(width 0.4)
		(layer "B.Cu")
		(net 650)
	)
	(segment
		(start 202.83 127)
		(end 203 127)
		(width 0.4)
		(layer "B.Cu")
		(net 650)
	)
	(segment
		(start 202.65 128.82)
		(end 202.83 129)
		(width 0.4)
		(layer "B.Cu")
		(net 650)
	)
	(segment
		(start 201.18 129.65)
		(end 201 129.47)
		(width 0.4)
		(layer "B.Cu")
		(net 650)
	)
	(segment
		(start 201.85 132.85)
		(end 202 133)
		(width 0.4)
		(layer "B.Cu")
		(net 650)
	)
	(segment
		(start 202.65 131.92)
		(end 202.73 132)
		(width 0.4)
		(layer "B.Cu")
		(net 650)
	)
	(segment
		(start 201.15 128.85)
		(end 201 129)
		(width 0.4)
		(layer "B.Cu")
		(net 650)
	)
	(segment
		(start 202.73 132)
		(end 203 132)
		(width 0.4)
		(layer "B.Cu")
		(net 650)
	)
	(segment
		(start 203.32 129.65)
		(end 203.67 130)
		(width 0.4)
		(layer "B.Cu")
		(net 650)
	)
	(segment
		(start 203.27 129)
		(end 203 129)
		(width 0.4)
		(layer "B.Cu")
		(net 650)
	)
	(segment
		(start 201.18 134.45)
		(end 201 134.27)
		(width 0.4)
		(layer "B.Cu")
		(net 650)
	)
	(segment
		(start 201.82 125.65)
		(end 202 125.83)
		(width 0.4)
		(layer "B.Cu")
		(net 650)
	)
	(segment
		(start 191.04349 140.95651)
		(end 191.04349 140.975001)
		(width 0.256)
		(layer "F.Cu")
		(net 654)
	)
	(segment
		(start 191.5 140.5)
		(end 191.04349 140.95651)
		(width 0.256)
		(layer "F.Cu")
		(net 654)
	)
	(segment
		(start 170.4 147.6)
		(end 170.8 147.2)
		(width 0.256)
		(layer "F.Cu")
		(net 654)
	)
	(via
		(at 170.4 147.6)
		(size 0.45)
		(drill 0.2)
		(layers "F.Cu" "B.Cu")
		(net 654)
	)
	(via
		(at 191.04349 140.975001)
		(size 0.45)
		(drill 0.2)
		(layers "F.Cu" "B.Cu")
		(net 654)
	)
	(segment
		(start 194.525 150.75)
		(end 194.225 151.05)
		(width 0.157)
		(layer "In5.Cu")
		(net 654)
	)
	(segment
		(start 173.4 153.175)
		(end 173.4 151.1)
		(width 0.157)
		(layer "In5.Cu")
		(net 654)
	)
	(segment
		(start 190.375 158.5)
		(end 178.725 158.5)
		(width 0.157)
		(layer "In5.Cu")
		(net 654)
	)
	(segment
		(start 171.214392 149.609871)
		(end 171.349999 149.474265)
		(width 0.157)
		(layer "In5.Cu")
		(net 654)
	)
	(segment
		(start 172.06292 150.458399)
		(end 172.198527 150.322793)
		(width 0.157)
		(layer "In5.Cu")
		(net 654)
	)
	(segment
		(start 194.225 151.05)
		(end 194.225 154.65)
		(width 0.157)
		(layer "In5.Cu")
		(net 654)
	)
	(segment
		(start 194.525 141.75)
		(end 194.525 150.75)
		(width 0.157)
		(layer "In5.Cu")
		(net 654)
	)
	(segment
		(start 191.04349 140.975001)
		(end 191.518491 140.5)
		(width 0.157)
		(layer "In5.Cu")
		(net 654)
	)
	(segment
		(start 171.774263 149.898527)
		(end 171.638657 150.034134)
		(width 0.157)
		(layer "In5.Cu")
		(net 654)
	)
	(segment
		(start 178.725 158.5)
		(end 173.4 153.175)
		(width 0.157)
		(layer "In5.Cu")
		(net 654)
	)
	(segment
		(start 173.4 151.1)
		(end 173.047055 150.747055)
		(width 0.157)
		(layer "In5.Cu")
		(net 654)
	)
	(segment
		(start 172.622791 150.747055)
		(end 172.487185 150.882662)
		(width 0.157)
		(layer "In5.Cu")
		(net 654)
	)
	(segment
		(start 170.4 148.1)
		(end 170.4 147.6)
		(width 0.157)
		(layer "In5.Cu")
		(net 654)
	)
	(segment
		(start 191.518491 140.5)
		(end 193.275 140.5)
		(width 0.157)
		(layer "In5.Cu")
		(net 654)
	)
	(segment
		(start 172.198528 149.898528)
		(end 172.198527 149.898527)
		(width 0.157)
		(layer "In5.Cu")
		(net 654)
	)
	(segment
		(start 171.35 149.05)
		(end 170.4 148.1)
		(width 0.157)
		(layer "In5.Cu")
		(net 654)
	)
	(segment
		(start 194.225 154.65)
		(end 190.375 158.5)
		(width 0.157)
		(layer "In5.Cu")
		(net 654)
	)
	(segment
		(start 193.275 140.5)
		(end 194.525 141.75)
		(width 0.157)
		(layer "In5.Cu")
		(net 654)
	)
	(arc
		(start 172.06292 150.882663)
		(mid 171.975052 150.670531)
		(end 172.06292 150.458399)
		(width 0.157)
		(layer "In5.Cu")
		(net 654)
	)
	(arc
		(start 171.214392 150.034135)
		(mid 171.126524 149.822003)
		(end 171.214392 149.609871)
		(width 0.157)
		(layer "In5.Cu")
		(net 654)
	)
	(arc
		(start 172.487185 150.882662)
		(mid 172.275053 150.970531)
		(end 172.06292 150.882663)
		(width 0.157)
		(layer "In5.Cu")
		(net 654)
	)
	(arc
		(start 172.198527 150.322793)
		(mid 172.286396 150.110661)
		(end 172.198528 149.898528)
		(width 0.157)
		(layer "In5.Cu")
		(net 654)
	)
	(arc
		(start 171.638657 150.034134)
		(mid 171.426525 150.122003)
		(end 171.214392 150.034135)
		(width 0.157)
		(layer "In5.Cu")
		(net 654)
	)
	(arc
		(start 171.349999 149.474265)
		(mid 171.437868 149.262133)
		(end 171.35 149.05)
		(width 0.157)
		(layer "In5.Cu")
		(net 654)
	)
	(arc
		(start 173.047055 150.747055)
		(mid 172.834923 150.659187)
		(end 172.622791 150.747055)
		(width 0.157)
		(layer "In5.Cu")
		(net 654)
	)
	(arc
		(start 172.198527 149.898527)
		(mid 171.986395 149.810659)
		(end 171.774263 149.898527)
		(width 0.157)
		(layer "In5.Cu")
		(net 654)
	)
	(segment
		(start 170.799999 144.000003)
		(end 171.2 143.6)
		(width 0.256)
		(layer "F.Cu")
		(net 655)
	)
	(segment
		(start 191 142)
		(end 191.5 141.5)
		(width 0.256)
		(layer "F.Cu")
		(net 655)
	)
	(via
		(at 171.2 143.6)
		(size 0.45)
		(drill 0.2)
		(layers "F.Cu" "B.Cu")
		(net 655)
	)
	(via
		(at 191 142)
		(size 0.45)
		(drill 0.2)
		(layers "F.Cu" "B.Cu")
		(net 655)
	)
	(segment
		(start 173.45 142.575)
		(end 174.175 143.3)
		(width 0.157)
		(layer "In5.Cu")
		(net 655)
	)
	(segment
		(start 187.2 145.95)
		(end 187.475 145.675)
		(width 0.157)
		(layer "In5.Cu")
		(net 655)
	)
	(segment
		(start 179.689212 144.63137)
		(end 180.693045 143.627538)
		(width 0.157)
		(layer "In5.Cu")
		(net 655)
	)
	(segment
		(start 179.123528 144.065684)
		(end 179.123527 144.065685)
		(width 0.157)
		(layer "In5.Cu")
		(net 655)
	)
	(segment
		(start 175.725 143.1)
		(end 175.725 141.7)
		(width 0.157)
		(layer "In5.Cu")
		(net 655)
	)
	(segment
		(start 180.254898 145.197054)
		(end 180.254897 145.197055)
		(width 0.157)
		(layer "In5.Cu")
		(net 655)
	)
	(segment
		(start 179.406369 144.631369)
		(end 179.406368 144.631368)
		(width 0.157)
		(layer "In5.Cu")
		(net 655)
	)
	(segment
		(start 180.975887 143.91038)
		(end 179.972053 144.914211)
		(width 0.157)
		(layer "In5.Cu")
		(net 655)
	)
	(segment
		(start 181.541573 144.193224)
		(end 181.541572 144.193223)
		(width 0.157)
		(layer "In5.Cu")
		(net 655)
	)
	(segment
		(start 174.925 143.1)
		(end 174.925 141.7)
		(width 0.157)
		(layer "In5.Cu")
		(net 655)
	)
	(segment
		(start 179.809161 142.814365)
		(end 178.840685 143.782842)
		(width 0.157)
		(layer "In5.Cu")
		(net 655)
	)
	(segment
		(start 190.75 142)
		(end 191 142)
		(width 0.157)
		(layer "In5.Cu")
		(net 655)
	)
	(segment
		(start 179.972053 145.197053)
		(end 179.972055 145.197055)
		(width 0.157)
		(layer "In5.Cu")
		(net 655)
	)
	(segment
		(start 178.557843 143.499999)
		(end 178.557842 143.5)
		(width 0.157)
		(layer "In5.Cu")
		(net 655)
	)
	(segment
		(start 178.840684 144.065684)
		(end 178.840685 144.065685)
		(width 0.157)
		(layer "In5.Cu")
		(net 655)
	)
	(segment
		(start 190.25 142.5)
		(end 190.75 142)
		(width 0.157)
		(layer "In5.Cu")
		(net 655)
	)
	(segment
		(start 180.410203 143.061854)
		(end 180.410202 143.061853)
		(width 0.157)
		(layer "In5.Cu")
		(net 655)
	)
	(segment
		(start 187.475 145.675)
		(end 187.475 143.8)
		(width 0.157)
		(layer "In5.Cu")
		(net 655)
	)
	(segment
		(start 171.2 143.6)
		(end 171.2 142.975)
		(width 0.157)
		(layer "In5.Cu")
		(net 655)
	)
	(segment
		(start 180.975886 143.910381)
		(end 180.975887 143.91038)
		(width 0.157)
		(layer "In5.Cu")
		(net 655)
	)
	(segment
		(start 171.6 142.575)
		(end 173.45 142.575)
		(width 0.157)
		(layer "In5.Cu")
		(net 655)
	)
	(segment
		(start 181.541572 144.476065)
		(end 180.537738 145.479896)
		(width 0.157)
		(layer "In5.Cu")
		(net 655)
	)
	(segment
		(start 179.406368 144.631368)
		(end 179.40637 144.63137)
		(width 0.157)
		(layer "In5.Cu")
		(net 655)
	)
	(segment
		(start 189.65 142.5)
		(end 190.25 142.5)
		(width 0.157)
		(layer "In5.Cu")
		(net 655)
	)
	(segment
		(start 181.541571 144.476066)
		(end 181.541572 144.476065)
		(width 0.157)
		(layer "In5.Cu")
		(net 655)
	)
	(segment
		(start 180.537738 145.762738)
		(end 180.725 145.95)
		(width 0.157)
		(layer "In5.Cu")
		(net 655)
	)
	(segment
		(start 180.410201 143.344696)
		(end 180.410202 143.344695)
		(width 0.157)
		(layer "In5.Cu")
		(net 655)
	)
	(segment
		(start 180.725 145.95)
		(end 187.2 145.95)
		(width 0.157)
		(layer "In5.Cu")
		(net 655)
	)
	(segment
		(start 179.972054 145.197054)
		(end 179.972053 145.197053)
		(width 0.157)
		(layer "In5.Cu")
		(net 655)
	)
	(segment
		(start 171.2 142.975)
		(end 171.6 142.575)
		(width 0.157)
		(layer "In5.Cu")
		(net 655)
	)
	(segment
		(start 177.325 143.1)
		(end 177.325 141.7)
		(width 0.157)
		(layer "In5.Cu")
		(net 655)
	)
	(segment
		(start 180.254897 145.197055)
		(end 181.25873 144.193223)
		(width 0.157)
		(layer "In5.Cu")
		(net 655)
	)
	(segment
		(start 174.175 143.3)
		(end 174.725 143.3)
		(width 0.157)
		(layer "In5.Cu")
		(net 655)
	)
	(segment
		(start 179.689213 144.631369)
		(end 179.689212 144.63137)
		(width 0.157)
		(layer "In5.Cu")
		(net 655)
	)
	(segment
		(start 178.075 143.3)
		(end 178.275 143.5)
		(width 0.157)
		(layer "In5.Cu")
		(net 655)
	)
	(segment
		(start 177.925 143.3)
		(end 177.975 143.3)
		(width 0.157)
		(layer "In5.Cu")
		(net 655)
	)
	(segment
		(start 175.325 141.7)
		(end 175.325 143.1)
		(width 0.157)
		(layer "In5.Cu")
		(net 655)
	)
	(segment
		(start 176.925 141.7)
		(end 176.925 143.1)
		(width 0.157)
		(layer "In5.Cu")
		(net 655)
	)
	(segment
		(start 187.775 143.5)
		(end 188.65 143.5)
		(width 0.157)
		(layer "In5.Cu")
		(net 655)
	)
	(segment
		(start 177.725 141.7)
		(end 177.725 143.1)
		(width 0.157)
		(layer "In5.Cu")
		(net 655)
	)
	(segment
		(start 177.975 143.3)
		(end 178.075 143.3)
		(width 0.157)
		(layer "In5.Cu")
		(net 655)
	)
	(segment
		(start 176.125 141.7)
		(end 176.125 143.1)
		(width 0.157)
		(layer "In5.Cu")
		(net 655)
	)
	(segment
		(start 179.123527 144.065685)
		(end 180.12736 143.061853)
		(width 0.157)
		(layer "In5.Cu")
		(net 655)
	)
	(segment
		(start 180.410202 143.344695)
		(end 179.406368 144.348526)
		(width 0.157)
		(layer "In5.Cu")
		(net 655)
	)
	(segment
		(start 178.557842 143.5)
		(end 179.526319 142.531524)
		(width 0.157)
		(layer "In5.Cu")
		(net 655)
	)
	(segment
		(start 188.65 143.5)
		(end 189.65 142.5)
		(width 0.157)
		(layer "In5.Cu")
		(net 655)
	)
	(segment
		(start 179.809162 142.531523)
		(end 179.809161 142.531523)
		(width 0.157)
		(layer "In5.Cu")
		(net 655)
	)
	(segment
		(start 178.840684 144.065685)
		(end 178.840684 144.065684)
		(width 0.157)
		(layer "In5.Cu")
		(net 655)
	)
	(segment
		(start 180.975888 143.627539)
		(end 180.975887 143.627538)
		(width 0.157)
		(layer "In5.Cu")
		(net 655)
	)
	(segment
		(start 179.80916 142.814366)
		(end 179.809161 142.814365)
		(width 0.157)
		(layer "In5.Cu")
		(net 655)
	)
	(segment
		(start 180.537739 145.762739)
		(end 180.537738 145.762738)
		(width 0.157)
		(layer "In5.Cu")
		(net 655)
	)
	(segment
		(start 187.475 143.8)
		(end 187.775 143.5)
		(width 0.157)
		(layer "In5.Cu")
		(net 655)
	)
	(segment
		(start 176.525 143.1)
		(end 176.525 141.7)
		(width 0.157)
		(layer "In5.Cu")
		(net 655)
	)
	(arc
		(start 180.537738 145.479896)
		(mid 180.47916 145.621318)
		(end 180.537739 145.762739)
		(width 0.157)
		(layer "In5.Cu")
		(net 655)
	)
	(arc
		(start 181.541572 144.193223)
		(mid 181.60015 144.334645)
		(end 181.541571 144.476066)
		(width 0.157)
		(layer "In5.Cu")
		(net 655)
	)
	(arc
		(start 175.325 143.1)
		(mid 175.383579 143.241421)
		(end 175.525 143.3)
		(width 0.157)
		(layer "In5.Cu")
		(net 655)
	)
	(arc
		(start 179.972055 145.197055)
		(mid 180.113477 145.255633)
		(end 180.254898 145.197054)
		(width 0.157)
		(layer "In5.Cu")
		(net 655)
	)
	(arc
		(start 175.525 143.3)
		(mid 175.666421 143.241421)
		(end 175.725 143.1)
		(width 0.157)
		(layer "In5.Cu")
		(net 655)
	)
	(arc
		(start 177.725 143.1)
		(mid 177.783579 143.241421)
		(end 177.925 143.3)
		(width 0.157)
		(layer "In5.Cu")
		(net 655)
	)
	(arc
		(start 176.925 143.1)
		(mid 176.983579 143.241421)
		(end 177.125 143.3)
		(width 0.157)
		(layer "In5.Cu")
		(net 655)
	)
	(arc
		(start 180.410202 143.061853)
		(mid 180.46878 143.203275)
		(end 180.410201 143.344696)
		(width 0.157)
		(layer "In5.Cu")
		(net 655)
	)
	(arc
		(start 177.525 141.5)
		(mid 177.666421 141.558579)
		(end 177.725 141.7)
		(width 0.157)
		(layer "In5.Cu")
		(net 655)
	)
	(arc
		(start 178.840685 144.065685)
		(mid 178.982107 144.124263)
		(end 179.123528 144.065684)
		(width 0.157)
		(layer "In5.Cu")
		(net 655)
	)
	(arc
		(start 176.525 141.7)
		(mid 176.583579 141.558579)
		(end 176.725 141.5)
		(width 0.157)
		(layer "In5.Cu")
		(net 655)
	)
	(arc
		(start 179.972053 144.914211)
		(mid 179.913475 145.055633)
		(end 179.972054 145.197054)
		(width 0.157)
		(layer "In5.Cu")
		(net 655)
	)
	(arc
		(start 180.693045 143.627538)
		(mid 180.834467 143.56896)
		(end 180.975888 143.627539)
		(width 0.157)
		(layer "In5.Cu")
		(net 655)
	)
	(arc
		(start 177.125 143.3)
		(mid 177.266421 143.241421)
		(end 177.325 143.1)
		(width 0.157)
		(layer "In5.Cu")
		(net 655)
	)
	(arc
		(start 180.12736 143.061853)
		(mid 180.268782 143.003275)
		(end 180.410203 143.061854)
		(width 0.157)
		(layer "In5.Cu")
		(net 655)
	)
	(arc
		(start 175.925 141.5)
		(mid 176.066421 141.558579)
		(end 176.125 141.7)
		(width 0.157)
		(layer "In5.Cu")
		(net 655)
	)
	(arc
		(start 177.325 141.7)
		(mid 177.383579 141.558579)
		(end 177.525 141.5)
		(width 0.157)
		(layer "In5.Cu")
		(net 655)
	)
	(arc
		(start 175.725 141.7)
		(mid 175.783579 141.558579)
		(end 175.925 141.5)
		(width 0.157)
		(layer "In5.Cu")
		(net 655)
	)
	(arc
		(start 181.25873 144.193223)
		(mid 181.400152 144.134645)
		(end 181.541573 144.193224)
		(width 0.157)
		(layer "In5.Cu")
		(net 655)
	)
	(arc
		(start 176.125 143.1)
		(mid 176.183579 143.241421)
		(end 176.325 143.3)
		(width 0.157)
		(layer "In5.Cu")
		(net 655)
	)
	(arc
		(start 179.526319 142.531524)
		(mid 179.66774 142.472945)
		(end 179.809162 142.531523)
		(width 0.157)
		(layer "In5.Cu")
		(net 655)
	)
	(arc
		(start 179.40637 144.63137)
		(mid 179.547792 144.689948)
		(end 179.689213 144.631369)
		(width 0.157)
		(layer "In5.Cu")
		(net 655)
	)
	(arc
		(start 179.809161 142.531523)
		(mid 179.867739 142.672945)
		(end 179.80916 142.814366)
		(width 0.157)
		(layer "In5.Cu")
		(net 655)
	)
	(arc
		(start 175.125 141.5)
		(mid 175.266421 141.558579)
		(end 175.325 141.7)
		(width 0.157)
		(layer "In5.Cu")
		(net 655)
	)
	(arc
		(start 179.406368 144.348526)
		(mid 179.34779 144.489948)
		(end 179.406369 144.631369)
		(width 0.157)
		(layer "In5.Cu")
		(net 655)
	)
	(arc
		(start 176.325 143.3)
		(mid 176.466421 143.241421)
		(end 176.525 143.1)
		(width 0.157)
		(layer "In5.Cu")
		(net 655)
	)
	(arc
		(start 178.840685 143.782842)
		(mid 178.782106 143.924263)
		(end 178.840684 144.065685)
		(width 0.157)
		(layer "In5.Cu")
		(net 655)
	)
	(arc
		(start 180.975887 143.627538)
		(mid 181.034465 143.76896)
		(end 180.975886 143.910381)
		(width 0.157)
		(layer "In5.Cu")
		(net 655)
	)
	(arc
		(start 176.725 141.5)
		(mid 176.866421 141.558579)
		(end 176.925 141.7)
		(width 0.157)
		(layer "In5.Cu")
		(net 655)
	)
	(arc
		(start 174.925 141.7)
		(mid 174.983579 141.558579)
		(end 175.125 141.5)
		(width 0.157)
		(layer "In5.Cu")
		(net 655)
	)
	(arc
		(start 178.275 143.5)
		(mid 178.416422 143.558578)
		(end 178.557843 143.499999)
		(width 0.157)
		(layer "In5.Cu")
		(net 655)
	)
	(arc
		(start 174.725 143.3)
		(mid 174.866421 143.241421)
		(end 174.925 143.1)
		(width 0.157)
		(layer "In5.Cu")
		(net 655)
	)
	(segment
		(start 191.5 142.5)
		(end 191 143)
		(width 0.256)
		(layer "F.Cu")
		(net 656)
	)
	(segment
		(start 172.4 144.56)
		(end 172.4 144)
		(width 0.225)
		(layer "F.Cu")
		(net 656)
	)
	(via
		(at 191 143)
		(size 0.45)
		(drill 0.2)
		(layers "F.Cu" "B.Cu")
		(net 656)
	)
	(via
		(at 172.4 144.56)
		(size 0.45)
		(drill 0.2)
		(layers "F.Cu" "B.Cu")
		(net 656)
	)
	(segment
		(start 189.912 143.796624)
		(end 190.361624 143.347)
		(width 0.141)
		(layer "In5.Cu")
		(net 656)
	)
	(segment
		(start 173.449195 145.089805)
		(end 177.070181 145.089805)
		(width 0.141)
		(layer "In5.Cu")
		(net 656)
	)
	(segment
		(start 184.688 151.828025)
		(end 184.688 150.335975)
		(width 0.141)
		(layer "In5.Cu")
		(net 656)
	)
	(segment
		(start 187.094 150.385975)
		(end 187.094 151.828025)
		(width 0.141)
		(layer "In5.Cu")
		(net 656)
	)
	(segment
		(start 184.294 150.335975)
		(end 184.294 151.828025)
		(width 0.141)
		(layer "In5.Cu")
		(net 656)
	)
	(segment
		(start 186.088 151.828025)
		(end 186.088 150.385975)
		(width 0.141)
		(layer "In5.Cu")
		(net 656)
	)
	(segment
		(start 182.894 150.385975)
		(end 182.894 151.828025)
		(width 0.141)
		(layer "In5.Cu")
		(net 656)
	)
	(segment
		(start 190.653 143.347)
		(end 191 143)
		(width 0.141)
		(layer "In5.Cu")
		(net 656)
	)
	(segment
		(start 173.399195 145.089805)
		(end 173.449195 145.089805)
		(width 0.141)
		(layer "In5.Cu")
		(net 656)
	)
	(segment
		(start 181.494 150.385975)
		(end 181.494 151.828025)
		(width 0.141)
		(layer "In5.Cu")
		(net 656)
	)
	(segment
		(start 187.488 151.828025)
		(end 187.488 150.385975)
		(width 0.141)
		(layer "In5.Cu")
		(net 656)
	)
	(segment
		(start 173.224195 144.607588)
		(end 173.224195 144.914805)
		(width 0.141)
		(layer "In5.Cu")
		(net 656)
	)
	(segment
		(start 179.725376 150.929)
		(end 180.291 150.929)
		(width 0.141)
		(layer "In5.Cu")
		(net 656)
	)
	(segment
		(start 181.888 151.828025)
		(end 181.888 150.385975)
		(width 0.141)
		(layer "In5.Cu")
		(net 656)
	)
	(segment
		(start 172.333982 145.089805)
		(end 172.699195 145.089805)
		(width 0.141)
		(layer "In5.Cu")
		(net 656)
	)
	(segment
		(start 183.288 151.828025)
		(end 183.288 150.335975)
		(width 0.141)
		(layer "In5.Cu")
		(net 656)
	)
	(segment
		(start 180.488 150.732)
		(end 180.488 150.385975)
		(width 0.141)
		(layer "In5.Cu")
		(net 656)
	)
	(segment
		(start 172.874195 144.914805)
		(end 172.874195 144.607588)
		(width 0.141)
		(layer "In5.Cu")
		(net 656)
	)
	(segment
		(start 190.361624 143.347)
		(end 190.653 143.347)
		(width 0.141)
		(layer "In5.Cu")
		(net 656)
	)
	(segment
		(start 178.473 146.492624)
		(end 178.473 149.676624)
		(width 0.141)
		(layer "In5.Cu")
		(net 656)
	)
	(segment
		(start 189.47226 150.929)
		(end 189.912 150.48926)
		(width 0.141)
		(layer "In5.Cu")
		(net 656)
	)
	(segment
		(start 177.070181 145.089805)
		(end 178.473 146.492624)
		(width 0.141)
		(layer "In5.Cu")
		(net 656)
	)
	(segment
		(start 172.4 144.56)
		(end 172.153 144.807)
		(width 0.141)
		(layer "In5.Cu")
		(net 656)
	)
	(segment
		(start 178.473 149.676624)
		(end 179.725376 150.929)
		(width 0.141)
		(layer "In5.Cu")
		(net 656)
	)
	(segment
		(start 185.694 150.335975)
		(end 185.694 151.828025)
		(width 0.141)
		(layer "In5.Cu")
		(net 656)
	)
	(segment
		(start 172.153 144.807)
		(end 172.153 144.908823)
		(width 0.141)
		(layer "In5.Cu")
		(net 656)
	)
	(segment
		(start 188.691 150.929)
		(end 189.47226 150.929)
		(width 0.141)
		(layer "In5.Cu")
		(net 656)
	)
	(segment
		(start 189.912 150.48926)
		(end 189.912 143.796624)
		(width 0.141)
		(layer "In5.Cu")
		(net 656)
	)
	(segment
		(start 188.494 150.385975)
		(end 188.494 150.732)
		(width 0.141)
		(layer "In5.Cu")
		(net 656)
	)
	(segment
		(start 172.153 144.908823)
		(end 172.333982 145.089805)
		(width 0.141)
		(layer "In5.Cu")
		(net 656)
	)
	(arc
		(start 181.691 152.025025)
		(mid 181.8303 151.967325)
		(end 181.888 151.828025)
		(width 0.141)
		(layer "In5.Cu")
		(net 656)
	)
	(arc
		(start 181.494 151.828025)
		(mid 181.5517 151.967325)
		(end 181.691 152.025025)
		(width 0.141)
		(layer "In5.Cu")
		(net 656)
	)
	(arc
		(start 173.049195 144.432588)
		(mid 173.172939 144.483844)
		(end 173.224195 144.607588)
		(width 0.141)
		(layer "In5.Cu")
		(net 656)
	)
	(arc
		(start 185.694 151.828025)
		(mid 185.7517 151.967325)
		(end 185.891 152.025025)
		(width 0.141)
		(layer "In5.Cu")
		(net 656)
	)
	(arc
		(start 186.591 149.882975)
		(mid 186.946675 150.0303)
		(end 187.094 150.385975)
		(width 0.141)
		(layer "In5.Cu")
		(net 656)
	)
	(arc
		(start 182.894 151.828025)
		(mid 182.9517 151.967325)
		(end 183.091 152.025025)
		(width 0.141)
		(layer "In5.Cu")
		(net 656)
	)
	(arc
		(start 185.891 152.025025)
		(mid 186.0303 151.967325)
		(end 186.088 151.828025)
		(width 0.141)
		(layer "In5.Cu")
		(net 656)
	)
	(arc
		(start 172.699195 145.089805)
		(mid 172.822939 145.038549)
		(end 172.874195 144.914805)
		(width 0.141)
		(layer "In5.Cu")
		(net 656)
	)
	(arc
		(start 187.488 150.385975)
		(mid 187.635325 150.0303)
		(end 187.991 149.882975)
		(width 0.141)
		(layer "In5.Cu")
		(net 656)
	)
	(arc
		(start 184.491 152.025025)
		(mid 184.6303 151.967325)
		(end 184.688 151.828025)
		(width 0.141)
		(layer "In5.Cu")
		(net 656)
	)
	(arc
		(start 183.091 152.025025)
		(mid 183.2303 151.967325)
		(end 183.288 151.828025)
		(width 0.141)
		(layer "In5.Cu")
		(net 656)
	)
	(arc
		(start 183.288 150.335975)
		(mid 183.435325 149.9803)
		(end 183.791 149.832975)
		(width 0.141)
		(layer "In5.Cu")
		(net 656)
	)
	(arc
		(start 183.791 149.832975)
		(mid 184.146675 149.9803)
		(end 184.294 150.335975)
		(width 0.141)
		(layer "In5.Cu")
		(net 656)
	)
	(arc
		(start 180.488 150.385975)
		(mid 180.635325 150.0303)
		(end 180.991 149.882975)
		(width 0.141)
		(layer "In5.Cu")
		(net 656)
	)
	(arc
		(start 187.991 149.882975)
		(mid 188.346675 150.0303)
		(end 188.494 150.385975)
		(width 0.141)
		(layer "In5.Cu")
		(net 656)
	)
	(arc
		(start 186.088 150.385975)
		(mid 186.235325 150.0303)
		(end 186.591 149.882975)
		(width 0.141)
		(layer "In5.Cu")
		(net 656)
	)
	(arc
		(start 181.888 150.385975)
		(mid 182.035325 150.0303)
		(end 182.391 149.882975)
		(width 0.141)
		(layer "In5.Cu")
		(net 656)
	)
	(arc
		(start 184.688 150.335975)
		(mid 184.835325 149.9803)
		(end 185.191 149.832975)
		(width 0.141)
		(layer "In5.Cu")
		(net 656)
	)
	(arc
		(start 180.291 150.929)
		(mid 180.4303 150.8713)
		(end 180.488 150.732)
		(width 0.141)
		(layer "In5.Cu")
		(net 656)
	)
	(arc
		(start 188.494 150.732)
		(mid 188.5517 150.8713)
		(end 188.691 150.929)
		(width 0.141)
		(layer "In5.Cu")
		(net 656)
	)
	(arc
		(start 173.224195 144.914805)
		(mid 173.275451 145.038549)
		(end 173.399195 145.089805)
		(width 0.141)
		(layer "In5.Cu")
		(net 656)
	)
	(arc
		(start 184.294 151.828025)
		(mid 184.3517 151.967325)
		(end 184.491 152.025025)
		(width 0.141)
		(layer "In5.Cu")
		(net 656)
	)
	(arc
		(start 182.391 149.882975)
		(mid 182.746675 150.0303)
		(end 182.894 150.385975)
		(width 0.141)
		(layer "In5.Cu")
		(net 656)
	)
	(arc
		(start 187.094 151.828025)
		(mid 187.1517 151.967325)
		(end 187.291 152.025025)
		(width 0.141)
		(layer "In5.Cu")
		(net 656)
	)
	(arc
		(start 180.991 149.882975)
		(mid 181.346675 150.0303)
		(end 181.494 150.385975)
		(width 0.141)
		(layer "In5.Cu")
		(net 656)
	)
	(arc
		(start 187.291 152.025025)
		(mid 187.4303 151.967325)
		(end 187.488 151.828025)
		(width 0.141)
		(layer "In5.Cu")
		(net 656)
	)
	(arc
		(start 185.191 149.832975)
		(mid 185.546675 149.9803)
		(end 185.694 150.335975)
		(width 0.141)
		(layer "In5.Cu")
		(net 656)
	)
	(arc
		(start 172.874195 144.607588)
		(mid 172.925451 144.483844)
		(end 173.049195 144.432588)
		(width 0.141)
		(layer "In5.Cu")
		(net 656)
	)
	(segment
		(start 190.5 143.5)
		(end 190 143)
		(width 0.256)
		(layer "F.Cu")
		(net 657)
	)
	(segment
		(start 172.8 148.4)
		(end 172.4 148)
		(width 0.256)
		(layer "F.Cu")
		(net 657)
	)
	(via
		(at 172.8 148.4)
		(size 0.45)
		(drill 0.2)
		(layers "F.Cu" "B.Cu")
		(net 657)
	)
	(via
		(at 190 143)
		(size 0.45)
		(drill 0.2)
		(layers "F.Cu" "B.Cu")
		(net 657)
	)
	(segment
		(start 181.35 156.2)
		(end 181.35 156.584686)
		(width 0.157)
		(layer "In5.Cu")
		(net 657)
	)
	(segment
		(start 174.95 152.35)
		(end 178.6 156)
		(width 0.157)
		(layer "In5.Cu")
		(net 657)
	)
	(segment
		(start 186.15 156.2)
		(end 186.15 156.584686)
		(width 0.157)
		(layer "In5.Cu")
		(net 657)
	)
	(segment
		(start 184.95 156.584686)
		(end 184.95 156.2)
		(width 0.157)
		(layer "In5.Cu")
		(net 657)
	)
	(segment
		(start 184.55 156.2)
		(end 184.55 156.584686)
		(width 0.157)
		(layer "In5.Cu")
		(net 657)
	)
	(segment
		(start 182.95 156.2)
		(end 182.95 156.584686)
		(width 0.157)
		(layer "In5.Cu")
		(net 657)
	)
	(segment
		(start 192.9035 144.832864)
		(end 192.499999 144.429363)
		(width 0.157)
		(layer "In5.Cu")
		(net 657)
	)
	(segment
		(start 184.15 156.584686)
		(end 184.15 156.2)
		(width 0.157)
		(layer "In5.Cu")
		(net 657)
	)
	(segment
		(start 187.55 156)
		(end 190.775 156)
		(width 0.157)
		(layer "In5.Cu")
		(net 657)
	)
	(segment
		(start 187.35 156.584686)
		(end 187.35 156.2)
		(width 0.157)
		(layer "In5.Cu")
		(net 657)
	)
	(segment
		(start 180.15 156.584686)
		(end 180.15 156.2)
		(width 0.157)
		(layer "In5.Cu")
		(net 657)
	)
	(segment
		(start 190.324998 143)
		(end 190 143)
		(width 0.157)
		(layer "In5.Cu")
		(net 657)
	)
	(segment
		(start 183.75 156.2)
		(end 183.75 156.584686)
		(width 0.157)
		(layer "In5.Cu")
		(net 657)
	)
	(segment
		(start 178.6 156)
		(end 179.55 156)
		(width 0.157)
		(layer "In5.Cu")
		(net 657)
	)
	(segment
		(start 186.95 156.2)
		(end 186.95 156.584686)
		(width 0.157)
		(layer "In5.Cu")
		(net 657)
	)
	(segment
		(start 192.499999 142.737499)
		(end 192.262499 142.499999)
		(width 0.157)
		(layer "In5.Cu")
		(net 657)
	)
	(segment
		(start 190.824999 142.499999)
		(end 190.324998 143)
		(width 0.157)
		(layer "In5.Cu")
		(net 657)
	)
	(segment
		(start 183.35 156.584686)
		(end 183.35 156.2)
		(width 0.157)
		(layer "In5.Cu")
		(net 657)
	)
	(segment
		(start 181.75 156.584686)
		(end 181.75 156.2)
		(width 0.157)
		(layer "In5.Cu")
		(net 657)
	)
	(segment
		(start 185.35 156.2)
		(end 185.35 156.584686)
		(width 0.157)
		(layer "In5.Cu")
		(net 657)
	)
	(segment
		(start 174.95 150.550004)
		(end 174.95 152.35)
		(width 0.157)
		(layer "In5.Cu")
		(net 657)
	)
	(segment
		(start 180.95 156.584686)
		(end 180.95 156.2)
		(width 0.157)
		(layer "In5.Cu")
		(net 657)
	)
	(segment
		(start 180.55 156.2)
		(end 180.55 156.584686)
		(width 0.157)
		(layer "In5.Cu")
		(net 657)
	)
	(segment
		(start 179.75 156.2)
		(end 179.75 156.584686)
		(width 0.157)
		(layer "In5.Cu")
		(net 657)
	)
	(segment
		(start 186.55 156.584686)
		(end 186.55 156.2)
		(width 0.157)
		(layer "In5.Cu")
		(net 657)
	)
	(segment
		(start 192.262499 142.499999)
		(end 190.824999 142.499999)
		(width 0.157)
		(layer "In5.Cu")
		(net 657)
	)
	(segment
		(start 172.8 148.4)
		(end 174.95 150.550004)
		(width 0.157)
		(layer "In5.Cu")
		(net 657)
	)
	(segment
		(start 192.499999 144.429363)
		(end 192.499999 142.737499)
		(width 0.157)
		(layer "In5.Cu")
		(net 657)
	)
	(segment
		(start 182.55 156.584686)
		(end 182.55 156.2)
		(width 0.157)
		(layer "In5.Cu")
		(net 657)
	)
	(segment
		(start 185.75 156.584686)
		(end 185.75 156.2)
		(width 0.157)
		(layer "In5.Cu")
		(net 657)
	)
	(segment
		(start 190.775 156)
		(end 192.9035 153.8715)
		(width 0.157)
		(layer "In5.Cu")
		(net 657)
	)
	(segment
		(start 182.15 156.2)
		(end 182.15 156.584686)
		(width 0.157)
		(layer "In5.Cu")
		(net 657)
	)
	(segment
		(start 192.9035 153.8715)
		(end 192.9035 144.832864)
		(width 0.157)
		(layer "In5.Cu")
		(net 657)
	)
	(arc
		(start 184.55 156.584686)
		(mid 184.608579 156.726107)
		(end 184.75 156.784686)
		(width 0.157)
		(layer "In5.Cu")
		(net 657)
	)
	(arc
		(start 186.95 156.584686)
		(mid 187.008579 156.726107)
		(end 187.15 156.784686)
		(width 0.157)
		(layer "In5.Cu")
		(net 657)
	)
	(arc
		(start 180.15 156.2)
		(mid 180.208579 156.058579)
		(end 180.35 156)
		(width 0.157)
		(layer "In5.Cu")
		(net 657)
	)
	(arc
		(start 182.15 156.584686)
		(mid 182.208579 156.726107)
		(end 182.35 156.784686)
		(width 0.157)
		(layer "In5.Cu")
		(net 657)
	)
	(arc
		(start 187.35 156.2)
		(mid 187.408579 156.058579)
		(end 187.55 156)
		(width 0.157)
		(layer "In5.Cu")
		(net 657)
	)
	(arc
		(start 180.55 156.584686)
		(mid 180.608579 156.726107)
		(end 180.75 156.784686)
		(width 0.157)
		(layer "In5.Cu")
		(net 657)
	)
	(arc
		(start 182.75 156)
		(mid 182.891421 156.058579)
		(end 182.95 156.2)
		(width 0.157)
		(layer "In5.Cu")
		(net 657)
	)
	(arc
		(start 180.75 156.784686)
		(mid 180.891421 156.726107)
		(end 180.95 156.584686)
		(width 0.157)
		(layer "In5.Cu")
		(net 657)
	)
	(arc
		(start 181.15 156)
		(mid 181.291421 156.058579)
		(end 181.35 156.2)
		(width 0.157)
		(layer "In5.Cu")
		(net 657)
	)
	(arc
		(start 181.55 156.784686)
		(mid 181.691421 156.726107)
		(end 181.75 156.584686)
		(width 0.157)
		(layer "In5.Cu")
		(net 657)
	)
	(arc
		(start 185.15 156)
		(mid 185.291421 156.058579)
		(end 185.35 156.2)
		(width 0.157)
		(layer "In5.Cu")
		(net 657)
	)
	(arc
		(start 183.75 156.584686)
		(mid 183.808579 156.726107)
		(end 183.95 156.784686)
		(width 0.157)
		(layer "In5.Cu")
		(net 657)
	)
	(arc
		(start 183.55 156)
		(mid 183.691421 156.058579)
		(end 183.75 156.2)
		(width 0.157)
		(layer "In5.Cu")
		(net 657)
	)
	(arc
		(start 180.95 156.2)
		(mid 181.008579 156.058579)
		(end 181.15 156)
		(width 0.157)
		(layer "In5.Cu")
		(net 657)
	)
	(arc
		(start 184.95 156.2)
		(mid 185.008579 156.058579)
		(end 185.15 156)
		(width 0.157)
		(layer "In5.Cu")
		(net 657)
	)
	(arc
		(start 182.95 156.584686)
		(mid 183.008579 156.726107)
		(end 183.15 156.784686)
		(width 0.157)
		(layer "In5.Cu")
		(net 657)
	)
	(arc
		(start 180.35 156)
		(mid 180.491421 156.058579)
		(end 180.55 156.2)
		(width 0.157)
		(layer "In5.Cu")
		(net 657)
	)
	(arc
		(start 179.55 156)
		(mid 179.691421 156.058579)
		(end 179.75 156.2)
		(width 0.157)
		(layer "In5.Cu")
		(net 657)
	)
	(arc
		(start 184.75 156.784686)
		(mid 184.891421 156.726107)
		(end 184.95 156.584686)
		(width 0.157)
		(layer "In5.Cu")
		(net 657)
	)
	(arc
		(start 181.75 156.2)
		(mid 181.808579 156.058579)
		(end 181.95 156)
		(width 0.157)
		(layer "In5.Cu")
		(net 657)
	)
	(arc
		(start 181.35 156.584686)
		(mid 181.408579 156.726107)
		(end 181.55 156.784686)
		(width 0.157)
		(layer "In5.Cu")
		(net 657)
	)
	(arc
		(start 183.15 156.784686)
		(mid 183.291421 156.726107)
		(end 183.35 156.584686)
		(width 0.157)
		(layer "In5.Cu")
		(net 657)
	)
	(arc
		(start 179.75 156.584686)
		(mid 179.808579 156.726107)
		(end 179.95 156.784686)
		(width 0.157)
		(layer "In5.Cu")
		(net 657)
	)
	(arc
		(start 186.15 156.584686)
		(mid 186.208579 156.726107)
		(end 186.35 156.784686)
		(width 0.157)
		(layer "In5.Cu")
		(net 657)
	)
	(arc
		(start 186.35 156.784686)
		(mid 186.491421 156.726107)
		(end 186.55 156.584686)
		(width 0.157)
		(layer "In5.Cu")
		(net 657)
	)
	(arc
		(start 179.95 156.784686)
		(mid 180.091421 156.726107)
		(end 180.15 156.584686)
		(width 0.157)
		(layer "In5.Cu")
		(net 657)
	)
	(arc
		(start 185.55 156.784686)
		(mid 185.691421 156.726107)
		(end 185.75 156.584686)
		(width 0.157)
		(layer "In5.Cu")
		(net 657)
	)
	(arc
		(start 187.15 156.784686)
		(mid 187.291421 156.726107)
		(end 187.35 156.584686)
		(width 0.157)
		(layer "In5.Cu")
		(net 657)
	)
	(arc
		(start 186.55 156.2)
		(mid 186.608579 156.058579)
		(end 186.75 156)
		(width 0.157)
		(layer "In5.Cu")
		(net 657)
	)
	(arc
		(start 183.35 156.2)
		(mid 183.408579 156.058579)
		(end 183.55 156)
		(width 0.157)
		(layer "In5.Cu")
		(net 657)
	)
	(arc
		(start 184.15 156.2)
		(mid 184.208579 156.058579)
		(end 184.35 156)
		(width 0.157)
		(layer "In5.Cu")
		(net 657)
	)
	(arc
		(start 182.55 156.2)
		(mid 182.608579 156.058579)
		(end 182.75 156)
		(width 0.157)
		(layer "In5.Cu")
		(net 657)
	)
	(arc
		(start 186.75 156)
		(mid 186.891421 156.058579)
		(end 186.95 156.2)
		(width 0.157)
		(layer "In5.Cu")
		(net 657)
	)
	(arc
		(start 182.35 156.784686)
		(mid 182.491421 156.726107)
		(end 182.55 156.584686)
		(width 0.157)
		(layer "In5.Cu")
		(net 657)
	)
	(arc
		(start 184.35 156)
		(mid 184.491421 156.058579)
		(end 184.55 156.2)
		(width 0.157)
		(layer "In5.Cu")
		(net 657)
	)
	(arc
		(start 181.95 156)
		(mid 182.091421 156.058579)
		(end 182.15 156.2)
		(width 0.157)
		(layer "In5.Cu")
		(net 657)
	)
	(arc
		(start 185.75 156.2)
		(mid 185.808579 156.058579)
		(end 185.95 156)
		(width 0.157)
		(layer "In5.Cu")
		(net 657)
	)
	(arc
		(start 185.35 156.584686)
		(mid 185.408579 156.726107)
		(end 185.55 156.784686)
		(width 0.157)
		(layer "In5.Cu")
		(net 657)
	)
	(arc
		(start 183.95 156.784686)
		(mid 184.091421 156.726107)
		(end 184.15 156.584686)
		(width 0.157)
		(layer "In5.Cu")
		(net 657)
	)
	(arc
		(start 185.95 156)
		(mid 186.091421 156.058579)
		(end 186.15 156.2)
		(width 0.157)
		(layer "In5.Cu")
		(net 657)
	)
	(segment
		(start 171.6 144.56)
		(end 171.6 144)
		(width 0.225)
		(layer "F.Cu")
		(net 658)
	)
	(segment
		(start 191.5 143.5)
		(end 191 144)
		(width 0.256)
		(layer "F.Cu")
		(net 658)
	)
	(segment
		(start 191 144)
		(end 190.97 144)
		(width 0.256)
		(layer "F.Cu")
		(net 658)
	)
	(via
		(at 171.6 144.56)
		(size 0.45)
		(drill 0.2)
		(layers "F.Cu" "B.Cu")
		(net 658)
	)
	(via
		(at 190.97 144)
		(size 0.45)
		(drill 0.2)
		(layers "F.Cu" "B.Cu")
		(net 658)
	)
	(segment
		(start 190.585682 144.674)
		(end 190.418 144.674)
		(width 0.141)
		(layer "In5.Cu")
		(net 658)
	)
	(segment
		(start 183.988 151.828025)
		(end 183.988 150.335975)
		(width 0.141)
		(layer "In5.Cu")
		(net 658)
	)
	(segment
		(start 181.188 151.828025)
		(end 181.188 150.385975)
		(width 0.141)
		(layer "In5.Cu")
		(net 658)
	)
	(segment
		(start 176.943429 145.395805)
		(end 172.20723 145.395805)
		(width 0.141)
		(layer "In5.Cu")
		(net 658)
	)
	(segment
		(start 190.623 143.653)
		(end 190.488376 143.653)
		(width 0.141)
		(layer "In5.Cu")
		(net 658)
	)
	(segment
		(start 190.97 144)
		(end 190.623 143.653)
		(width 0.141)
		(layer "In5.Cu")
		(net 658)
	)
	(segment
		(start 178.167 146.619376)
		(end 176.943429 145.395805)
		(width 0.141)
		(layer "In5.Cu")
		(net 658)
	)
	(segment
		(start 185.388 151.828025)
		(end 185.388 150.335975)
		(width 0.141)
		(layer "In5.Cu")
		(net 658)
	)
	(segment
		(start 190.488376 143.653)
		(end 190.218 143.923376)
		(width 0.141)
		(layer "In5.Cu")
		(net 658)
	)
	(segment
		(start 190.218 143.923376)
		(end 190.218 144.074)
		(width 0.141)
		(layer "In5.Cu")
		(net 658)
	)
	(segment
		(start 186.394 150.385975)
		(end 186.394 151.828025)
		(width 0.141)
		(layer "In5.Cu")
		(net 658)
	)
	(segment
		(start 182.588 151.828025)
		(end 182.588 150.385975)
		(width 0.141)
		(layer "In5.Cu")
		(net 658)
	)
	(segment
		(start 171.847 144.807)
		(end 171.6 144.56)
		(width 0.141)
		(layer "In5.Cu")
		(net 658)
	)
	(segment
		(start 184.994 150.335975)
		(end 184.994 151.828025)
		(width 0.141)
		(layer "In5.Cu")
		(net 658)
	)
	(segment
		(start 190.218 144.874)
		(end 190.218 150.616012)
		(width 0.141)
		(layer "In5.Cu")
		(net 658)
	)
	(segment
		(start 180.291 151.235)
		(end 179.598624 151.235)
		(width 0.141)
		(layer "In5.Cu")
		(net 658)
	)
	(segment
		(start 172.20723 145.395805)
		(end 171.847 145.035575)
		(width 0.141)
		(layer "In5.Cu")
		(net 658)
	)
	(segment
		(start 182.194 150.385975)
		(end 182.194 151.828025)
		(width 0.141)
		(layer "In5.Cu")
		(net 658)
	)
	(segment
		(start 187.794 150.385975)
		(end 187.794 151.828025)
		(width 0.141)
		(layer "In5.Cu")
		(net 658)
	)
	(segment
		(start 183.594 150.335975)
		(end 183.594 151.828025)
		(width 0.141)
		(layer "In5.Cu")
		(net 658)
	)
	(segment
		(start 188.188 150.732)
		(end 188.188 150.385975)
		(width 0.141)
		(layer "In5.Cu")
		(net 658)
	)
	(segment
		(start 180.794 150.385975)
		(end 180.794 150.732)
		(width 0.141)
		(layer "In5.Cu")
		(net 658)
	)
	(segment
		(start 171.847 145.035575)
		(end 171.847 144.807)
		(width 0.141)
		(layer "In5.Cu")
		(net 658)
	)
	(segment
		(start 190.218 150.616012)
		(end 189.599012 151.235)
		(width 0.141)
		(layer "In5.Cu")
		(net 658)
	)
	(segment
		(start 179.598624 151.235)
		(end 178.167 149.803376)
		(width 0.141)
		(layer "In5.Cu")
		(net 658)
	)
	(segment
		(start 178.167 149.803376)
		(end 178.167 146.619376)
		(width 0.141)
		(layer "In5.Cu")
		(net 658)
	)
	(segment
		(start 189.599012 151.235)
		(end 188.691 151.235)
		(width 0.141)
		(layer "In5.Cu")
		(net 658)
	)
	(segment
		(start 190.418 144.274)
		(end 190.585682 144.274)
		(width 0.141)
		(layer "In5.Cu")
		(net 658)
	)
	(segment
		(start 186.788 151.828025)
		(end 186.788 150.385975)
		(width 0.141)
		(layer "In5.Cu")
		(net 658)
	)
	(arc
		(start 182.194 151.828025)
		(mid 182.046675 152.1837)
		(end 181.691 152.331025)
		(width 0.141)
		(layer "In5.Cu")
		(net 658)
	)
	(arc
		(start 190.585682 144.274)
		(mid 190.727103 144.332579)
		(end 190.785682 144.474)
		(width 0.141)
		(layer "In5.Cu")
		(net 658)
	)
	(arc
		(start 180.991 150.188975)
		(mid 180.8517 150.246675)
		(end 180.794 150.385975)
		(width 0.141)
		(layer "In5.Cu")
		(net 658)
	)
	(arc
		(start 183.791 150.138975)
		(mid 183.6517 150.196675)
		(end 183.594 150.335975)
		(width 0.141)
		(layer "In5.Cu")
		(net 658)
	)
	(arc
		(start 182.391 150.188975)
		(mid 182.2517 150.246675)
		(end 182.194 150.385975)
		(width 0.141)
		(layer "In5.Cu")
		(net 658)
	)
	(arc
		(start 188.188 150.385975)
		(mid 188.1303 150.246675)
		(end 187.991 150.188975)
		(width 0.141)
		(layer "In5.Cu")
		(net 658)
	)
	(arc
		(start 190.418 144.674)
		(mid 190.276579 144.732579)
		(end 190.218 144.874)
		(width 0.141)
		(layer "In5.Cu")
		(net 658)
	)
	(arc
		(start 185.891 152.331025)
		(mid 185.535325 152.1837)
		(end 185.388 151.828025)
		(width 0.141)
		(layer "In5.Cu")
		(net 658)
	)
	(arc
		(start 185.191 150.138975)
		(mid 185.0517 150.196675)
		(end 184.994 150.335975)
		(width 0.141)
		(layer "In5.Cu")
		(net 658)
	)
	(arc
		(start 182.588 150.385975)
		(mid 182.5303 150.246675)
		(end 182.391 150.188975)
		(width 0.141)
		(layer "In5.Cu")
		(net 658)
	)
	(arc
		(start 188.691 151.235)
		(mid 188.335325 151.087675)
		(end 188.188 150.732)
		(width 0.141)
		(layer "In5.Cu")
		(net 658)
	)
	(arc
		(start 181.188 150.385975)
		(mid 181.1303 150.246675)
		(end 180.991 150.188975)
		(width 0.141)
		(layer "In5.Cu")
		(net 658)
	)
	(arc
		(start 184.491 152.331025)
		(mid 184.135325 152.1837)
		(end 183.988 151.828025)
		(width 0.141)
		(layer "In5.Cu")
		(net 658)
	)
	(arc
		(start 190.218 144.074)
		(mid 190.276579 144.215421)
		(end 190.418 144.274)
		(width 0.141)
		(layer "In5.Cu")
		(net 658)
	)
	(arc
		(start 186.591 150.188975)
		(mid 186.4517 150.246675)
		(end 186.394 150.385975)
		(width 0.141)
		(layer "In5.Cu")
		(net 658)
	)
	(arc
		(start 184.994 151.828025)
		(mid 184.846675 152.1837)
		(end 184.491 152.331025)
		(width 0.141)
		(layer "In5.Cu")
		(net 658)
	)
	(arc
		(start 185.388 150.335975)
		(mid 185.3303 150.196675)
		(end 185.191 150.138975)
		(width 0.141)
		(layer "In5.Cu")
		(net 658)
	)
	(arc
		(start 180.794 150.732)
		(mid 180.646675 151.087675)
		(end 180.291 151.235)
		(width 0.141)
		(layer "In5.Cu")
		(net 658)
	)
	(arc
		(start 181.691 152.331025)
		(mid 181.335325 152.1837)
		(end 181.188 151.828025)
		(width 0.141)
		(layer "In5.Cu")
		(net 658)
	)
	(arc
		(start 187.291 152.331025)
		(mid 186.935325 152.1837)
		(end 186.788 151.828025)
		(width 0.141)
		(layer "In5.Cu")
		(net 658)
	)
	(arc
		(start 186.788 150.385975)
		(mid 186.7303 150.246675)
		(end 186.591 150.188975)
		(width 0.141)
		(layer "In5.Cu")
		(net 658)
	)
	(arc
		(start 183.988 150.335975)
		(mid 183.9303 150.196675)
		(end 183.791 150.138975)
		(width 0.141)
		(layer "In5.Cu")
		(net 658)
	)
	(arc
		(start 187.794 151.828025)
		(mid 187.646675 152.1837)
		(end 187.291 152.331025)
		(width 0.141)
		(layer "In5.Cu")
		(net 658)
	)
	(arc
		(start 183.594 151.828025)
		(mid 183.446675 152.1837)
		(end 183.091 152.331025)
		(width 0.141)
		(layer "In5.Cu")
		(net 658)
	)
	(arc
		(start 187.991 150.188975)
		(mid 187.8517 150.246675)
		(end 187.794 150.385975)
		(width 0.141)
		(layer "In5.Cu")
		(net 658)
	)
	(arc
		(start 190.785682 144.474)
		(mid 190.727103 144.615421)
		(end 190.585682 144.674)
		(width 0.141)
		(layer "In5.Cu")
		(net 658)
	)
	(arc
		(start 183.091 152.331025)
		(mid 182.735325 152.1837)
		(end 182.588 151.828025)
		(width 0.141)
		(layer "In5.Cu")
		(net 658)
	)
	(arc
		(start 186.394 151.828025)
		(mid 186.246675 152.1837)
		(end 185.891 152.331025)
		(width 0.141)
		(layer "In5.Cu")
		(net 658)
	)
	(segment
		(start 192.5 143.5)
		(end 192.012347 143.987653)
		(width 0.256)
		(layer "F.Cu")
		(net 659)
	)
	(segment
		(start 170.8 148)
		(end 171.2 147.6)
		(width 0.256)
		(layer "F.Cu")
		(net 659)
	)
	(segment
		(start 192.012347 143.987653)
		(end 192.012347 144.000103)
		(width 0.256)
		(layer "F.Cu")
		(net 659)
	)
	(via
		(at 192.012347 144.000103)
		(size 0.45)
		(drill 0.2)
		(layers "F.Cu" "B.Cu")
		(net 659)
	)
	(via
		(at 171.2 147.6)
		(size 0.45)
		(drill 0.2)
		(layers "F.Cu" "B.Cu")
		(net 659)
	)
	(segment
		(start 188.35 154)
		(end 188.35 154.397431)
		(width 0.157)
		(layer "In5.Cu")
		(net 659)
	)
	(segment
		(start 187.95 154.397431)
		(end 187.95 154)
		(width 0.157)
		(layer "In5.Cu")
		(net 659)
	)
	(segment
		(start 192.012347 145.637651)
		(end 191.475 146.174998)
		(width 0.157)
		(layer "In5.Cu")
		(net 659)
	)
	(segment
		(start 184.75 154.397431)
		(end 184.75 154)
		(width 0.157)
		(layer "In5.Cu")
		(net 659)
	)
	(segment
		(start 178.3 153.8)
		(end 176.849999 152.349999)
		(width 0.157)
		(layer "In5.Cu")
		(net 659)
	)
	(segment
		(start 179.15 154.397431)
		(end 179.15 154)
		(width 0.157)
		(layer "In5.Cu")
		(net 659)
	)
	(segment
		(start 187.55 154)
		(end 187.55 154.397431)
		(width 0.157)
		(layer "In5.Cu")
		(net 659)
	)
	(segment
		(start 181.55 154.397431)
		(end 181.55 154)
		(width 0.157)
		(layer "In5.Cu")
		(net 659)
	)
	(segment
		(start 185.55 154.397431)
		(end 185.55 154)
		(width 0.157)
		(layer "In5.Cu")
		(net 659)
	)
	(segment
		(start 180.75 154.397431)
		(end 180.75 154)
		(width 0.157)
		(layer "In5.Cu")
		(net 659)
	)
	(segment
		(start 182.35 154.397431)
		(end 182.35 154)
		(width 0.157)
		(layer "In5.Cu")
		(net 659)
	)
	(segment
		(start 172.750002 146.05)
		(end 171.2 147.6)
		(width 0.157)
		(layer "In5.Cu")
		(net 659)
	)
	(segment
		(start 185.15 154)
		(end 185.15 154.397431)
		(width 0.157)
		(layer "In5.Cu")
		(net 659)
	)
	(segment
		(start 186.75 154)
		(end 186.75 154.397431)
		(width 0.157)
		(layer "In5.Cu")
		(net 659)
	)
	(segment
		(start 179.95 154.397431)
		(end 179.95 154)
		(width 0.157)
		(layer "In5.Cu")
		(net 659)
	)
	(segment
		(start 176.849999 147.849999)
		(end 175.05 146.05)
		(width 0.157)
		(layer "In5.Cu")
		(net 659)
	)
	(segment
		(start 184.35 154)
		(end 184.35 154.397431)
		(width 0.157)
		(layer "In5.Cu")
		(net 659)
	)
	(segment
		(start 181.15 154)
		(end 181.15 154.397431)
		(width 0.157)
		(layer "In5.Cu")
		(net 659)
	)
	(segment
		(start 183.95 154.397431)
		(end 183.95 154)
		(width 0.157)
		(layer "In5.Cu")
		(net 659)
	)
	(segment
		(start 185.95 154)
		(end 185.95 154.397431)
		(width 0.157)
		(layer "In5.Cu")
		(net 659)
	)
	(segment
		(start 187.15 154.397431)
		(end 187.15 154)
		(width 0.157)
		(layer "In5.Cu")
		(net 659)
	)
	(segment
		(start 178.95 153.8)
		(end 178.3 153.8)
		(width 0.157)
		(layer "In5.Cu")
		(net 659)
	)
	(segment
		(start 183.55 154)
		(end 183.55 154.397431)
		(width 0.157)
		(layer "In5.Cu")
		(net 659)
	)
	(segment
		(start 191.475 146.174998)
		(end 191.475 152.775)
		(width 0.157)
		(layer "In5.Cu")
		(net 659)
	)
	(segment
		(start 190.45 153.8)
		(end 188.55 153.8)
		(width 0.157)
		(layer "In5.Cu")
		(net 659)
	)
	(segment
		(start 182.75 154)
		(end 182.75 154.397431)
		(width 0.157)
		(layer "In5.Cu")
		(net 659)
	)
	(segment
		(start 183.15 154.397431)
		(end 183.15 154)
		(width 0.157)
		(layer "In5.Cu")
		(net 659)
	)
	(segment
		(start 179.55 154)
		(end 179.55 154.397431)
		(width 0.157)
		(layer "In5.Cu")
		(net 659)
	)
	(segment
		(start 180.35 154)
		(end 180.35 154.397431)
		(width 0.157)
		(layer "In5.Cu")
		(net 659)
	)
	(segment
		(start 192.012347 144.000103)
		(end 192.012347 145.637651)
		(width 0.157)
		(layer "In5.Cu")
		(net 659)
	)
	(segment
		(start 176.849999 152.349999)
		(end 176.849999 147.849999)
		(width 0.157)
		(layer "In5.Cu")
		(net 659)
	)
	(segment
		(start 186.35 154.397431)
		(end 186.35 154)
		(width 0.157)
		(layer "In5.Cu")
		(net 659)
	)
	(segment
		(start 181.95 154)
		(end 181.95 154.397431)
		(width 0.157)
		(layer "In5.Cu")
		(net 659)
	)
	(segment
		(start 191.475 152.775)
		(end 190.45 153.8)
		(width 0.157)
		(layer "In5.Cu")
		(net 659)
	)
	(segment
		(start 175.05 146.05)
		(end 172.750002 146.05)
		(width 0.157)
		(layer "In5.Cu")
		(net 659)
	)
	(arc
		(start 179.95 154)
		(mid 179.891421 153.858579)
		(end 179.75 153.8)
		(width 0.157)
		(layer "In5.Cu")
		(net 659)
	)
	(arc
		(start 182.95 153.8)
		(mid 182.808579 153.858579)
		(end 182.75 154)
		(width 0.157)
		(layer "In5.Cu")
		(net 659)
	)
	(arc
		(start 181.95 154.397431)
		(mid 181.891421 154.538852)
		(end 181.75 154.597431)
		(width 0.157)
		(layer "In5.Cu")
		(net 659)
	)
	(arc
		(start 186.35 154)
		(mid 186.291421 153.858579)
		(end 186.15 153.8)
		(width 0.157)
		(layer "In5.Cu")
		(net 659)
	)
	(arc
		(start 185.95 154.397431)
		(mid 185.891421 154.538852)
		(end 185.75 154.597431)
		(width 0.157)
		(layer "In5.Cu")
		(net 659)
	)
	(arc
		(start 185.75 154.597431)
		(mid 185.608579 154.538852)
		(end 185.55 154.397431)
		(width 0.157)
		(layer "In5.Cu")
		(net 659)
	)
	(arc
		(start 179.35 154.597431)
		(mid 179.208579 154.538852)
		(end 179.15 154.397431)
		(width 0.157)
		(layer "In5.Cu")
		(net 659)
	)
	(arc
		(start 180.75 154)
		(mid 180.691421 153.858579)
		(end 180.55 153.8)
		(width 0.157)
		(layer "In5.Cu")
		(net 659)
	)
	(arc
		(start 180.15 154.597431)
		(mid 180.008579 154.538852)
		(end 179.95 154.397431)
		(width 0.157)
		(layer "In5.Cu")
		(net 659)
	)
	(arc
		(start 183.95 154)
		(mid 183.891421 153.858579)
		(end 183.75 153.8)
		(width 0.157)
		(layer "In5.Cu")
		(net 659)
	)
	(arc
		(start 187.35 154.597431)
		(mid 187.208579 154.538852)
		(end 187.15 154.397431)
		(width 0.157)
		(layer "In5.Cu")
		(net 659)
	)
	(arc
		(start 180.35 154.397431)
		(mid 180.291421 154.538852)
		(end 180.15 154.597431)
		(width 0.157)
		(layer "In5.Cu")
		(net 659)
	)
	(arc
		(start 183.55 154.397431)
		(mid 183.491421 154.538852)
		(end 183.35 154.597431)
		(width 0.157)
		(layer "In5.Cu")
		(net 659)
	)
	(arc
		(start 181.15 154.397431)
		(mid 181.091421 154.538852)
		(end 180.95 154.597431)
		(width 0.157)
		(layer "In5.Cu")
		(net 659)
	)
	(arc
		(start 185.15 154.397431)
		(mid 185.091421 154.538852)
		(end 184.95 154.597431)
		(width 0.157)
		(layer "In5.Cu")
		(net 659)
	)
	(arc
		(start 184.75 154)
		(mid 184.691421 153.858579)
		(end 184.55 153.8)
		(width 0.157)
		(layer "In5.Cu")
		(net 659)
	)
	(arc
		(start 184.95 154.597431)
		(mid 184.808579 154.538852)
		(end 184.75 154.397431)
		(width 0.157)
		(layer "In5.Cu")
		(net 659)
	)
	(arc
		(start 185.35 153.8)
		(mid 185.208579 153.858579)
		(end 185.15 154)
		(width 0.157)
		(layer "In5.Cu")
		(net 659)
	)
	(arc
		(start 186.55 154.597431)
		(mid 186.408579 154.538852)
		(end 186.35 154.397431)
		(width 0.157)
		(layer "In5.Cu")
		(net 659)
	)
	(arc
		(start 181.75 154.597431)
		(mid 181.608579 154.538852)
		(end 181.55 154.397431)
		(width 0.157)
		(layer "In5.Cu")
		(net 659)
	)
	(arc
		(start 182.75 154.397431)
		(mid 182.691421 154.538852)
		(end 182.55 154.597431)
		(width 0.157)
		(layer "In5.Cu")
		(net 659)
	)
	(arc
		(start 186.15 153.8)
		(mid 186.008579 153.858579)
		(end 185.95 154)
		(width 0.157)
		(layer "In5.Cu")
		(net 659)
	)
	(arc
		(start 179.75 153.8)
		(mid 179.608579 153.858579)
		(end 179.55 154)
		(width 0.157)
		(layer "In5.Cu")
		(net 659)
	)
	(arc
		(start 182.55 154.597431)
		(mid 182.408579 154.538852)
		(end 182.35 154.397431)
		(width 0.157)
		(layer "In5.Cu")
		(net 659)
	)
	(arc
		(start 187.15 154)
		(mid 187.091421 153.858579)
		(end 186.95 153.8)
		(width 0.157)
		(layer "In5.Cu")
		(net 659)
	)
	(arc
		(start 183.15 154)
		(mid 183.091421 153.858579)
		(end 182.95 153.8)
		(width 0.157)
		(layer "In5.Cu")
		(net 659)
	)
	(arc
		(start 185.55 154)
		(mid 185.491421 153.858579)
		(end 185.35 153.8)
		(width 0.157)
		(layer "In5.Cu")
		(net 659)
	)
	(arc
		(start 179.15 154)
		(mid 179.091421 153.858579)
		(end 178.95 153.8)
		(width 0.157)
		(layer "In5.Cu")
		(net 659)
	)
	(arc
		(start 180.95 154.597431)
		(mid 180.808579 154.538852)
		(end 180.75 154.397431)
		(width 0.157)
		(layer "In5.Cu")
		(net 659)
	)
	(arc
		(start 188.55 153.8)
		(mid 188.408579 153.858579)
		(end 188.35 154)
		(width 0.157)
		(layer "In5.Cu")
		(net 659)
	)
	(arc
		(start 184.15 154.597431)
		(mid 184.008579 154.538852)
		(end 183.95 154.397431)
		(width 0.157)
		(layer "In5.Cu")
		(net 659)
	)
	(arc
		(start 186.95 153.8)
		(mid 186.808579 153.858579)
		(end 186.75 154)
		(width 0.157)
		(layer "In5.Cu")
		(net 659)
	)
	(arc
		(start 186.75 154.397431)
		(mid 186.691421 154.538852)
		(end 186.55 154.597431)
		(width 0.157)
		(layer "In5.Cu")
		(net 659)
	)
	(arc
		(start 187.75 153.8)
		(mid 187.608579 153.858579)
		(end 187.55 154)
		(width 0.157)
		(layer "In5.Cu")
		(net 659)
	)
	(arc
		(start 184.35 154.397431)
		(mid 184.291421 154.538852)
		(end 184.15 154.597431)
		(width 0.157)
		(layer "In5.Cu")
		(net 659)
	)
	(arc
		(start 187.55 154.397431)
		(mid 187.491421 154.538852)
		(end 187.35 154.597431)
		(width 0.157)
		(layer "In5.Cu")
		(net 659)
	)
	(arc
		(start 187.95 154)
		(mid 187.891421 153.858579)
		(end 187.75 153.8)
		(width 0.157)
		(layer "In5.Cu")
		(net 659)
	)
	(arc
		(start 181.35 153.8)
		(mid 181.208579 153.858579)
		(end 181.15 154)
		(width 0.157)
		(layer "In5.Cu")
		(net 659)
	)
	(arc
		(start 182.15 153.8)
		(mid 182.008579 153.858579)
		(end 181.95 154)
		(width 0.157)
		(layer "In5.Cu")
		(net 659)
	)
	(arc
		(start 180.55 153.8)
		(mid 180.408579 153.858579)
		(end 180.35 154)
		(width 0.157)
		(layer "In5.Cu")
		(net 659)
	)
	(arc
		(start 182.35 154)
		(mid 182.291421 153.858579)
		(end 182.15 153.8)
		(width 0.157)
		(layer "In5.Cu")
		(net 659)
	)
	(arc
		(start 183.75 153.8)
		(mid 183.608579 153.858579)
		(end 183.55 154)
		(width 0.157)
		(layer "In5.Cu")
		(net 659)
	)
	(arc
		(start 183.35 154.597431)
		(mid 183.208579 154.538852)
		(end 183.15 154.397431)
		(width 0.157)
		(layer "In5.Cu")
		(net 659)
	)
	(arc
		(start 179.55 154.397431)
		(mid 179.491421 154.538852)
		(end 179.35 154.597431)
		(width 0.157)
		(layer "In5.Cu")
		(net 659)
	)
	(arc
		(start 184.55 153.8)
		(mid 184.408579 153.858579)
		(end 184.35 154)
		(width 0.157)
		(layer "In5.Cu")
		(net 659)
	)
	(arc
		(start 188.35 154.397431)
		(mid 188.291421 154.538852)
		(end 188.15 154.597431)
		(width 0.157)
		(layer "In5.Cu")
		(net 659)
	)
	(arc
		(start 188.15 154.597431)
		(mid 188.008579 154.538852)
		(end 187.95 154.397431)
		(width 0.157)
		(layer "In5.Cu")
		(net 659)
	)
	(arc
		(start 181.55 154)
		(mid 181.491421 153.858579)
		(end 181.35 153.8)
		(width 0.157)
		(layer "In5.Cu")
		(net 659)
	)
	(segment
		(start 171.599999 143.200003)
		(end 171.600003 143.200003)
		(width 0.256)
		(layer "F.Cu")
		(net 660)
	)
	(segment
		(start 171.600003 143.200003)
		(end 172 143.6)
		(width 0.256)
		(layer "F.Cu")
		(net 660)
	)
	(segment
		(start 188.5 144.5)
		(end 188 145)
		(width 0.256)
		(layer "F.Cu")
		(net 660)
	)
	(via
		(at 188 145)
		(size 0.45)
		(drill 0.2)
		(layers "F.Cu" "B.Cu")
		(net 660)
	)
	(via
		(at 172 143.6)
		(size 0.45)
		(drill 0.2)
		(layers "F.Cu" "B.Cu")
		(net 660)
	)
	(segment
		(start 184.275 147.575)
		(end 184.275 146.513227)
		(width 0.157)
		(layer "In5.Cu")
		(net 660)
	)
	(segment
		(start 181.475 146.513227)
		(end 181.475 147.575)
		(width 0.157)
		(layer "In5.Cu")
		(net 660)
	)
	(segment
		(start 185.475 146.513227)
		(end 185.475 147.575)
		(width 0.157)
		(layer "In5.Cu")
		(net 660)
	)
	(segment
		(start 179.525 145.375)
		(end 179.525 147.5)
		(width 0.157)
		(layer "In5.Cu")
		(net 660)
	)
	(segment
		(start 174.05 143.8)
		(end 177.95 143.8)
		(width 0.157)
		(layer "In5.Cu")
		(net 660)
	)
	(segment
		(start 186.275 146.513227)
		(end 186.275 147.575)
		(width 0.157)
		(layer "In5.Cu")
		(net 660)
	)
	(segment
		(start 187.075 146.513227)
		(end 187.075 147.575)
		(width 0.157)
		(layer "In5.Cu")
		(net 660)
	)
	(segment
		(start 187.475 147.575)
		(end 187.475 146.513227)
		(width 0.157)
		(layer "In5.Cu")
		(net 660)
	)
	(segment
		(start 186.675 147.575)
		(end 186.675 146.513227)
		(width 0.157)
		(layer "In5.Cu")
		(net 660)
	)
	(segment
		(start 185.875 147.575)
		(end 185.875 146.513227)
		(width 0.157)
		(layer "In5.Cu")
		(net 660)
	)
	(segment
		(start 188.575 147.5)
		(end 188.575 145.575)
		(width 0.157)
		(layer "In5.Cu")
		(net 660)
	)
	(segment
		(start 177.95 143.8)
		(end 179.525 145.375)
		(width 0.157)
		(layer "In5.Cu")
		(net 660)
	)
	(segment
		(start 185.075 147.575)
		(end 185.075 146.513227)
		(width 0.157)
		(layer "In5.Cu")
		(net 660)
	)
	(segment
		(start 187.875 146.513227)
		(end 187.875 147.575)
		(width 0.157)
		(layer "In5.Cu")
		(net 660)
	)
	(segment
		(start 179.8 147.775)
		(end 180.075 147.775)
		(width 0.157)
		(layer "In5.Cu")
		(net 660)
	)
	(segment
		(start 183.875 146.513227)
		(end 183.875 147.575)
		(width 0.157)
		(layer "In5.Cu")
		(net 660)
	)
	(segment
		(start 182.675 147.575)
		(end 182.675 146.513227)
		(width 0.157)
		(layer "In5.Cu")
		(net 660)
	)
	(segment
		(start 180.275 147.575)
		(end 180.275 146.513227)
		(width 0.157)
		(layer "In5.Cu")
		(net 660)
	)
	(segment
		(start 183.075 146.513227)
		(end 183.075 147.575)
		(width 0.157)
		(layer "In5.Cu")
		(net 660)
	)
	(segment
		(start 172.675 142.925)
		(end 173.175 142.925)
		(width 0.157)
		(layer "In5.Cu")
		(net 660)
	)
	(segment
		(start 173.175 142.925)
		(end 174.05 143.8)
		(width 0.157)
		(layer "In5.Cu")
		(net 660)
	)
	(segment
		(start 180.675 146.513227)
		(end 180.675 147.575)
		(width 0.157)
		(layer "In5.Cu")
		(net 660)
	)
	(segment
		(start 188.125 147.775)
		(end 188.3 147.775)
		(width 0.157)
		(layer "In5.Cu")
		(net 660)
	)
	(segment
		(start 182.275 146.513227)
		(end 182.275 147.575)
		(width 0.157)
		(layer "In5.Cu")
		(net 660)
	)
	(segment
		(start 184.675 146.513227)
		(end 184.675 147.575)
		(width 0.157)
		(layer "In5.Cu")
		(net 660)
	)
	(segment
		(start 179.525 147.5)
		(end 179.8 147.775)
		(width 0.157)
		(layer "In5.Cu")
		(net 660)
	)
	(segment
		(start 188.075 147.775)
		(end 188.125 147.775)
		(width 0.157)
		(layer "In5.Cu")
		(net 660)
	)
	(segment
		(start 188.3 147.775)
		(end 188.575 147.5)
		(width 0.157)
		(layer "In5.Cu")
		(net 660)
	)
	(segment
		(start 172 143.6)
		(end 172.675 142.925)
		(width 0.157)
		(layer "In5.Cu")
		(net 660)
	)
	(segment
		(start 183.475 147.575)
		(end 183.475 146.513227)
		(width 0.157)
		(layer "In5.Cu")
		(net 660)
	)
	(segment
		(start 181.875 147.575)
		(end 181.875 146.513227)
		(width 0.157)
		(layer "In5.Cu")
		(net 660)
	)
	(segment
		(start 188.575 145.575)
		(end 188 145)
		(width 0.157)
		(layer "In5.Cu")
		(net 660)
	)
	(segment
		(start 181.075 147.575)
		(end 181.075 146.513227)
		(width 0.157)
		(layer "In5.Cu")
		(net 660)
	)
	(arc
		(start 182.275 147.575)
		(mid 182.333579 147.716421)
		(end 182.475 147.775)
		(width 0.157)
		(layer "In5.Cu")
		(net 660)
	)
	(arc
		(start 187.875 147.575)
		(mid 187.933579 147.716421)
		(end 188.075 147.775)
		(width 0.157)
		(layer "In5.Cu")
		(net 660)
	)
	(arc
		(start 183.675 146.313227)
		(mid 183.816421 146.371806)
		(end 183.875 146.513227)
		(width 0.157)
		(layer "In5.Cu")
		(net 660)
	)
	(arc
		(start 186.875 146.313227)
		(mid 187.016421 146.371806)
		(end 187.075 146.513227)
		(width 0.157)
		(layer "In5.Cu")
		(net 660)
	)
	(arc
		(start 185.275 146.313227)
		(mid 185.416421 146.371806)
		(end 185.475 146.513227)
		(width 0.157)
		(layer "In5.Cu")
		(net 660)
	)
	(arc
		(start 183.275 147.775)
		(mid 183.416421 147.716421)
		(end 183.475 147.575)
		(width 0.157)
		(layer "In5.Cu")
		(net 660)
	)
	(arc
		(start 181.675 147.775)
		(mid 181.816421 147.716421)
		(end 181.875 147.575)
		(width 0.157)
		(layer "In5.Cu")
		(net 660)
	)
	(arc
		(start 185.675 147.775)
		(mid 185.816421 147.716421)
		(end 185.875 147.575)
		(width 0.157)
		(layer "In5.Cu")
		(net 660)
	)
	(arc
		(start 184.075 147.775)
		(mid 184.216421 147.716421)
		(end 184.275 147.575)
		(width 0.157)
		(layer "In5.Cu")
		(net 660)
	)
	(arc
		(start 186.275 147.575)
		(mid 186.333579 147.716421)
		(end 186.475 147.775)
		(width 0.157)
		(layer "In5.Cu")
		(net 660)
	)
	(arc
		(start 180.475 146.313227)
		(mid 180.616421 146.371806)
		(end 180.675 146.513227)
		(width 0.157)
		(layer "In5.Cu")
		(net 660)
	)
	(arc
		(start 183.875 147.575)
		(mid 183.933579 147.716421)
		(end 184.075 147.775)
		(width 0.157)
		(layer "In5.Cu")
		(net 660)
	)
	(arc
		(start 181.075 146.513227)
		(mid 181.133579 146.371806)
		(end 181.275 146.313227)
		(width 0.157)
		(layer "In5.Cu")
		(net 660)
	)
	(arc
		(start 180.875 147.775)
		(mid 181.016421 147.716421)
		(end 181.075 147.575)
		(width 0.157)
		(layer "In5.Cu")
		(net 660)
	)
	(arc
		(start 184.475 146.313227)
		(mid 184.616421 146.371806)
		(end 184.675 146.513227)
		(width 0.157)
		(layer "In5.Cu")
		(net 660)
	)
	(arc
		(start 182.075 146.313227)
		(mid 182.216421 146.371806)
		(end 182.275 146.513227)
		(width 0.157)
		(layer "In5.Cu")
		(net 660)
	)
	(arc
		(start 187.075 147.575)
		(mid 187.133579 147.716421)
		(end 187.275 147.775)
		(width 0.157)
		(layer "In5.Cu")
		(net 660)
	)
	(arc
		(start 186.075 146.313227)
		(mid 186.216421 146.371806)
		(end 186.275 146.513227)
		(width 0.157)
		(layer "In5.Cu")
		(net 660)
	)
	(arc
		(start 180.075 147.775)
		(mid 180.216421 147.716421)
		(end 180.275 147.575)
		(width 0.157)
		(layer "In5.Cu")
		(net 660)
	)
	(arc
		(start 187.475 146.513227)
		(mid 187.533579 146.371806)
		(end 187.675 146.313227)
		(width 0.157)
		(layer "In5.Cu")
		(net 660)
	)
	(arc
		(start 184.275 146.513227)
		(mid 184.333579 146.371806)
		(end 184.475 146.313227)
		(width 0.157)
		(layer "In5.Cu")
		(net 660)
	)
	(arc
		(start 185.475 147.575)
		(mid 185.533579 147.716421)
		(end 185.675 147.775)
		(width 0.157)
		(layer "In5.Cu")
		(net 660)
	)
	(arc
		(start 187.675 146.313227)
		(mid 187.816421 146.371806)
		(end 187.875 146.513227)
		(width 0.157)
		(layer "In5.Cu")
		(net 660)
	)
	(arc
		(start 187.275 147.775)
		(mid 187.416421 147.716421)
		(end 187.475 147.575)
		(width 0.157)
		(layer "In5.Cu")
		(net 660)
	)
	(arc
		(start 182.675 146.513227)
		(mid 182.733579 146.371806)
		(end 182.875 146.313227)
		(width 0.157)
		(layer "In5.Cu")
		(net 660)
	)
	(arc
		(start 181.275 146.313227)
		(mid 181.416421 146.371806)
		(end 181.475 146.513227)
		(width 0.157)
		(layer "In5.Cu")
		(net 660)
	)
	(arc
		(start 182.475 147.775)
		(mid 182.616421 147.716421)
		(end 182.675 147.575)
		(width 0.157)
		(layer "In5.Cu")
		(net 660)
	)
	(arc
		(start 184.675 147.575)
		(mid 184.733579 147.716421)
		(end 184.875 147.775)
		(width 0.157)
		(layer "In5.Cu")
		(net 660)
	)
	(arc
		(start 181.875 146.513227)
		(mid 181.933579 146.371806)
		(end 182.075 146.313227)
		(width 0.157)
		(layer "In5.Cu")
		(net 660)
	)
	(arc
		(start 180.675 147.575)
		(mid 180.733579 147.716421)
		(end 180.875 147.775)
		(width 0.157)
		(layer "In5.Cu")
		(net 660)
	)
	(arc
		(start 186.675 146.513227)
		(mid 186.733579 146.371806)
		(end 186.875 146.313227)
		(width 0.157)
		(layer "In5.Cu")
		(net 660)
	)
	(arc
		(start 181.475 147.575)
		(mid 181.533579 147.716421)
		(end 181.675 147.775)
		(width 0.157)
		(layer "In5.Cu")
		(net 660)
	)
	(arc
		(start 186.475 147.775)
		(mid 186.616421 147.716421)
		(end 186.675 147.575)
		(width 0.157)
		(layer "In5.Cu")
		(net 660)
	)
	(arc
		(start 182.875 146.313227)
		(mid 183.016421 146.371806)
		(end 183.075 146.513227)
		(width 0.157)
		(layer "In5.Cu")
		(net 660)
	)
	(arc
		(start 180.275 146.513227)
		(mid 180.333579 146.371806)
		(end 180.475 146.313227)
		(width 0.157)
		(layer "In5.Cu")
		(net 660)
	)
	(arc
		(start 184.875 147.775)
		(mid 185.016421 147.716421)
		(end 185.075 147.575)
		(width 0.157)
		(layer "In5.Cu")
		(net 660)
	)
	(arc
		(start 183.075 147.575)
		(mid 183.133579 147.716421)
		(end 183.275 147.775)
		(width 0.157)
		(layer "In5.Cu")
		(net 660)
	)
	(arc
		(start 185.075 146.513227)
		(mid 185.133579 146.371806)
		(end 185.275 146.313227)
		(width 0.157)
		(layer "In5.Cu")
		(net 660)
	)
	(arc
		(start 183.475 146.513227)
		(mid 183.533579 146.371806)
		(end 183.675 146.313227)
		(width 0.157)
		(layer "In5.Cu")
		(net 660)
	)
	(arc
		(start 185.875 146.513227)
		(mid 185.933579 146.371806)
		(end 186.075 146.313227)
		(width 0.157)
		(layer "In5.Cu")
		(net 660)
	)
	(segment
		(start 189.5 144.5)
		(end 189 145)
		(width 0.256)
		(layer "F.Cu")
		(net 661)
	)
	(segment
		(start 189 145)
		(end 189 145.04)
		(width 0.256)
		(layer "F.Cu")
		(net 661)
	)
	(segment
		(start 173.6 144.4)
		(end 173.2 144)
		(width 0.256)
		(layer "F.Cu")
		(net 661)
	)
	(via
		(at 189 145.04)
		(size 0.45)
		(drill 0.2)
		(layers "F.Cu" "B.Cu")
		(net 661)
	)
	(via
		(at 173.6 144.4)
		(size 0.45)
		(drill 0.2)
		(layers "F.Cu" "B.Cu")
		(net 661)
	)
	(segment
		(start 180.125 149.55)
		(end 180.075 149.55)
		(width 0.157)
		(layer "In5.Cu")
		(net 661)
	)
	(segment
		(start 185.525 149.35)
		(end 185.525 148.265723)
		(width 0.157)
		(layer "In5.Cu")
		(net 661)
	)
	(segment
		(start 180.325 148.265723)
		(end 180.325 149.35)
		(width 0.157)
		(layer "In5.Cu")
		(net 661)
	)
	(segment
		(start 184.725 149.35)
		(end 184.725 148.265723)
		(width 0.157)
		(layer "In5.Cu")
		(net 661)
	)
	(segment
		(start 186.325 149.35)
		(end 186.325 148.265723)
		(width 0.157)
		(layer "In5.Cu")
		(net 661)
	)
	(segment
		(start 189 145.04)
		(end 189 149.1)
		(width 0.157)
		(layer "In5.Cu")
		(net 661)
	)
	(segment
		(start 184.325 148.265723)
		(end 184.325 149.35)
		(width 0.157)
		(layer "In5.Cu")
		(net 661)
	)
	(segment
		(start 177.4 144.4)
		(end 173.6 144.4)
		(width 0.157)
		(layer "In5.Cu")
		(net 661)
	)
	(segment
		(start 185.925 148.265723)
		(end 185.925 149.35)
		(width 0.157)
		(layer "In5.Cu")
		(net 661)
	)
	(segment
		(start 187.125 149.35)
		(end 187.125 148.265723)
		(width 0.157)
		(layer "In5.Cu")
		(net 661)
	)
	(segment
		(start 181.525 149.35)
		(end 181.525 148.265723)
		(width 0.157)
		(layer "In5.Cu")
		(net 661)
	)
	(segment
		(start 187.525 148.265723)
		(end 187.525 149.35)
		(width 0.157)
		(layer "In5.Cu")
		(net 661)
	)
	(segment
		(start 183.925 149.35)
		(end 183.925 148.265723)
		(width 0.157)
		(layer "In5.Cu")
		(net 661)
	)
	(segment
		(start 179.1 149.075)
		(end 179.1 146.1)
		(width 0.157)
		(layer "In5.Cu")
		(net 661)
	)
	(segment
		(start 182.725 148.265723)
		(end 182.725 149.35)
		(width 0.157)
		(layer "In5.Cu")
		(net 661)
	)
	(segment
		(start 187.925 149.35)
		(end 187.925 148.265723)
		(width 0.157)
		(layer "In5.Cu")
		(net 661)
	)
	(segment
		(start 185.125 148.265723)
		(end 185.125 149.35)
		(width 0.157)
		(layer "In5.Cu")
		(net 661)
	)
	(segment
		(start 183.525 148.265723)
		(end 183.525 149.35)
		(width 0.157)
		(layer "In5.Cu")
		(net 661)
	)
	(segment
		(start 182.325 149.35)
		(end 182.325 148.265723)
		(width 0.157)
		(layer "In5.Cu")
		(net 661)
	)
	(segment
		(start 180.075 149.55)
		(end 179.575 149.55)
		(width 0.157)
		(layer "In5.Cu")
		(net 661)
	)
	(segment
		(start 181.125 148.265723)
		(end 181.125 149.35)
		(width 0.157)
		(layer "In5.Cu")
		(net 661)
	)
	(segment
		(start 188.55 149.55)
		(end 188.125 149.55)
		(width 0.157)
		(layer "In5.Cu")
		(net 661)
	)
	(segment
		(start 180.725 149.35)
		(end 180.725 148.265723)
		(width 0.157)
		(layer "In5.Cu")
		(net 661)
	)
	(segment
		(start 179.575 149.55)
		(end 179.1 149.075)
		(width 0.157)
		(layer "In5.Cu")
		(net 661)
	)
	(segment
		(start 181.925 148.265723)
		(end 181.925 149.35)
		(width 0.157)
		(layer "In5.Cu")
		(net 661)
	)
	(segment
		(start 186.725 148.265723)
		(end 186.725 149.35)
		(width 0.157)
		(layer "In5.Cu")
		(net 661)
	)
	(segment
		(start 189 149.1)
		(end 188.55 149.55)
		(width 0.157)
		(layer "In5.Cu")
		(net 661)
	)
	(segment
		(start 183.125 149.35)
		(end 183.125 148.265723)
		(width 0.157)
		(layer "In5.Cu")
		(net 661)
	)
	(segment
		(start 179.1 146.1)
		(end 177.4 144.4)
		(width 0.157)
		(layer "In5.Cu")
		(net 661)
	)
	(arc
		(start 182.325 148.265723)
		(mid 182.266421 148.124302)
		(end 182.125 148.065723)
		(width 0.157)
		(layer "In5.Cu")
		(net 661)
	)
	(arc
		(start 182.925 148.065723)
		(mid 182.783579 148.124302)
		(end 182.725 148.265723)
		(width 0.157)
		(layer "In5.Cu")
		(net 661)
	)
	(arc
		(start 181.725 149.55)
		(mid 181.583579 149.491421)
		(end 181.525 149.35)
		(width 0.157)
		(layer "In5.Cu")
		(net 661)
	)
	(arc
		(start 186.925 148.065723)
		(mid 186.783579 148.124302)
		(end 186.725 148.265723)
		(width 0.157)
		(layer "In5.Cu")
		(net 661)
	)
	(arc
		(start 182.125 148.065723)
		(mid 181.983579 148.124302)
		(end 181.925 148.265723)
		(width 0.157)
		(layer "In5.Cu")
		(net 661)
	)
	(arc
		(start 180.725 148.265723)
		(mid 180.666421 148.124302)
		(end 180.525 148.065723)
		(width 0.157)
		(layer "In5.Cu")
		(net 661)
	)
	(arc
		(start 186.525 149.55)
		(mid 186.383579 149.491421)
		(end 186.325 149.35)
		(width 0.157)
		(layer "In5.Cu")
		(net 661)
	)
	(arc
		(start 187.125 148.265723)
		(mid 187.066421 148.124302)
		(end 186.925 148.065723)
		(width 0.157)
		(layer "In5.Cu")
		(net 661)
	)
	(arc
		(start 184.125 149.55)
		(mid 183.983579 149.491421)
		(end 183.925 149.35)
		(width 0.157)
		(layer "In5.Cu")
		(net 661)
	)
	(arc
		(start 183.125 148.265723)
		(mid 183.066421 148.124302)
		(end 182.925 148.065723)
		(width 0.157)
		(layer "In5.Cu")
		(net 661)
	)
	(arc
		(start 182.525 149.55)
		(mid 182.383579 149.491421)
		(end 182.325 149.35)
		(width 0.157)
		(layer "In5.Cu")
		(net 661)
	)
	(arc
		(start 185.725 149.55)
		(mid 185.583579 149.491421)
		(end 185.525 149.35)
		(width 0.157)
		(layer "In5.Cu")
		(net 661)
	)
	(arc
		(start 184.525 148.065723)
		(mid 184.383579 148.124302)
		(end 184.325 148.265723)
		(width 0.157)
		(layer "In5.Cu")
		(net 661)
	)
	(arc
		(start 184.925 149.55)
		(mid 184.783579 149.491421)
		(end 184.725 149.35)
		(width 0.157)
		(layer "In5.Cu")
		(net 661)
	)
	(arc
		(start 187.925 148.265723)
		(mid 187.866421 148.124302)
		(end 187.725 148.065723)
		(width 0.157)
		(layer "In5.Cu")
		(net 661)
	)
	(arc
		(start 181.325 148.065723)
		(mid 181.183579 148.124302)
		(end 181.125 148.265723)
		(width 0.157)
		(layer "In5.Cu")
		(net 661)
	)
	(arc
		(start 180.525 148.065723)
		(mid 180.383579 148.124302)
		(end 180.325 148.265723)
		(width 0.157)
		(layer "In5.Cu")
		(net 661)
	)
	(arc
		(start 185.325 148.065723)
		(mid 185.183579 148.124302)
		(end 185.125 148.265723)
		(width 0.157)
		(layer "In5.Cu")
		(net 661)
	)
	(arc
		(start 185.525 148.265723)
		(mid 185.466421 148.124302)
		(end 185.325 148.065723)
		(width 0.157)
		(layer "In5.Cu")
		(net 661)
	)
	(arc
		(start 187.325 149.55)
		(mid 187.183579 149.491421)
		(end 187.125 149.35)
		(width 0.157)
		(layer "In5.Cu")
		(net 661)
	)
	(arc
		(start 180.325 149.35)
		(mid 180.266421 149.491421)
		(end 180.125 149.55)
		(width 0.157)
		(layer "In5.Cu")
		(net 661)
	)
	(arc
		(start 183.325 149.55)
		(mid 183.183579 149.491421)
		(end 183.125 149.35)
		(width 0.157)
		(layer "In5.Cu")
		(net 661)
	)
	(arc
		(start 187.525 149.35)
		(mid 187.466421 149.491421)
		(end 187.325 149.55)
		(width 0.157)
		(layer "In5.Cu")
		(net 661)
	)
	(arc
		(start 188.125 149.55)
		(mid 187.983579 149.491421)
		(end 187.925 149.35)
		(width 0.157)
		(layer "In5.Cu")
		(net 661)
	)
	(arc
		(start 181.525 148.265723)
		(mid 181.466421 148.124302)
		(end 181.325 148.065723)
		(width 0.157)
		(layer "In5.Cu")
		(net 661)
	)
	(arc
		(start 184.325 149.35)
		(mid 184.266421 149.491421)
		(end 184.125 149.55)
		(width 0.157)
		(layer "In5.Cu")
		(net 661)
	)
	(arc
		(start 181.925 149.35)
		(mid 181.866421 149.491421)
		(end 181.725 149.55)
		(width 0.157)
		(layer "In5.Cu")
		(net 661)
	)
	(arc
		(start 186.725 149.35)
		(mid 186.666421 149.491421)
		(end 186.525 149.55)
		(width 0.157)
		(layer "In5.Cu")
		(net 661)
	)
	(arc
		(start 185.125 149.35)
		(mid 185.066421 149.491421)
		(end 184.925 149.55)
		(width 0.157)
		(layer "In5.Cu")
		(net 661)
	)
	(arc
		(start 181.125 149.35)
		(mid 181.066421 149.491421)
		(end 180.925 149.55)
		(width 0.157)
		(layer "In5.Cu")
		(net 661)
	)
	(arc
		(start 183.725 148.065723)
		(mid 183.583579 148.124302)
		(end 183.525 148.265723)
		(width 0.157)
		(layer "In5.Cu")
		(net 661)
	)
	(arc
		(start 184.725 148.265723)
		(mid 184.666421 148.124302)
		(end 184.525 148.065723)
		(width 0.157)
		(layer "In5.Cu")
		(net 661)
	)
	(arc
		(start 185.925 149.35)
		(mid 185.866421 149.491421)
		(end 185.725 149.55)
		(width 0.157)
		(layer "In5.Cu")
		(net 661)
	)
	(arc
		(start 186.325 148.265723)
		(mid 186.266421 148.124302)
		(end 186.125 148.065723)
		(width 0.157)
		(layer "In5.Cu")
		(net 661)
	)
	(arc
		(start 187.725 148.065723)
		(mid 187.583579 148.124302)
		(end 187.525 148.265723)
		(width 0.157)
		(layer "In5.Cu")
		(net 661)
	)
	(arc
		(start 186.125 148.065723)
		(mid 185.983579 148.124302)
		(end 185.925 148.265723)
		(width 0.157)
		(layer "In5.Cu")
		(net 661)
	)
	(arc
		(start 180.925 149.55)
		(mid 180.783579 149.491421)
		(end 180.725 149.35)
		(width 0.157)
		(layer "In5.Cu")
		(net 661)
	)
	(arc
		(start 182.725 149.35)
		(mid 182.666421 149.491421)
		(end 182.525 149.55)
		(width 0.157)
		(layer "In5.Cu")
		(net 661)
	)
	(arc
		(start 183.525 149.35)
		(mid 183.466421 149.491421)
		(end 183.325 149.55)
		(width 0.157)
		(layer "In5.Cu")
		(net 661)
	)
	(arc
		(start 183.925 148.265723)
		(mid 183.866421 148.124302)
		(end 183.725 148.065723)
		(width 0.157)
		(layer "In5.Cu")
		(net 661)
	)
	(segment
		(start 190.5 144.5)
		(end 191 145)
		(width 0.256)
		(layer "F.Cu")
		(net 662)
	)
	(segment
		(start 172.402 143.2)
		(end 172.402 143.202)
		(width 0.256)
		(layer "F.Cu")
		(net 662)
	)
	(segment
		(start 172.402 143.202)
		(end 172.8 143.6)
		(width 0.256)
		(layer "F.Cu")
		(net 662)
	)
	(via
		(at 172.8 143.6)
		(size 0.45)
		(drill 0.2)
		(layers "F.Cu" "B.Cu")
		(net 662)
	)
	(via
		(at 191 145)
		(size 0.45)
		(drill 0.2)
		(layers "F.Cu" "B.Cu")
		(net 662)
	)
	(segment
		(start 186.075 153.275)
		(end 186.075 152.874941)
		(width 0.157)
		(layer "In5.Cu")
		(net 662)
	)
	(segment
		(start 179.775 153.275)
		(end 179.775 152.874941)
		(width 0.157)
		(layer "In5.Cu")
		(net 662)
	)
	(segment
		(start 186.975 153.275)
		(end 186.975 152.874941)
		(width 0.157)
		(layer "In5.Cu")
		(net 662)
	)
	(segment
		(start 171.375 144.075)
		(end 171.1 144.35)
		(width 0.157)
		(layer "In5.Cu")
		(net 662)
	)
	(segment
		(start 185.175 153.275)
		(end 185.175 152.874941)
		(width 0.157)
		(layer "In5.Cu")
		(net 662)
	)
	(segment
		(start 187.425 152.874941)
		(end 187.425 153.275)
		(width 0.157)
		(layer "In5.Cu")
		(net 662)
	)
	(segment
		(start 189.825 153.5)
		(end 191 152.325)
		(width 0.157)
		(layer "In5.Cu")
		(net 662)
	)
	(segment
		(start 182.475 153.275)
		(end 182.475 152.874941)
		(width 0.157)
		(layer "In5.Cu")
		(net 662)
	)
	(segment
		(start 171.1 145.425)
		(end 171.425 145.75)
		(width 0.157)
		(layer "In5.Cu")
		(net 662)
	)
	(segment
		(start 188.775 153.275)
		(end 188.775 152.874941)
		(width 0.157)
		(layer "In5.Cu")
		(net 662)
	)
	(segment
		(start 172.8 143.6)
		(end 172.325 144.075)
		(width 0.157)
		(layer "In5.Cu")
		(net 662)
	)
	(segment
		(start 171.1 144.35)
		(end 171.1 145.425)
		(width 0.157)
		(layer "In5.Cu")
		(net 662)
	)
	(segment
		(start 180.225 152.874941)
		(end 180.225 153.275)
		(width 0.157)
		(layer "In5.Cu")
		(net 662)
	)
	(segment
		(start 191 152.325)
		(end 191 145)
		(width 0.157)
		(layer "In5.Cu")
		(net 662)
	)
	(segment
		(start 183.825 152.874941)
		(end 183.825 153.275)
		(width 0.157)
		(layer "In5.Cu")
		(net 662)
	)
	(segment
		(start 184.725 152.874941)
		(end 184.725 153.275)
		(width 0.157)
		(layer "In5.Cu")
		(net 662)
	)
	(segment
		(start 185.625 152.874941)
		(end 185.625 153.275)
		(width 0.157)
		(layer "In5.Cu")
		(net 662)
	)
	(segment
		(start 187.875 153.275)
		(end 187.875 152.874941)
		(width 0.157)
		(layer "In5.Cu")
		(net 662)
	)
	(segment
		(start 186.525 152.874941)
		(end 186.525 153.275)
		(width 0.157)
		(layer "In5.Cu")
		(net 662)
	)
	(segment
		(start 189.225 152.874941)
		(end 189.225 153.275)
		(width 0.157)
		(layer "In5.Cu")
		(net 662)
	)
	(segment
		(start 177.5 151.95)
		(end 179.05 153.5)
		(width 0.157)
		(layer "In5.Cu")
		(net 662)
	)
	(segment
		(start 172.325 144.075)
		(end 171.375 144.075)
		(width 0.157)
		(layer "In5.Cu")
		(net 662)
	)
	(segment
		(start 189.5 153.5)
		(end 189.825 153.5)
		(width 0.157)
		(layer "In5.Cu")
		(net 662)
	)
	(segment
		(start 189.45 153.5)
		(end 189.5 153.5)
		(width 0.157)
		(layer "In5.Cu")
		(net 662)
	)
	(segment
		(start 177.5 147.3)
		(end 177.5 151.95)
		(width 0.157)
		(layer "In5.Cu")
		(net 662)
	)
	(segment
		(start 188.325 152.874941)
		(end 188.325 153.275)
		(width 0.157)
		(layer "In5.Cu")
		(net 662)
	)
	(segment
		(start 184.275 153.275)
		(end 184.275 152.874941)
		(width 0.157)
		(layer "In5.Cu")
		(net 662)
	)
	(segment
		(start 182.925 152.874941)
		(end 182.925 153.275)
		(width 0.157)
		(layer "In5.Cu")
		(net 662)
	)
	(segment
		(start 179.05 153.5)
		(end 179.55 153.5)
		(width 0.157)
		(layer "In5.Cu")
		(net 662)
	)
	(segment
		(start 183.375 153.275)
		(end 183.375 152.874941)
		(width 0.157)
		(layer "In5.Cu")
		(net 662)
	)
	(segment
		(start 175.95 145.75)
		(end 177.5 147.3)
		(width 0.157)
		(layer "In5.Cu")
		(net 662)
	)
	(segment
		(start 181.125 152.874941)
		(end 181.125 153.275)
		(width 0.157)
		(layer "In5.Cu")
		(net 662)
	)
	(segment
		(start 180.675 153.275)
		(end 180.675 152.874941)
		(width 0.157)
		(layer "In5.Cu")
		(net 662)
	)
	(segment
		(start 181.575 153.275)
		(end 181.575 152.874941)
		(width 0.157)
		(layer "In5.Cu")
		(net 662)
	)
	(segment
		(start 171.425 145.75)
		(end 175.95 145.75)
		(width 0.157)
		(layer "In5.Cu")
		(net 662)
	)
	(segment
		(start 182.025 152.874941)
		(end 182.025 153.275)
		(width 0.157)
		(layer "In5.Cu")
		(net 662)
	)
	(arc
		(start 186.75 153.5)
		(mid 186.909099 153.434099)
		(end 186.975 153.275)
		(width 0.157)
		(layer "In5.Cu")
		(net 662)
	)
	(arc
		(start 187.65 153.5)
		(mid 187.809099 153.434099)
		(end 187.875 153.275)
		(width 0.157)
		(layer "In5.Cu")
		(net 662)
	)
	(arc
		(start 188.1 152.649941)
		(mid 188.259099 152.715842)
		(end 188.325 152.874941)
		(width 0.157)
		(layer "In5.Cu")
		(net 662)
	)
	(arc
		(start 185.625 153.275)
		(mid 185.690901 153.434099)
		(end 185.85 153.5)
		(width 0.157)
		(layer "In5.Cu")
		(net 662)
	)
	(arc
		(start 184.5 152.649941)
		(mid 184.659099 152.715842)
		(end 184.725 152.874941)
		(width 0.157)
		(layer "In5.Cu")
		(net 662)
	)
	(arc
		(start 188.325 153.275)
		(mid 188.390901 153.434099)
		(end 188.55 153.5)
		(width 0.157)
		(layer "In5.Cu")
		(net 662)
	)
	(arc
		(start 180.45 153.5)
		(mid 180.609099 153.434099)
		(end 180.675 153.275)
		(width 0.157)
		(layer "In5.Cu")
		(net 662)
	)
	(arc
		(start 184.95 153.5)
		(mid 185.109099 153.434099)
		(end 185.175 153.275)
		(width 0.157)
		(layer "In5.Cu")
		(net 662)
	)
	(arc
		(start 182.475 152.874941)
		(mid 182.540901 152.715842)
		(end 182.7 152.649941)
		(width 0.157)
		(layer "In5.Cu")
		(net 662)
	)
	(arc
		(start 181.125 153.275)
		(mid 181.190901 153.434099)
		(end 181.35 153.5)
		(width 0.157)
		(layer "In5.Cu")
		(net 662)
	)
	(arc
		(start 180.675 152.874941)
		(mid 180.740901 152.715842)
		(end 180.9 152.649941)
		(width 0.157)
		(layer "In5.Cu")
		(net 662)
	)
	(arc
		(start 186.525 153.275)
		(mid 186.590901 153.434099)
		(end 186.75 153.5)
		(width 0.157)
		(layer "In5.Cu")
		(net 662)
	)
	(arc
		(start 185.4 152.649941)
		(mid 185.559099 152.715842)
		(end 185.625 152.874941)
		(width 0.157)
		(layer "In5.Cu")
		(net 662)
	)
	(arc
		(start 182.25 153.5)
		(mid 182.409099 153.434099)
		(end 182.475 153.275)
		(width 0.157)
		(layer "In5.Cu")
		(net 662)
	)
	(arc
		(start 185.85 153.5)
		(mid 186.009099 153.434099)
		(end 186.075 153.275)
		(width 0.157)
		(layer "In5.Cu")
		(net 662)
	)
	(arc
		(start 188.775 152.874941)
		(mid 188.840901 152.715842)
		(end 189 152.649941)
		(width 0.157)
		(layer "In5.Cu")
		(net 662)
	)
	(arc
		(start 187.425 153.275)
		(mid 187.490901 153.434099)
		(end 187.65 153.5)
		(width 0.157)
		(layer "In5.Cu")
		(net 662)
	)
	(arc
		(start 182.925 153.275)
		(mid 182.990901 153.434099)
		(end 183.15 153.5)
		(width 0.157)
		(layer "In5.Cu")
		(net 662)
	)
	(arc
		(start 180.225 153.275)
		(mid 180.290901 153.434099)
		(end 180.45 153.5)
		(width 0.157)
		(layer "In5.Cu")
		(net 662)
	)
	(arc
		(start 186.975 152.874941)
		(mid 187.040901 152.715842)
		(end 187.2 152.649941)
		(width 0.157)
		(layer "In5.Cu")
		(net 662)
	)
	(arc
		(start 187.2 152.649941)
		(mid 187.359099 152.715842)
		(end 187.425 152.874941)
		(width 0.157)
		(layer "In5.Cu")
		(net 662)
	)
	(arc
		(start 186.075 152.874941)
		(mid 186.140901 152.715842)
		(end 186.3 152.649941)
		(width 0.157)
		(layer "In5.Cu")
		(net 662)
	)
	(arc
		(start 180 152.649941)
		(mid 180.159099 152.715842)
		(end 180.225 152.874941)
		(width 0.157)
		(layer "In5.Cu")
		(net 662)
	)
	(arc
		(start 180.9 152.649941)
		(mid 181.059099 152.715842)
		(end 181.125 152.874941)
		(width 0.157)
		(layer "In5.Cu")
		(net 662)
	)
	(arc
		(start 182.025 153.275)
		(mid 182.090901 153.434099)
		(end 182.25 153.5)
		(width 0.157)
		(layer "In5.Cu")
		(net 662)
	)
	(arc
		(start 181.575 152.874941)
		(mid 181.640901 152.715842)
		(end 181.8 152.649941)
		(width 0.157)
		(layer "In5.Cu")
		(net 662)
	)
	(arc
		(start 186.3 152.649941)
		(mid 186.459099 152.715842)
		(end 186.525 152.874941)
		(width 0.157)
		(layer "In5.Cu")
		(net 662)
	)
	(arc
		(start 185.175 152.874941)
		(mid 185.240901 152.715842)
		(end 185.4 152.649941)
		(width 0.157)
		(layer "In5.Cu")
		(net 662)
	)
	(arc
		(start 183.15 153.5)
		(mid 183.309099 153.434099)
		(end 183.375 153.275)
		(width 0.157)
		(layer "In5.Cu")
		(net 662)
	)
	(arc
		(start 189 152.649941)
		(mid 189.159099 152.715842)
		(end 189.225 152.874941)
		(width 0.157)
		(layer "In5.Cu")
		(net 662)
	)
	(arc
		(start 179.55 153.5)
		(mid 179.709099 153.434099)
		(end 179.775 153.275)
		(width 0.157)
		(layer "In5.Cu")
		(net 662)
	)
	(arc
		(start 184.275 152.874941)
		(mid 184.340901 152.715842)
		(end 184.5 152.649941)
		(width 0.157)
		(layer "In5.Cu")
		(net 662)
	)
	(arc
		(start 189.225 153.275)
		(mid 189.290901 153.434099)
		(end 189.45 153.5)
		(width 0.157)
		(layer "In5.Cu")
		(net 662)
	)
	(arc
		(start 184.05 153.5)
		(mid 184.209099 153.434099)
		(end 184.275 153.275)
		(width 0.157)
		(layer "In5.Cu")
		(net 662)
	)
	(arc
		(start 183.6 152.649941)
		(mid 183.759099 152.715842)
		(end 183.825 152.874941)
		(width 0.157)
		(layer "In5.Cu")
		(net 662)
	)
	(arc
		(start 181.35 153.5)
		(mid 181.509099 153.434099)
		(end 181.575 153.275)
		(width 0.157)
		(layer "In5.Cu")
		(net 662)
	)
	(arc
		(start 183.375 152.874941)
		(mid 183.440901 152.715842)
		(end 183.6 152.649941)
		(width 0.157)
		(layer "In5.Cu")
		(net 662)
	)
	(arc
		(start 179.775 152.874941)
		(mid 179.840901 152.715842)
		(end 180 152.649941)
		(width 0.157)
		(layer "In5.Cu")
		(net 662)
	)
	(arc
		(start 188.55 153.5)
		(mid 188.709099 153.434099)
		(end 188.775 153.275)
		(width 0.157)
		(layer "In5.Cu")
		(net 662)
	)
	(arc
		(start 184.725 153.275)
		(mid 184.790901 153.434099)
		(end 184.95 153.5)
		(width 0.157)
		(layer "In5.Cu")
		(net 662)
	)
	(arc
		(start 187.875 152.874941)
		(mid 187.940901 152.715842)
		(end 188.1 152.649941)
		(width 0.157)
		(layer "In5.Cu")
		(net 662)
	)
	(arc
		(start 183.825 153.275)
		(mid 183.890901 153.434099)
		(end 184.05 153.5)
		(width 0.157)
		(layer "In5.Cu")
		(net 662)
	)
	(arc
		(start 181.8 152.649941)
		(mid 181.959099 152.715842)
		(end 182.025 152.874941)
		(width 0.157)
		(layer "In5.Cu")
		(net 662)
	)
	(arc
		(start 182.7 152.649941)
		(mid 182.859099 152.715842)
		(end 182.925 152.874941)
		(width 0.157)
		(layer "In5.Cu")
		(net 662)
	)
	(segment
		(start 192.5 144.5)
		(end 192.5 145.207107)
		(width 0.256)
		(layer "F.Cu")
		(net 663)
	)
	(segment
		(start 172.4 147.2)
		(end 172.8 146.8)
		(width 0.256)
		(layer "F.Cu")
		(net 663)
	)
	(via
		(at 192.5 145.207107)
		(size 0.45)
		(drill 0.2)
		(layers "F.Cu" "B.Cu")
		(net 663)
	)
	(via
		(at 172.8 146.8)
		(size 0.45)
		(drill 0.2)
		(layers "F.Cu" "B.Cu")
		(net 663)
	)
	(segment
		(start 186.95 155.458558)
		(end 186.95 155.1)
		(width 0.157)
		(layer "In5.Cu")
		(net 663)
	)
	(segment
		(start 179.35 155.1)
		(end 179.35 155.458558)
		(width 0.157)
		(layer "In5.Cu")
		(net 663)
	)
	(segment
		(start 172.8 146.8)
		(end 173.25 146.35)
		(width 0.157)
		(layer "In5.Cu")
		(net 663)
	)
	(segment
		(start 185.75 155.1)
		(end 185.75 155.458558)
		(width 0.157)
		(layer "In5.Cu")
		(net 663)
	)
	(segment
		(start 182.95 155.458558)
		(end 182.95 155.1)
		(width 0.157)
		(layer "In5.Cu")
		(net 663)
	)
	(segment
		(start 178.45 154.9)
		(end 179.15 154.9)
		(width 0.157)
		(layer "In5.Cu")
		(net 663)
	)
	(segment
		(start 190.35 154.9)
		(end 190.65 154.9)
		(width 0.157)
		(layer "In5.Cu")
		(net 663)
	)
	(segment
		(start 190.65 154.9)
		(end 192.2 153.35)
		(width 0.157)
		(layer "In5.Cu")
		(net 663)
	)
	(segment
		(start 187.75 155.458558)
		(end 187.75 155.1)
		(width 0.157)
		(layer "In5.Cu")
		(net 663)
	)
	(segment
		(start 188.95 155.1)
		(end 188.95 155.458558)
		(width 0.157)
		(layer "In5.Cu")
		(net 663)
	)
	(segment
		(start 188.15 155.1)
		(end 188.15 155.458558)
		(width 0.157)
		(layer "In5.Cu")
		(net 663)
	)
	(segment
		(start 179.75 155.458558)
		(end 179.75 155.1)
		(width 0.157)
		(layer "In5.Cu")
		(net 663)
	)
	(segment
		(start 173.25 146.35)
		(end 174.15 146.35)
		(width 0.157)
		(layer "In5.Cu")
		(net 663)
	)
	(segment
		(start 182.55 155.1)
		(end 182.55 155.458558)
		(width 0.157)
		(layer "In5.Cu")
		(net 663)
	)
	(segment
		(start 185.35 155.458558)
		(end 185.35 155.1)
		(width 0.157)
		(layer "In5.Cu")
		(net 663)
	)
	(segment
		(start 181.75 155.1)
		(end 181.75 155.458558)
		(width 0.157)
		(layer "In5.Cu")
		(net 663)
	)
	(segment
		(start 188.55 155.458558)
		(end 188.55 155.1)
		(width 0.157)
		(layer "In5.Cu")
		(net 663)
	)
	(segment
		(start 183.75 155.458558)
		(end 183.75 155.1)
		(width 0.157)
		(layer "In5.Cu")
		(net 663)
	)
	(segment
		(start 175.95 148.15)
		(end 175.95 152.4)
		(width 0.157)
		(layer "In5.Cu")
		(net 663)
	)
	(segment
		(start 181.35 155.458558)
		(end 181.35 155.1)
		(width 0.157)
		(layer "In5.Cu")
		(net 663)
	)
	(segment
		(start 180.95 155.1)
		(end 180.95 155.458558)
		(width 0.157)
		(layer "In5.Cu")
		(net 663)
	)
	(segment
		(start 184.95 155.1)
		(end 184.95 155.458558)
		(width 0.157)
		(layer "In5.Cu")
		(net 663)
	)
	(segment
		(start 175.95 152.4)
		(end 178.45 154.9)
		(width 0.157)
		(layer "In5.Cu")
		(net 663)
	)
	(segment
		(start 180.55 155.458558)
		(end 180.55 155.1)
		(width 0.157)
		(layer "In5.Cu")
		(net 663)
	)
	(segment
		(start 183.35 155.1)
		(end 183.35 155.458558)
		(width 0.157)
		(layer "In5.Cu")
		(net 663)
	)
	(segment
		(start 186.55 155.1)
		(end 186.55 155.458558)
		(width 0.157)
		(layer "In5.Cu")
		(net 663)
	)
	(segment
		(start 186.15 155.458558)
		(end 186.15 155.1)
		(width 0.157)
		(layer "In5.Cu")
		(net 663)
	)
	(segment
		(start 187.35 155.1)
		(end 187.35 155.458558)
		(width 0.157)
		(layer "In5.Cu")
		(net 663)
	)
	(segment
		(start 190.15 155.458558)
		(end 190.15 155.1)
		(width 0.157)
		(layer "In5.Cu")
		(net 663)
	)
	(segment
		(start 192.2 153.35)
		(end 192.2 146.36)
		(width 0.157)
		(layer "In5.Cu")
		(net 663)
	)
	(segment
		(start 189.75 155.1)
		(end 189.75 155.458558)
		(width 0.157)
		(layer "In5.Cu")
		(net 663)
	)
	(segment
		(start 174.15 146.35)
		(end 175.95 148.15)
		(width 0.157)
		(layer "In5.Cu")
		(net 663)
	)
	(segment
		(start 184.15 155.1)
		(end 184.15 155.458558)
		(width 0.157)
		(layer "In5.Cu")
		(net 663)
	)
	(segment
		(start 192.5 146.06)
		(end 192.5 145.207107)
		(width 0.157)
		(layer "In5.Cu")
		(net 663)
	)
	(segment
		(start 180.15 155.1)
		(end 180.15 155.458558)
		(width 0.157)
		(layer "In5.Cu")
		(net 663)
	)
	(segment
		(start 182.15 155.458558)
		(end 182.15 155.1)
		(width 0.157)
		(layer "In5.Cu")
		(net 663)
	)
	(segment
		(start 189.35 155.458558)
		(end 189.35 155.1)
		(width 0.157)
		(layer "In5.Cu")
		(net 663)
	)
	(segment
		(start 184.55 155.458558)
		(end 184.55 155.1)
		(width 0.157)
		(layer "In5.Cu")
		(net 663)
	)
	(segment
		(start 192.2 146.36)
		(end 192.5 146.06)
		(width 0.157)
		(layer "In5.Cu")
		(net 663)
	)
	(arc
		(start 181.75 155.458558)
		(mid 181.808579 155.599979)
		(end 181.95 155.658558)
		(width 0.157)
		(layer "In5.Cu")
		(net 663)
	)
	(arc
		(start 179.15 154.9)
		(mid 179.291421 154.958579)
		(end 179.35 155.1)
		(width 0.157)
		(layer "In5.Cu")
		(net 663)
	)
	(arc
		(start 188.95 155.458558)
		(mid 189.008579 155.599979)
		(end 189.15 155.658558)
		(width 0.157)
		(layer "In5.Cu")
		(net 663)
	)
	(arc
		(start 183.35 155.458558)
		(mid 183.408579 155.599979)
		(end 183.55 155.658558)
		(width 0.157)
		(layer "In5.Cu")
		(net 663)
	)
	(arc
		(start 179.75 155.1)
		(mid 179.808579 154.958579)
		(end 179.95 154.9)
		(width 0.157)
		(layer "In5.Cu")
		(net 663)
	)
	(arc
		(start 187.75 155.1)
		(mid 187.808579 154.958579)
		(end 187.95 154.9)
		(width 0.157)
		(layer "In5.Cu")
		(net 663)
	)
	(arc
		(start 182.15 155.1)
		(mid 182.208579 154.958579)
		(end 182.35 154.9)
		(width 0.157)
		(layer "In5.Cu")
		(net 663)
	)
	(arc
		(start 186.55 155.458558)
		(mid 186.608579 155.599979)
		(end 186.75 155.658558)
		(width 0.157)
		(layer "In5.Cu")
		(net 663)
	)
	(arc
		(start 185.75 155.458558)
		(mid 185.808579 155.599979)
		(end 185.95 155.658558)
		(width 0.157)
		(layer "In5.Cu")
		(net 663)
	)
	(arc
		(start 182.75 155.658558)
		(mid 182.891421 155.599979)
		(end 182.95 155.458558)
		(width 0.157)
		(layer "In5.Cu")
		(net 663)
	)
	(arc
		(start 185.15 155.658558)
		(mid 185.291421 155.599979)
		(end 185.35 155.458558)
		(width 0.157)
		(layer "In5.Cu")
		(net 663)
	)
	(arc
		(start 190.15 155.1)
		(mid 190.208579 154.958579)
		(end 190.35 154.9)
		(width 0.157)
		(layer "In5.Cu")
		(net 663)
	)
	(arc
		(start 180.95 155.458558)
		(mid 181.008579 155.599979)
		(end 181.15 155.658558)
		(width 0.157)
		(layer "In5.Cu")
		(net 663)
	)
	(arc
		(start 184.95 155.458558)
		(mid 185.008579 155.599979)
		(end 185.15 155.658558)
		(width 0.157)
		(layer "In5.Cu")
		(net 663)
	)
	(arc
		(start 188.15 155.458558)
		(mid 188.208579 155.599979)
		(end 188.35 155.658558)
		(width 0.157)
		(layer "In5.Cu")
		(net 663)
	)
	(arc
		(start 182.55 155.458558)
		(mid 182.608579 155.599979)
		(end 182.75 155.658558)
		(width 0.157)
		(layer "In5.Cu")
		(net 663)
	)
	(arc
		(start 185.35 155.1)
		(mid 185.408579 154.958579)
		(end 185.55 154.9)
		(width 0.157)
		(layer "In5.Cu")
		(net 663)
	)
	(arc
		(start 181.95 155.658558)
		(mid 182.091421 155.599979)
		(end 182.15 155.458558)
		(width 0.157)
		(layer "In5.Cu")
		(net 663)
	)
	(arc
		(start 183.15 154.9)
		(mid 183.291421 154.958579)
		(end 183.35 155.1)
		(width 0.157)
		(layer "In5.Cu")
		(net 663)
	)
	(arc
		(start 186.75 155.658558)
		(mid 186.891421 155.599979)
		(end 186.95 155.458558)
		(width 0.157)
		(layer "In5.Cu")
		(net 663)
	)
	(arc
		(start 183.75 155.1)
		(mid 183.808579 154.958579)
		(end 183.95 154.9)
		(width 0.157)
		(layer "In5.Cu")
		(net 663)
	)
	(arc
		(start 186.35 154.9)
		(mid 186.491421 154.958579)
		(end 186.55 155.1)
		(width 0.157)
		(layer "In5.Cu")
		(net 663)
	)
	(arc
		(start 189.95 155.658558)
		(mid 190.091421 155.599979)
		(end 190.15 155.458558)
		(width 0.157)
		(layer "In5.Cu")
		(net 663)
	)
	(arc
		(start 179.95 154.9)
		(mid 180.091421 154.958579)
		(end 180.15 155.1)
		(width 0.157)
		(layer "In5.Cu")
		(net 663)
	)
	(arc
		(start 186.95 155.1)
		(mid 187.008579 154.958579)
		(end 187.15 154.9)
		(width 0.157)
		(layer "In5.Cu")
		(net 663)
	)
	(arc
		(start 187.95 154.9)
		(mid 188.091421 154.958579)
		(end 188.15 155.1)
		(width 0.157)
		(layer "In5.Cu")
		(net 663)
	)
	(arc
		(start 184.75 154.9)
		(mid 184.891421 154.958579)
		(end 184.95 155.1)
		(width 0.157)
		(layer "In5.Cu")
		(net 663)
	)
	(arc
		(start 182.95 155.1)
		(mid 183.008579 154.958579)
		(end 183.15 154.9)
		(width 0.157)
		(layer "In5.Cu")
		(net 663)
	)
	(arc
		(start 189.35 155.1)
		(mid 189.408579 154.958579)
		(end 189.55 154.9)
		(width 0.157)
		(layer "In5.Cu")
		(net 663)
	)
	(arc
		(start 186.15 155.1)
		(mid 186.208579 154.958579)
		(end 186.35 154.9)
		(width 0.157)
		(layer "In5.Cu")
		(net 663)
	)
	(arc
		(start 189.55 154.9)
		(mid 189.691421 154.958579)
		(end 189.75 155.1)
		(width 0.157)
		(layer "In5.Cu")
		(net 663)
	)
	(arc
		(start 179.35 155.458558)
		(mid 179.408579 155.599979)
		(end 179.55 155.658558)
		(width 0.157)
		(layer "In5.Cu")
		(net 663)
	)
	(arc
		(start 187.35 155.458558)
		(mid 187.408579 155.599979)
		(end 187.55 155.658558)
		(width 0.157)
		(layer "In5.Cu")
		(net 663)
	)
	(arc
		(start 188.55 155.1)
		(mid 188.608579 154.958579)
		(end 188.75 154.9)
		(width 0.157)
		(layer "In5.Cu")
		(net 663)
	)
	(arc
		(start 182.35 154.9)
		(mid 182.491421 154.958579)
		(end 182.55 155.1)
		(width 0.157)
		(layer "In5.Cu")
		(net 663)
	)
	(arc
		(start 180.55 155.1)
		(mid 180.608579 154.958579)
		(end 180.75 154.9)
		(width 0.157)
		(layer "In5.Cu")
		(net 663)
	)
	(arc
		(start 183.55 155.658558)
		(mid 183.691421 155.599979)
		(end 183.75 155.458558)
		(width 0.157)
		(layer "In5.Cu")
		(net 663)
	)
	(arc
		(start 184.15 155.458558)
		(mid 184.208579 155.599979)
		(end 184.35 155.658558)
		(width 0.157)
		(layer "In5.Cu")
		(net 663)
	)
	(arc
		(start 179.55 155.658558)
		(mid 179.691421 155.599979)
		(end 179.75 155.458558)
		(width 0.157)
		(layer "In5.Cu")
		(net 663)
	)
	(arc
		(start 188.35 155.658558)
		(mid 188.491421 155.599979)
		(end 188.55 155.458558)
		(width 0.157)
		(layer "In5.Cu")
		(net 663)
	)
	(arc
		(start 180.35 155.658558)
		(mid 180.491421 155.599979)
		(end 180.55 155.458558)
		(width 0.157)
		(layer "In5.Cu")
		(net 663)
	)
	(arc
		(start 188.75 154.9)
		(mid 188.891421 154.958579)
		(end 188.95 155.1)
		(width 0.157)
		(layer "In5.Cu")
		(net 663)
	)
	(arc
		(start 180.15 155.458558)
		(mid 180.208579 155.599979)
		(end 180.35 155.658558)
		(width 0.157)
		(layer "In5.Cu")
		(net 663)
	)
	(arc
		(start 189.15 155.658558)
		(mid 189.291421 155.599979)
		(end 189.35 155.458558)
		(width 0.157)
		(layer "In5.Cu")
		(net 663)
	)
	(arc
		(start 183.95 154.9)
		(mid 184.091421 154.958579)
		(end 184.15 155.1)
		(width 0.157)
		(layer "In5.Cu")
		(net 663)
	)
	(arc
		(start 181.35 155.1)
		(mid 181.408579 154.958579)
		(end 181.55 154.9)
		(width 0.157)
		(layer "In5.Cu")
		(net 663)
	)
	(arc
		(start 181.15 155.658558)
		(mid 181.291421 155.599979)
		(end 181.35 155.458558)
		(width 0.157)
		(layer "In5.Cu")
		(net 663)
	)
	(arc
		(start 184.35 155.658558)
		(mid 184.491421 155.599979)
		(end 184.55 155.458558)
		(width 0.157)
		(layer "In5.Cu")
		(net 663)
	)
	(arc
		(start 185.95 155.658558)
		(mid 186.091421 155.599979)
		(end 186.15 155.458558)
		(width 0.157)
		(layer "In5.Cu")
		(net 663)
	)
	(arc
		(start 187.15 154.9)
		(mid 187.291421 154.958579)
		(end 187.35 155.1)
		(width 0.157)
		(layer "In5.Cu")
		(net 663)
	)
	(arc
		(start 187.55 155.658558)
		(mid 187.691421 155.599979)
		(end 187.75 155.458558)
		(width 0.157)
		(layer "In5.Cu")
		(net 663)
	)
	(arc
		(start 189.75 155.458558)
		(mid 189.808579 155.599979)
		(end 189.95 155.658558)
		(width 0.157)
		(layer "In5.Cu")
		(net 663)
	)
	(arc
		(start 181.55 154.9)
		(mid 181.691421 154.958579)
		(end 181.75 155.1)
		(width 0.157)
		(layer "In5.Cu")
		(net 663)
	)
	(arc
		(start 184.55 155.1)
		(mid 184.608579 154.958579)
		(end 184.75 154.9)
		(width 0.157)
		(layer "In5.Cu")
		(net 663)
	)
	(arc
		(start 185.55 154.9)
		(mid 185.691421 154.958579)
		(end 185.75 155.1)
		(width 0.157)
		(layer "In5.Cu")
		(net 663)
	)
	(arc
		(start 180.75 154.9)
		(mid 180.891421 154.958579)
		(end 180.95 155.1)
		(width 0.157)
		(layer "In5.Cu")
		(net 663)
	)
	(segment
		(start 211.5 128.5)
		(end 212 128)
		(width 0.256)
		(layer "F.Cu")
		(net 664)
	)
	(segment
		(start 222.125 131.775)
		(end 222.5 131.4)
		(width 0.184)
		(layer "F.Cu")
		(net 664)
	)
	(via
		(at 212 128)
		(size 0.45)
		(drill 0.2)
		(layers "F.Cu" "B.Cu")
		(net 664)
	)
	(via
		(at 222.5 131.4)
		(size 0.45)
		(drill 0.2)
		(layers "F.Cu" "B.Cu")
		(net 664)
	)
	(segment
		(start 212.78 127.6)
		(end 212.38 128)
		(width 0.1)
		(layer "In3.Cu")
		(net 664)
	)
	(segment
		(start 217.25 127.65)
		(end 215.180331 127.65)
		(width 0.1)
		(layer "In3.Cu")
		(net 664)
	)
	(segment
		(start 215.130331 127.6)
		(end 212.78 127.6)
		(width 0.1)
		(layer "In3.Cu")
		(net 664)
	)
	(segment
		(start 218 126.9)
		(end 217.25 127.65)
		(width 0.1)
		(layer "In3.Cu")
		(net 664)
	)
	(segment
		(start 222.5 131.4)
		(end 222.875 131.025)
		(width 0.1)
		(layer "In3.Cu")
		(net 664)
	)
	(segment
		(start 222.875 131.025)
		(end 222.875 129.525)
		(width 0.1)
		(layer "In3.Cu")
		(net 664)
	)
	(segment
		(start 223.625 127.4625)
		(end 223.0625 126.9)
		(width 0.1)
		(layer "In3.Cu")
		(net 664)
	)
	(segment
		(start 223.625 128.775)
		(end 223.625 127.4625)
		(width 0.1)
		(layer "In3.Cu")
		(net 664)
	)
	(segment
		(start 223.0625 126.9)
		(end 218 126.9)
		(width 0.1)
		(layer "In3.Cu")
		(net 664)
	)
	(segment
		(start 215.180331 127.65)
		(end 215.130331 127.6)
		(width 0.1)
		(layer "In3.Cu")
		(net 664)
	)
	(segment
		(start 222.875 129.525)
		(end 223.625 128.775)
		(width 0.1)
		(layer "In3.Cu")
		(net 664)
	)
	(segment
		(start 212.38 128)
		(end 212 128)
		(width 0.1)
		(layer "In3.Cu")
		(net 664)
	)
	(segment
		(start 212.5 128.5)
		(end 213 128)
		(width 0.256)
		(layer "F.Cu")
		(net 665)
	)
	(segment
		(start 221.375 131.775)
		(end 221.75 131.4)
		(width 0.184)
		(layer "F.Cu")
		(net 665)
	)
	(via
		(at 213 128)
		(size 0.45)
		(drill 0.2)
		(layers "F.Cu" "B.Cu")
		(net 665)
	)
	(via
		(at 221.75 131.4)
		(size 0.45)
		(drill 0.2)
		(layers "F.Cu" "B.Cu")
		(net 665)
	)
	(segment
		(start 217.4375 128.025)
		(end 215.9375 128.025)
		(width 0.1)
		(layer "In3.Cu")
		(net 665)
	)
	(segment
		(start 218.1875 127.275)
		(end 217.4375 128.025)
		(width 0.1)
		(layer "In3.Cu")
		(net 665)
	)
	(segment
		(start 215.4625 128.5)
		(end 213.5 128.5)
		(width 0.1)
		(layer "In3.Cu")
		(net 665)
	)
	(segment
		(start 221.75 131.4)
		(end 222.125 131.025)
		(width 0.1)
		(layer "In3.Cu")
		(net 665)
	)
	(segment
		(start 222.125 129.525)
		(end 222.875 128.775)
		(width 0.1)
		(layer "In3.Cu")
		(net 665)
	)
	(segment
		(start 213.5 128.5)
		(end 213 128)
		(width 0.1)
		(layer "In3.Cu")
		(net 665)
	)
	(segment
		(start 222.6875 127.275)
		(end 218.1875 127.275)
		(width 0.1)
		(layer "In3.Cu")
		(net 665)
	)
	(segment
		(start 222.125 131.025)
		(end 222.125 129.525)
		(width 0.1)
		(layer "In3.Cu")
		(net 665)
	)
	(segment
		(start 215.9375 128.025)
		(end 215.4625 128.5)
		(width 0.1)
		(layer "In3.Cu")
		(net 665)
	)
	(segment
		(start 222.875 127.4625)
		(end 222.6875 127.275)
		(width 0.1)
		(layer "In3.Cu")
		(net 665)
	)
	(segment
		(start 222.875 128.775)
		(end 222.875 127.4625)
		(width 0.1)
		(layer "In3.Cu")
		(net 665)
	)
	(segment
		(start 213.5 128.5)
		(end 214 128)
		(width 0.256)
		(layer "F.Cu")
		(net 666)
	)
	(segment
		(start 223.625 129.525)
		(end 224 129.15)
		(width 0.184)
		(layer "F.Cu")
		(net 666)
	)
	(via
		(at 214 128)
		(size 0.45)
		(drill 0.2)
		(layers "F.Cu" "B.Cu")
		(net 666)
	)
	(via
		(at 224 129.15)
		(size 0.45)
		(drill 0.2)
		(layers "F.Cu" "B.Cu")
		(net 666)
	)
	(segment
		(start 215.75 127.4625)
		(end 216.6875 126.525)
		(width 0.1)
		(layer "In5.Cu")
		(net 666)
	)
	(segment
		(start 216.6875 126.525)
		(end 222.6875 126.525)
		(width 0.1)
		(layer "In5.Cu")
		(net 666)
	)
	(segment
		(start 214.4375 127.4625)
		(end 215.75 127.4625)
		(width 0.1)
		(layer "In5.Cu")
		(net 666)
	)
	(segment
		(start 214 128)
		(end 214 127.9)
		(width 0.1)
		(layer "In5.Cu")
		(net 666)
	)
	(segment
		(start 214 127.9)
		(end 214.4375 127.4625)
		(width 0.1)
		(layer "In5.Cu")
		(net 666)
	)
	(segment
		(start 222.6875 126.525)
		(end 224 127.8375)
		(width 0.1)
		(layer "In5.Cu")
		(net 666)
	)
	(segment
		(start 224 127.8375)
		(end 224 129.15)
		(width 0.1)
		(layer "In5.Cu")
		(net 666)
	)
	(segment
		(start 222.875 128.025)
		(end 222.5 127.65)
		(width 0.184)
		(layer "F.Cu")
		(net 667)
	)
	(segment
		(start 210.5 129.5)
		(end 211 129)
		(width 0.256)
		(layer "F.Cu")
		(net 667)
	)
	(via
		(at 222.5 127.65)
		(size 0.45)
		(drill 0.2)
		(layers "F.Cu" "B.Cu")
		(net 667)
	)
	(via
		(at 211 129)
		(size 0.45)
		(drill 0.2)
		(layers "F.Cu" "B.Cu")
		(net 667)
	)
	(segment
		(start 217.0625 127.275)
		(end 215.7275 128.61)
		(width 0.1)
		(layer "In5.Cu")
		(net 667)
	)
	(segment
		(start 215.7275 128.61)
		(end 211.39 128.61)
		(width 0.1)
		(layer "In5.Cu")
		(net 667)
	)
	(segment
		(start 222.125 127.275)
		(end 217.0625 127.275)
		(width 0.1)
		(layer "In5.Cu")
		(net 667)
	)
	(segment
		(start 211.39 128.61)
		(end 211 129)
		(width 0.1)
		(layer "In5.Cu")
		(net 667)
	)
	(segment
		(start 222.5 127.65)
		(end 222.125 127.275)
		(width 0.1)
		(layer "In5.Cu")
		(net 667)
	)
	(segment
		(start 220.625 130.275)
		(end 220.25 129.9)
		(width 0.184)
		(layer "F.Cu")
		(net 668)
	)
	(segment
		(start 212.965 129.035)
		(end 213 129.035)
		(width 0.256)
		(layer "F.Cu")
		(net 668)
	)
	(segment
		(start 212.5 129.5)
		(end 212.965 129.035)
		(width 0.256)
		(layer "F.Cu")
		(net 668)
	)
	(via
		(at 213 129.035)
		(size 0.45)
		(drill 0.2)
		(layers "F.Cu" "B.Cu")
		(net 668)
	)
	(via
		(at 220.25 129.9)
		(size 0.45)
		(drill 0.2)
		(layers "F.Cu" "B.Cu")
		(net 668)
	)
	(segment
		(start 213.465 129.5)
		(end 214.225 129.5)
		(width 0.1)
		(layer "In3.Cu")
		(net 668)
	)
	(segment
		(start 213 129.035)
		(end 213.465 129.5)
		(width 0.1)
		(layer "In3.Cu")
		(net 668)
	)
	(segment
		(start 214.225 129.5)
		(end 214.625 129.9)
		(width 0.1)
		(layer "In3.Cu")
		(net 668)
	)
	(segment
		(start 214.625 129.9)
		(end 220.25 129.9)
		(width 0.1)
		(layer "In3.Cu")
		(net 668)
	)
	(segment
		(start 213.5 129.5)
		(end 214 129)
		(width 0.256)
		(layer "F.Cu")
		(net 669)
	)
	(segment
		(start 219.875 129.525)
		(end 219.3125 129.525)
		(width 0.184)
		(layer "F.Cu")
		(net 669)
	)
	(via
		(at 219.3125 129.525)
		(size 0.45)
		(drill 0.2)
		(layers "F.Cu" "B.Cu")
		(net 669)
	)
	(via
		(at 214 129)
		(size 0.45)
		(drill 0.2)
		(layers "F.Cu" "B.Cu")
		(net 669)
	)
	(segment
		(start 219.3125 129.525)
		(end 219.2275 129.61)
		(width 0.1)
		(layer "In3.Cu")
		(net 669)
	)
	(segment
		(start 219.2275 129.61)
		(end 215.01 129.61)
		(width 0.1)
		(layer "In3.Cu")
		(net 669)
	)
	(segment
		(start 214.4 129)
		(end 214 129)
		(width 0.1)
		(layer "In3.Cu")
		(net 669)
	)
	(segment
		(start 215.01 129.61)
		(end 214.4 129)
		(width 0.1)
		(layer "In3.Cu")
		(net 669)
	)
	(segment
		(start 222.125 128.025)
		(end 221.75 128.4)
		(width 0.184)
		(layer "F.Cu")
		(net 670)
	)
	(segment
		(start 214.5 129.5)
		(end 215 129)
		(width 0.256)
		(layer "F.Cu")
		(net 670)
	)
	(via
		(at 215 129)
		(size 0.45)
		(drill 0.2)
		(layers "F.Cu" "B.Cu")
		(net 670)
	)
	(via
		(at 221.75 128.4)
		(size 0.45)
		(drill 0.2)
		(layers "F.Cu" "B.Cu")
		(net 670)
	)
	(segment
		(start 219.5 128.4)
		(end 216.125 128.4)
		(width 0.1)
		(layer "In3.Cu")
		(net 670)
	)
	(segment
		(start 216.125 128.4)
		(end 215.525 129)
		(width 0.1)
		(layer "In3.Cu")
		(net 670)
	)
	(segment
		(start 215.525 129)
		(end 215 129)
		(width 0.1)
		(layer "In3.Cu")
		(net 670)
	)
	(segment
		(start 221.75 128.4)
		(end 221.375 128.025)
		(width 0.1)
		(layer "In3.Cu")
		(net 670)
	)
	(segment
		(start 219.875 128.025)
		(end 219.5 128.4)
		(width 0.1)
		(layer "In3.Cu")
		(net 670)
	)
	(segment
		(start 221.375 128.025)
		(end 219.875 128.025)
		(width 0.1)
		(layer "In3.Cu")
		(net 670)
	)
	(segment
		(start 209.5 130.5)
		(end 210 131)
		(width 0.256)
		(layer "F.Cu")
		(net 671)
	)
	(segment
		(start 220.625 133.275)
		(end 221 132.9)
		(width 0.184)
		(layer "F.Cu")
		(net 671)
	)
	(via
		(at 221 132.9)
		(size 0.45)
		(drill 0.2)
		(layers "F.Cu" "B.Cu")
		(net 671)
	)
	(via
		(at 210 131)
		(size 0.45)
		(drill 0.2)
		(layers "F.Cu" "B.Cu")
		(net 671)
	)
	(segment
		(start 214.380331 132.15)
		(end 214.155331 132.375)
		(width 0.1)
		(layer "In5.Cu")
		(net 671)
	)
	(segment
		(start 221 132.9)
		(end 221 132.15)
		(width 0.1)
		(layer "In5.Cu")
		(net 671)
	)
	(segment
		(start 210.625 132.155331)
		(end 210.625 131.625)
		(width 0.1)
		(layer "In5.Cu")
		(net 671)
	)
	(segment
		(start 221 132.15)
		(end 220.625 131.775)
		(width 0.1)
		(layer "In5.Cu")
		(net 671)
	)
	(segment
		(start 210.625 131.625)
		(end 210 131)
		(width 0.1)
		(layer "In5.Cu")
		(net 671)
	)
	(segment
		(start 216.125 131.775)
		(end 215.75 132.15)
		(width 0.1)
		(layer "In5.Cu")
		(net 671)
	)
	(segment
		(start 215.75 132.15)
		(end 214.380331 132.15)
		(width 0.1)
		(layer "In5.Cu")
		(net 671)
	)
	(segment
		(start 210.844669 132.375)
		(end 210.625 132.155331)
		(width 0.1)
		(layer "In5.Cu")
		(net 671)
	)
	(segment
		(start 220.625 131.775)
		(end 216.125 131.775)
		(width 0.1)
		(layer "In5.Cu")
		(net 671)
	)
	(segment
		(start 214.155331 132.375)
		(end 210.844669 132.375)
		(width 0.1)
		(layer "In5.Cu")
		(net 671)
	)
	(segment
		(start 222.125 132.525)
		(end 221.75 132.15)
		(width 0.184)
		(layer "F.Cu")
		(net 672)
	)
	(segment
		(start 211 131)
		(end 210.5 130.5)
		(width 0.256)
		(layer "F.Cu")
		(net 672)
	)
	(segment
		(start 221.75 132.15)
		(end 221.75 132.1495)
		(width 0.184)
		(layer "F.Cu")
		(net 672)
	)
	(via
		(at 221.75 132.1495)
		(size 0.45)
		(drill 0.2)
		(layers "F.Cu" "B.Cu")
		(net 672)
	)
	(via
		(at 211 131)
		(size 0.45)
		(drill 0.2)
		(layers "F.Cu" "B.Cu")
		(net 672)
	)
	(segment
		(start 221.3755 131.775)
		(end 221.75 132.1495)
		(width 0.1)
		(layer "In3.Cu")
		(net 672)
	)
	(segment
		(start 211 131)
		(end 211.4 131.4)
		(width 0.1)
		(layer "In3.Cu")
		(net 672)
	)
	(segment
		(start 214.7 131.5)
		(end 218.8 131.5)
		(width 0.1)
		(layer "In3.Cu")
		(net 672)
	)
	(segment
		(start 219.075 131.775)
		(end 221.3755 131.775)
		(width 0.1)
		(layer "In3.Cu")
		(net 672)
	)
	(segment
		(start 211.4 131.4)
		(end 214.6 131.4)
		(width 0.1)
		(layer "In3.Cu")
		(net 672)
	)
	(segment
		(start 218.8 131.5)
		(end 219.075 131.775)
		(width 0.1)
		(layer "In3.Cu")
		(net 672)
	)
	(segment
		(start 214.6 131.4)
		(end 214.7 131.5)
		(width 0.1)
		(layer "In3.Cu")
		(net 672)
	)
	(segment
		(start 221.375 128.775)
		(end 221 129.15)
		(width 0.184)
		(layer "F.Cu")
		(net 673)
	)
	(segment
		(start 211.5 130.5)
		(end 212 131)
		(width 0.256)
		(layer "F.Cu")
		(net 673)
	)
	(via
		(at 221 129.15)
		(size 0.45)
		(drill 0.2)
		(layers "F.Cu" "B.Cu")
		(net 673)
	)
	(via
		(at 212 131)
		(size 0.45)
		(drill 0.2)
		(layers "F.Cu" "B.Cu")
		(net 673)
	)
	(segment
		(start 219.5 129.9)
		(end 214.9 129.9)
		(width 0.1)
		(layer "In7.Cu")
		(net 673)
	)
	(segment
		(start 220.25 129.15)
		(end 219.5 129.9)
		(width 0.1)
		(layer "In7.Cu")
		(net 673)
	)
	(segment
		(start 214.3 130.5)
		(end 212.5 130.5)
		(width 0.1)
		(layer "In7.Cu")
		(net 673)
	)
	(segment
		(start 212.5 130.5)
		(end 212 131)
		(width 0.1)
		(layer "In7.Cu")
		(net 673)
	)
	(segment
		(start 214.9 129.9)
		(end 214.3 130.5)
		(width 0.1)
		(layer "In7.Cu")
		(net 673)
	)
	(segment
		(start 221 129.15)
		(end 220.25 129.15)
		(width 0.1)
		(layer "In7.Cu")
		(net 673)
	)
	(segment
		(start 212.973999 130.973999)
		(end 212.973999 131.025)
		(width 0.256)
		(layer "F.Cu")
		(net 674)
	)
	(segment
		(start 212.5 130.5)
		(end 212.973999 130.973999)
		(width 0.256)
		(layer "F.Cu")
		(net 674)
	)
	(segment
		(start 220.625 131.025)
		(end 220.25 131.4)
		(width 0.184)
		(layer "F.Cu")
		(net 674)
	)
	(via
		(at 220.25 131.4)
		(size 0.45)
		(drill 0.2)
		(layers "F.Cu" "B.Cu")
		(net 674)
	)
	(via
		(at 212.973999 131.025)
		(size 0.45)
		(drill 0.2)
		(layers "F.Cu" "B.Cu")
		(net 674)
	)
	(segment
		(start 212.973999 130.801001)
		(end 213.275 130.5)
		(width 0.1)
		(layer "In3.Cu")
		(net 674)
	)
	(segment
		(start 219.3 131.4)
		(end 220.25 131.4)
		(width 0.1)
		(layer "In3.Cu")
		(net 674)
	)
	(segment
		(start 213.275 130.5)
		(end 214.3 130.5)
		(width 0.1)
		(layer "In3.Cu")
		(net 674)
	)
	(segment
		(start 219 131.1)
		(end 219.3 131.4)
		(width 0.1)
		(layer "In3.Cu")
		(net 674)
	)
	(segment
		(start 214.3 130.5)
		(end 214.9 131.1)
		(width 0.1)
		(layer "In3.Cu")
		(net 674)
	)
	(segment
		(start 212.973999 131.025)
		(end 212.973999 130.801001)
		(width 0.1)
		(layer "In3.Cu")
		(net 674)
	)
	(segment
		(start 214.9 131.1)
		(end 219 131.1)
		(width 0.1)
		(layer "In3.Cu")
		(net 674)
	)
	(segment
		(start 215.040312 130.5)
		(end 215.214812 130.6745)
		(width 0.256)
		(layer "F.Cu")
		(net 675)
	)
	(segment
		(start 221.375 129.525)
		(end 221 129.9)
		(width 0.184)
		(layer "F.Cu")
		(net 675)
	)
	(segment
		(start 214.5 130.5)
		(end 215.040312 130.5)
		(width 0.256)
		(layer "F.Cu")
		(net 675)
	)
	(via
		(at 215.214812 130.6745)
		(size 0.45)
		(drill 0.2)
		(layers "F.Cu" "B.Cu")
		(net 675)
	)
	(via
		(at 221 129.9)
		(size 0.45)
		(drill 0.2)
		(layers "F.Cu" "B.Cu")
		(net 675)
	)
	(segment
		(start 220.625 130.275)
		(end 215.614312 130.275)
		(width 0.1)
		(layer "In3.Cu")
		(net 675)
	)
	(segment
		(start 221 129.9)
		(end 220.625 130.275)
		(width 0.1)
		(layer "In3.Cu")
		(net 675)
	)
	(segment
		(start 215.614312 130.275)
		(end 215.214812 130.6745)
		(width 0.1)
		(layer "In3.Cu")
		(net 675)
	)
	(segment
		(start 219.875 131.775)
		(end 219.5 132.15)
		(width 0.184)
		(layer "F.Cu")
		(net 676)
	)
	(segment
		(start 204.5 131.5)
		(end 205 132)
		(width 0.256)
		(layer "F.Cu")
		(net 676)
	)
	(via
		(at 205 132)
		(size 0.45)
		(drill 0.2)
		(layers "F.Cu" "B.Cu")
		(net 676)
	)
	(via
		(at 219.5 132.15)
		(size 0.45)
		(drill 0.2)
		(layers "F.Cu" "B.Cu")
		(net 676)
	)
	(segment
		(start 219.5 132.15)
		(end 218.85 132.15)
		(width 0.1)
		(layer "In3.Cu")
		(net 676)
	)
	(segment
		(start 218.56875 131.86875)
		(end 214.53125 131.86875)
		(width 0.1)
		(layer "In3.Cu")
		(net 676)
	)
	(segment
		(start 218.85 132.15)
		(end 218.56875 131.86875)
		(width 0.1)
		(layer "In3.Cu")
		(net 676)
	)
	(segment
		(start 214.53125 131.86875)
		(end 214.2625 131.6)
		(width 0.1)
		(layer "In3.Cu")
		(net 676)
	)
	(segment
		(start 214.2625 131.6)
		(end 205.4 131.6)
		(width 0.1)
		(layer "In3.Cu")
		(net 676)
	)
	(segment
		(start 205.4 131.6)
		(end 205 132)
		(width 0.1)
		(layer "In3.Cu")
		(net 676)
	)
	(segment
		(start 207.975 131.975)
		(end 207.975 132.015481)
		(width 0.256)
		(layer "F.Cu")
		(net 677)
	)
	(segment
		(start 207.5 131.5)
		(end 207.975 131.975)
		(width 0.256)
		(layer "F.Cu")
		(net 677)
	)
	(segment
		(start 222.125 129.525)
		(end 221.75 129.15)
		(width 0.184)
		(layer "F.Cu")
		(net 677)
	)
	(via
		(at 221.75 129.15)
		(size 0.45)
		(drill 0.2)
		(layers "F.Cu" "B.Cu")
		(net 677)
	)
	(via
		(at 207.975 132.015481)
		(size 0.45)
		(drill 0.2)
		(layers "F.Cu" "B.Cu")
		(net 677)
	)
	(segment
		(start 221.75 127.0875)
		(end 222.125 127.4625)
		(width 0.1)
		(layer "In7.Cu")
		(net 677)
	)
	(segment
		(start 210.445 128.785)
		(end 210.6425 128.5875)
		(width 0.1)
		(layer "In7.Cu")
		(net 677)
	)
	(segment
		(start 210.6425 128.5875)
		(end 217.8125 128.5875)
		(width 0.1)
		(layer "In7.Cu")
		(net 677)
	)
	(segment
		(start 219.3125 127.0875)
		(end 221.75 127.0875)
		(width 0.1)
		(layer "In7.Cu")
		(net 677)
	)
	(segment
		(start 217.8125 128.5875)
		(end 219.3125 127.0875)
		(width 0.1)
		(layer "In7.Cu")
		(net 677)
	)
	(segment
		(start 208.625 131.365481)
		(end 208.625 130.725)
		(width 0.1)
		(layer "In7.Cu")
		(net 677)
	)
	(segment
		(start 222.125 128.775)
		(end 221.75 129.15)
		(width 0.1)
		(layer "In7.Cu")
		(net 677)
	)
	(segment
		(start 210.445 129.185)
		(end 210.445 128.785)
		(width 0.1)
		(layer "In7.Cu")
		(net 677)
	)
	(segment
		(start 209.725 129.625)
		(end 210.005 129.625)
		(width 0.1)
		(layer "In7.Cu")
		(net 677)
	)
	(segment
		(start 208.625 130.725)
		(end 209.725 129.625)
		(width 0.1)
		(layer "In7.Cu")
		(net 677)
	)
	(segment
		(start 207.975 132.015481)
		(end 208.625 131.365481)
		(width 0.1)
		(layer "In7.Cu")
		(net 677)
	)
	(segment
		(start 222.125 127.4625)
		(end 222.125 128.775)
		(width 0.1)
		(layer "In7.Cu")
		(net 677)
	)
	(segment
		(start 210.005 129.625)
		(end 210.445 129.185)
		(width 0.1)
		(layer "In7.Cu")
		(net 677)
	)
	(segment
		(start 220.625 128.025)
		(end 221 127.65)
		(width 0.184)
		(layer "F.Cu")
		(net 678)
	)
	(segment
		(start 209.5 131.5)
		(end 210 132)
		(width 0.256)
		(layer "F.Cu")
		(net 678)
	)
	(via
		(at 210 132)
		(size 0.45)
		(drill 0.2)
		(layers "F.Cu" "B.Cu")
		(net 678)
	)
	(via
		(at 221 127.65)
		(size 0.45)
		(drill 0.2)
		(layers "F.Cu" "B.Cu")
		(net 678)
	)
	(segment
		(start 218.29 129.61)
		(end 210.59 129.61)
		(width 0.1)
		(layer "In7.Cu")
		(net 678)
	)
	(segment
		(start 210.5 129.7)
		(end 210.5 131.5)
		(width 0.1)
		(layer "In7.Cu")
		(net 678)
	)
	(segment
		(start 221 127.65)
		(end 220.25 127.65)
		(width 0.1)
		(layer "In7.Cu")
		(net 678)
	)
	(segment
		(start 220.25 127.65)
		(end 218.29 129.61)
		(width 0.1)
		(layer "In7.Cu")
		(net 678)
	)
	(segment
		(start 210.59 129.61)
		(end 210.5 129.7)
		(width 0.1)
		(layer "In7.Cu")
		(net 678)
	)
	(segment
		(start 210.5 131.5)
		(end 210 132)
		(width 0.1)
		(layer "In7.Cu")
		(net 678)
	)
	(segment
		(start 211.5 131.5)
		(end 212 132)
		(width 0.256)
		(layer "F.Cu")
		(net 679)
	)
	(segment
		(start 221.375 128.025)
		(end 221 128.4)
		(width 0.184)
		(layer "F.Cu")
		(net 679)
	)
	(via
		(at 212 132)
		(size 0.45)
		(drill 0.2)
		(layers "F.Cu" "B.Cu")
		(net 679)
	)
	(via
		(at 221 128.4)
		(size 0.45)
		(drill 0.2)
		(layers "F.Cu" "B.Cu")
		(net 679)
	)
	(segment
		(start 219.319669 130.3)
		(end 215 130.3)
		(width 0.1)
		(layer "In7.Cu")
		(net 679)
	)
	(segment
		(start 214.4375 131.2125)
		(end 214.15 131.5)
		(width 0.1)
		(layer "In7.Cu")
		(net 679)
	)
	(segment
		(start 221 128.4)
		(end 221.375 128.775)
		(width 0.1)
		(layer "In7.Cu")
		(net 679)
	)
	(segment
		(start 215 130.3)
		(end 214.4375 130.8625)
		(width 0.1)
		(layer "In7.Cu")
		(net 679)
	)
	(segment
		(start 221.375 130.0875)
		(end 221.1625 130.3)
		(width 0.1)
		(layer "In7.Cu")
		(net 679)
	)
	(segment
		(start 214.4375 130.8625)
		(end 214.4375 131.2125)
		(width 0.1)
		(layer "In7.Cu")
		(net 679)
	)
	(segment
		(start 219.344669 130.275)
		(end 219.319669 130.3)
		(width 0.1)
		(layer "In7.Cu")
		(net 679)
	)
	(segment
		(start 212.5 131.5)
		(end 212 132)
		(width 0.1)
		(layer "In7.Cu")
		(net 679)
	)
	(segment
		(start 214.15 131.5)
		(end 212.5 131.5)
		(width 0.1)
		(layer "In7.Cu")
		(net 679)
	)
	(segment
		(start 221.1625 130.3)
		(end 221.1375 130.275)
		(width 0.1)
		(layer "In7.Cu")
		(net 679)
	)
	(segment
		(start 221.375 128.775)
		(end 221.375 130.0875)
		(width 0.1)
		(layer "In7.Cu")
		(net 679)
	)
	(segment
		(start 221.1375 130.275)
		(end 219.344669 130.275)
		(width 0.1)
		(layer "In7.Cu")
		(net 679)
	)
	(segment
		(start 212.96 131.96)
		(end 212.96 132)
		(width 0.256)
		(layer "F.Cu")
		(net 680)
	)
	(segment
		(start 212.5 131.5)
		(end 212.96 131.96)
		(width 0.256)
		(layer "F.Cu")
		(net 680)
	)
	(segment
		(start 222.125 133.275)
		(end 222.45 133.6)
		(width 0.184)
		(layer "F.Cu")
		(net 680)
	)
	(segment
		(start 222.45 133.6)
		(end 222.5 133.6)
		(width 0.184)
		(layer "F.Cu")
		(net 680)
	)
	(via
		(at 222.5 133.6)
		(size 0.45)
		(drill 0.2)
		(layers "F.Cu" "B.Cu")
		(net 680)
	)
	(via
		(at 212.96 132)
		(size 0.45)
		(drill 0.2)
		(layers "F.Cu" "B.Cu")
		(net 680)
	)
	(segment
		(start 222.5 132.15)
		(end 222.5 133.6)
		(width 0.1)
		(layer "In5.Cu")
		(net 680)
	)
	(segment
		(start 219.825 131.025)
		(end 221.9375 131.025)
		(width 0.1)
		(layer "In5.Cu")
		(net 680)
	)
	(segment
		(start 219.56875 131.28125)
		(end 219.825 131.025)
		(width 0.1)
		(layer "In5.Cu")
		(net 680)
	)
	(segment
		(start 222.125 131.2125)
		(end 222.125 131.775)
		(width 0.1)
		(layer "In5.Cu")
		(net 680)
	)
	(segment
		(start 221.9375 131.025)
		(end 222.125 131.2125)
		(width 0.1)
		(layer "In5.Cu")
		(net 680)
	)
	(segment
		(start 215.3625 131.6)
		(end 215.68125 131.28125)
		(width 0.1)
		(layer "In5.Cu")
		(net 680)
	)
	(segment
		(start 215.68125 131.28125)
		(end 219.56875 131.28125)
		(width 0.1)
		(layer "In5.Cu")
		(net 680)
	)
	(segment
		(start 222.125 131.775)
		(end 222.5 132.15)
		(width 0.1)
		(layer "In5.Cu")
		(net 680)
	)
	(segment
		(start 213.36 131.6)
		(end 215.3625 131.6)
		(width 0.1)
		(layer "In5.Cu")
		(net 680)
	)
	(segment
		(start 212.96 132)
		(end 213.36 131.6)
		(width 0.1)
		(layer "In5.Cu")
		(net 680)
	)
	(segment
		(start 222.125 128.775)
		(end 222.5 128.4)
		(width 0.184)
		(layer "F.Cu")
		(net 681)
	)
	(segment
		(start 203.5 132.5)
		(end 204 133)
		(width 0.256)
		(layer "F.Cu")
		(net 681)
	)
	(via
		(at 222.5 128.4)
		(size 0.45)
		(drill 0.2)
		(layers "F.Cu" "B.Cu")
		(net 681)
	)
	(via
		(at 204 133)
		(size 0.45)
		(drill 0.2)
		(layers "F.Cu" "B.Cu")
		(net 681)
	)
	(segment
		(start 222.5 128.4)
		(end 222.875 128.025)
		(width 0.1)
		(layer "In5.Cu")
		(net 681)
	)
	(segment
		(start 222.875 128.025)
		(end 222.875 127.275)
		(width 0.1)
		(layer "In5.Cu")
		(net 681)
	)
	(segment
		(start 216.875 126.9)
		(end 215.365 128.41)
		(width 0.1)
		(layer "In5.Cu")
		(net 681)
	)
	(segment
		(start 222.875 127.275)
		(end 222.5 126.9)
		(width 0.1)
		(layer "In5.Cu")
		(net 681)
	)
	(segment
		(start 222.5 126.9)
		(end 216.875 126.9)
		(width 0.1)
		(layer "In5.Cu")
		(net 681)
	)
	(segment
		(start 205.245 132.485)
		(end 204.515 132.485)
		(width 0.1)
		(layer "In5.Cu")
		(net 681)
	)
	(segment
		(start 205.5 132.23)
		(end 205.245 132.485)
		(width 0.1)
		(layer "In5.Cu")
		(net 681)
	)
	(segment
		(start 205.84 128.41)
		(end 205.5 128.75)
		(width 0.1)
		(layer "In5.Cu")
		(net 681)
	)
	(segment
		(start 204.515 132.485)
		(end 204 133)
		(width 0.1)
		(layer "In5.Cu")
		(net 681)
	)
	(segment
		(start 205.5 128.75)
		(end 205.5 132.23)
		(width 0.1)
		(layer "In5.Cu")
		(net 681)
	)
	(segment
		(start 215.365 128.41)
		(end 205.84 128.41)
		(width 0.1)
		(layer "In5.Cu")
		(net 681)
	)
	(segment
		(start 204.974087 133.003845)
		(end 204.974087 132.974087)
		(width 0.256)
		(layer "F.Cu")
		(net 682)
	)
	(segment
		(start 221.750001 132.900001)
		(end 221.375 132.525)
		(width 0.184)
		(layer "F.Cu")
		(net 682)
	)
	(segment
		(start 221.750001 133.649999)
		(end 221.750001 132.900001)
		(width 0.184)
		(layer "F.Cu")
		(net 682)
	)
	(segment
		(start 204.974087 132.974087)
		(end 204.5 132.5)
		(width 0.256)
		(layer "F.Cu")
		(net 682)
	)
	(via
		(at 221.750001 133.649999)
		(size 0.45)
		(drill 0.2)
		(layers "F.Cu" "B.Cu")
		(net 682)
	)
	(via
		(at 204.974087 133.003845)
		(size 0.45)
		(drill 0.2)
		(layers "F.Cu" "B.Cu")
		(net 682)
	)
	(segment
		(start 204.974087 133.003845)
		(end 205.595242 133.625)
		(width 0.1)
		(layer "In7.Cu")
		(net 682)
	)
	(segment
		(start 215.5625 133.275)
		(end 221.375002 133.275)
		(width 0.1)
		(layer "In7.Cu")
		(net 682)
	)
	(segment
		(start 221.375002 133.275)
		(end 221.750001 133.649999)
		(width 0.1)
		(layer "In7.Cu")
		(net 682)
	)
	(segment
		(start 215.2125 133.625)
		(end 215.5625 133.275)
		(width 0.1)
		(layer "In7.Cu")
		(net 682)
	)
	(segment
		(start 205.595242 133.625)
		(end 215.2125 133.625)
		(width 0.1)
		(layer "In7.Cu")
		(net 682)
	)
	(segment
		(start 223.625 131.775)
		(end 223.25 132.15)
		(width 0.184)
		(layer "F.Cu")
		(net 683)
	)
	(segment
		(start 205.5 132.5)
		(end 206 133)
		(width 0.256)
		(layer "F.Cu")
		(net 683)
	)
	(via
		(at 223.25 132.15)
		(size 0.45)
		(drill 0.2)
		(layers "F.Cu" "B.Cu")
		(net 683)
	)
	(via
		(at 206 133)
		(size 0.45)
		(drill 0.2)
		(layers "F.Cu" "B.Cu")
		(net 683)
	)
	(segment
		(start 206.425 133.425)
		(end 214.25 133.425)
		(width 0.1)
		(layer "In7.Cu")
		(net 683)
	)
	(segment
		(start 214.4375 133.2375)
		(end 214.4375 132.9)
		(width 0.1)
		(layer "In7.Cu")
		(net 683)
	)
	(segment
		(start 222.875 131.775)
		(end 223.25 132.15)
		(width 0.1)
		(layer "In7.Cu")
		(net 683)
	)
	(segment
		(start 206 133)
		(end 206.425 133.425)
		(width 0.1)
		(layer "In7.Cu")
		(net 683)
	)
	(segment
		(start 215.5625 131.775)
		(end 222.875 131.775)
		(width 0.1)
		(layer "In7.Cu")
		(net 683)
	)
	(segment
		(start 214.25 133.425)
		(end 214.4375 133.2375)
		(width 0.1)
		(layer "In7.Cu")
		(net 683)
	)
	(segment
		(start 214.4375 132.9)
		(end 215.5625 131.775)
		(width 0.1)
		(layer "In7.Cu")
		(net 683)
	)
	(segment
		(start 221.375 131.025)
		(end 221 131.4)
		(width 0.184)
		(layer "F.Cu")
		(net 684)
	)
	(segment
		(start 208.5 132.5)
		(end 209 133)
		(width 0.256)
		(layer "F.Cu")
		(net 684)
	)
	(via
		(at 209 133)
		(size 0.45)
		(drill 0.2)
		(layers "F.Cu" "B.Cu")
		(net 684)
	)
	(via
		(at 221 131.4)
		(size 0.45)
		(drill 0.2)
		(layers "F.Cu" "B.Cu")
		(net 684)
	)
	(segment
		(start 215.75 131.025)
		(end 214.25 132.525)
		(width 0.1)
		(layer "In7.Cu")
		(net 684)
	)
	(segment
		(start 214.25 132.525)
		(end 209.475 132.525)
		(width 0.1)
		(layer "In7.Cu")
		(net 684)
	)
	(segment
		(start 221 131.4)
		(end 220.625 131.025)
		(width 0.1)
		(layer "In7.Cu")
		(net 684)
	)
	(segment
		(start 209.475 132.525)
		(end 209 133)
		(width 0.1)
		(layer "In7.Cu")
		(net 684)
	)
	(segment
		(start 220.625 131.025)
		(end 215.75 131.025)
		(width 0.1)
		(layer "In7.Cu")
		(net 684)
	)
	(segment
		(start 223.625 128.025)
		(end 223.25 128.4)
		(width 0.184)
		(layer "F.Cu")
		(net 685)
	)
	(segment
		(start 209.965 132.965)
		(end 209.965 132.98)
		(width 0.256)
		(layer "F.Cu")
		(net 685)
	)
	(segment
		(start 209.5 132.5)
		(end 209.965 132.965)
		(width 0.256)
		(layer "F.Cu")
		(net 685)
	)
	(via
		(at 209.965 132.98)
		(size 0.45)
		(drill 0.2)
		(layers "F.Cu" "B.Cu")
		(net 685)
	)
	(via
		(at 223.25 128.4)
		(size 0.45)
		(drill 0.2)
		(layers "F.Cu" "B.Cu")
		(net 685)
	)
	(segment
		(start 217.05 128.775)
		(end 222.875 128.775)
		(width 0.1)
		(layer "In5.Cu")
		(net 685)
	)
	(segment
		(start 209.975 130.425)
		(end 214.225 130.425)
		(width 0.1)
		(layer "In5.Cu")
		(net 685)
	)
	(segment
		(start 209.625 132.64)
		(end 209.625 130.775)
		(width 0.1)
		(layer "In5.Cu")
		(net 685)
	)
	(segment
		(start 214.225 130.425)
		(end 214.7375 129.9125)
		(width 0.1)
		(layer "In5.Cu")
		(net 685)
	)
	(segment
		(start 209.965 132.98)
		(end 209.625 132.64)
		(width 0.1)
		(layer "In5.Cu")
		(net 685)
	)
	(segment
		(start 215.9125 129.9125)
		(end 217.05 128.775)
		(width 0.1)
		(layer "In5.Cu")
		(net 685)
	)
	(segment
		(start 209.625 130.775)
		(end 209.975 130.425)
		(width 0.1)
		(layer "In5.Cu")
		(net 685)
	)
	(segment
		(start 214.7375 129.9125)
		(end 215.9125 129.9125)
		(width 0.1)
		(layer "In5.Cu")
		(net 685)
	)
	(segment
		(start 222.875 128.775)
		(end 223.25 128.4)
		(width 0.1)
		(layer "In5.Cu")
		(net 685)
	)
	(segment
		(start 221 133.65)
		(end 221.375 133.275)
		(width 0.184)
		(layer "F.Cu")
		(net 686)
	)
	(segment
		(start 213.5 132.5)
		(end 214 133)
		(width 0.256)
		(layer "F.Cu")
		(net 686)
	)
	(via
		(at 214 133)
		(size 0.45)
		(drill 0.2)
		(layers "F.Cu" "B.Cu")
		(net 686)
	)
	(via
		(at 221 133.65)
		(size 0.45)
		(drill 0.2)
		(layers "F.Cu" "B.Cu")
		(net 686)
	)
	(segment
		(start 215.530331 133)
		(end 215.155331 133.375)
		(width 0.1)
		(layer "In5.Cu")
		(net 686)
	)
	(segment
		(start 219.6 133)
		(end 215.530331 133)
		(width 0.1)
		(layer "In5.Cu")
		(net 686)
	)
	(segment
		(start 221 133.65)
		(end 220.25 133.65)
		(width 0.1)
		(layer "In5.Cu")
		(net 686)
	)
	(segment
		(start 220.25 133.65)
		(end 219.6 133)
		(width 0.1)
		(layer "In5.Cu")
		(net 686)
	)
	(segment
		(start 214.375 133.375)
		(end 214 133)
		(width 0.1)
		(layer "In5.Cu")
		(net 686)
	)
	(segment
		(start 215.155331 133.375)
		(end 214.375 133.375)
		(width 0.1)
		(layer "In5.Cu")
		(net 686)
	)
	(segment
		(start 214.5 132.5)
		(end 215 133)
		(width 0.256)
		(layer "F.Cu")
		(net 687)
	)
	(segment
		(start 222.875 131.025)
		(end 223.25 131.4)
		(width 0.184)
		(layer "F.Cu")
		(net 687)
	)
	(via
		(at 215 133)
		(size 0.45)
		(drill 0.2)
		(layers "F.Cu" "B.Cu")
		(net 687)
	)
	(via
		(at 223.25 131.4)
		(size 0.45)
		(drill 0.2)
		(layers "F.Cu" "B.Cu")
		(net 687)
	)
	(segment
		(start 215.475 132.525)
		(end 223.4375 132.525)
		(width 0.1)
		(layer "In7.Cu")
		(net 687)
	)
	(segment
		(start 223.4375 132.525)
		(end 223.625 132.3375)
		(width 0.1)
		(layer "In7.Cu")
		(net 687)
	)
	(segment
		(start 215 133)
		(end 215.475 132.525)
		(width 0.1)
		(layer "In7.Cu")
		(net 687)
	)
	(segment
		(start 223.625 132.3375)
		(end 223.625 131.775)
		(width 0.1)
		(layer "In7.Cu")
		(net 687)
	)
	(segment
		(start 223.625 131.775)
		(end 223.25 131.4)
		(width 0.1)
		(layer "In7.Cu")
		(net 687)
	)
	(segment
		(start 205.5 133.5)
		(end 206 134)
		(width 0.256)
		(layer "F.Cu")
		(net 688)
	)
	(segment
		(start 222.875 130.275)
		(end 223.25 129.9)
		(width 0.184)
		(layer "F.Cu")
		(net 688)
	)
	(via
		(at 223.25 129.9)
		(size 0.45)
		(drill 0.2)
		(layers "F.Cu" "B.Cu")
		(net 688)
	)
	(via
		(at 206 134)
		(size 0.45)
		(drill 0.2)
		(layers "F.Cu" "B.Cu")
		(net 688)
	)
	(segment
		(start 215.67 135.6)
		(end 206.9 135.6)
		(width 0.1)
		(layer "In7.Cu")
		(net 688)
	)
	(segment
		(start 216.87 136.8)
		(end 215.67 135.6)
		(width 0.1)
		(layer "In7.Cu")
		(net 688)
	)
	(segment
		(start 206.5 134.5)
		(end 206 134)
		(width 0.1)
		(layer "In7.Cu")
		(net 688)
	)
	(segment
		(start 206.5 135.2)
		(end 206.5 134.5)
		(width 0.1)
		(layer "In7.Cu")
		(net 688)
	)
	(segment
		(start 224.9375 130.275)
		(end 224.9375 134.5875)
		(width 0.1)
		(layer "In7.Cu")
		(net 688)
	)
	(segment
		(start 224.9375 134.5875)
		(end 223.235 136.29)
		(width 0.1)
		(layer "In7.Cu")
		(net 688)
	)
	(segment
		(start 223.25 129.9)
		(end 224.5625 129.9)
		(width 0.1)
		(layer "In7.Cu")
		(net 688)
	)
	(segment
		(start 224.5625 129.9)
		(end 224.9375 130.275)
		(width 0.1)
		(layer "In7.Cu")
		(net 688)
	)
	(segment
		(start 206.9 135.6)
		(end 206.5 135.2)
		(width 0.1)
		(layer "In7.Cu")
		(net 688)
	)
	(segment
		(start 221.58 136.8)
		(end 216.87 136.8)
		(width 0.1)
		(layer "In7.Cu")
		(net 688)
	)
	(segment
		(start 222.09 136.29)
		(end 221.58 136.8)
		(width 0.1)
		(layer "In7.Cu")
		(net 688)
	)
	(segment
		(start 223.235 136.29)
		(end 222.09 136.29)
		(width 0.1)
		(layer "In7.Cu")
		(net 688)
	)
	(segment
		(start 207.5 133.5)
		(end 208 134)
		(width 0.256)
		(layer "F.Cu")
		(net 689)
	)
	(segment
		(start 221.375 130.275)
		(end 221.75 130.65)
		(width 0.184)
		(layer "F.Cu")
		(net 689)
	)
	(via
		(at 208 134)
		(size 0.45)
		(drill 0.2)
		(layers "F.Cu" "B.Cu")
		(net 689)
	)
	(via
		(at 221.75 130.65)
		(size 0.45)
		(drill 0.2)
		(layers "F.Cu" "B.Cu")
		(net 689)
	)
	(segment
		(start 224.375 130.275)
		(end 224.5625 130.4625)
		(width 0.1)
		(layer "In7.Cu")
		(net 689)
	)
	(segment
		(start 208.5875 134.5875)
		(end 208 134)
		(width 0.1)
		(layer "In7.Cu")
		(net 689)
	)
	(segment
		(start 222.125 130.275)
		(end 224.375 130.275)
		(width 0.1)
		(layer "In7.Cu")
		(net 689)
	)
	(segment
		(start 221.75 130.65)
		(end 222.125 130.275)
		(width 0.1)
		(layer "In7.Cu")
		(net 689)
	)
	(segment
		(start 224.5625 134.2125)
		(end 224.1875 134.5875)
		(width 0.1)
		(layer "In7.Cu")
		(net 689)
	)
	(segment
		(start 224.1875 134.5875)
		(end 208.5875 134.5875)
		(width 0.1)
		(layer "In7.Cu")
		(net 689)
	)
	(segment
		(start 224.5625 130.4625)
		(end 224.5625 134.2125)
		(width 0.1)
		(layer "In7.Cu")
		(net 689)
	)
	(segment
		(start 222.125 131.025)
		(end 222.5 130.65)
		(width 0.184)
		(layer "F.Cu")
		(net 690)
	)
	(segment
		(start 208.5 133.5)
		(end 209 134)
		(width 0.256)
		(layer "F.Cu")
		(net 690)
	)
	(via
		(at 209 134)
		(size 0.45)
		(drill 0.2)
		(layers "F.Cu" "B.Cu")
		(net 690)
	)
	(via
		(at 222.5 130.65)
		(size 0.45)
		(drill 0.2)
		(layers "F.Cu" "B.Cu")
		(net 690)
	)
	(segment
		(start 223.625 134.2125)
		(end 215.5625 134.2125)
		(width 0.1)
		(layer "In7.Cu")
		(net 690)
	)
	(segment
		(start 223.625 131.025)
		(end 224 131.4)
		(width 0.1)
		(layer "In7.Cu")
		(net 690)
	)
	(segment
		(start 224 131.4)
		(end 224 133.8375)
		(width 0.1)
		(layer "In7.Cu")
		(net 690)
	)
	(segment
		(start 222.875 131.025)
		(end 223.625 131.025)
		(width 0.1)
		(layer "In7.Cu")
		(net 690)
	)
	(segment
		(start 209 134.025)
		(end 209 134)
		(width 0.1)
		(layer "In7.Cu")
		(net 690)
	)
	(segment
		(start 222.5 130.65)
		(end 222.875 131.025)
		(width 0.1)
		(layer "In7.Cu")
		(net 690)
	)
	(segment
		(start 215.5625 134.2125)
		(end 215.3875 134.3875)
		(width 0.1)
		(layer "In7.Cu")
		(net 690)
	)
	(segment
		(start 224 133.8375)
		(end 223.625 134.2125)
		(width 0.1)
		(layer "In7.Cu")
		(net 690)
	)
	(segment
		(start 209.3625 134.3875)
		(end 209 134.025)
		(width 0.1)
		(layer "In7.Cu")
		(net 690)
	)
	(segment
		(start 215.3875 134.3875)
		(end 209.3625 134.3875)
		(width 0.1)
		(layer "In7.Cu")
		(net 690)
	)
	(segment
		(start 219.875 128.025)
		(end 219.3125 128.025)
		(width 0.184)
		(layer "F.Cu")
		(net 691)
	)
	(segment
		(start 210.5 133.5)
		(end 211 134)
		(width 0.256)
		(layer "F.Cu")
		(net 691)
	)
	(via
		(at 211 134)
		(size 0.45)
		(drill 0.2)
		(layers "F.Cu" "B.Cu")
		(net 691)
	)
	(via
		(at 219.3125 128.025)
		(size 0.45)
		(drill 0.2)
		(layers "F.Cu" "B.Cu")
		(net 691)
	)
	(segment
		(start 206.65 129.625)
		(end 215.8375 129.625)
		(width 0.1)
		(layer "In5.Cu")
		(net 691)
	)
	(segment
		(start 207.2875 133.625)
		(end 206.575 132.9125)
		(width 0.1)
		(layer "In5.Cu")
		(net 691)
	)
	(segment
		(start 217.4375 128.025)
		(end 219.3125 128.025)
		(width 0.1)
		(layer "In5.Cu")
		(net 691)
	)
	(segment
		(start 211 134)
		(end 210.625 133.625)
		(width 0.1)
		(layer "In5.Cu")
		(net 691)
	)
	(segment
		(start 206.575 132.9125)
		(end 206.575 129.7)
		(width 0.1)
		(layer "In5.Cu")
		(net 691)
	)
	(segment
		(start 210.625 133.625)
		(end 207.2875 133.625)
		(width 0.1)
		(layer "In5.Cu")
		(net 691)
	)
	(segment
		(start 215.8375 129.625)
		(end 217.4375 128.025)
		(width 0.1)
		(layer "In5.Cu")
		(net 691)
	)
	(segment
		(start 206.575 129.7)
		(end 206.65 129.625)
		(width 0.1)
		(layer "In5.Cu")
		(net 691)
	)
	(segment
		(start 234.614665 146.710835)
		(end 234.614665 147.685335)
		(width 0.182)
		(layer "F.Cu")
		(net 693)
	)
	(segment
		(start 201.985047 143.997173)
		(end 201.985047 143.985047)
		(width 0.256)
		(layer "F.Cu")
		(net 693)
	)
	(segment
		(start 234.614665 147.685335)
		(end 234.5 147.8)
		(width 0.182)
		(layer "F.Cu")
		(net 693)
	)
	(segment
		(start 201.985047 143.985047)
		(end 201.5 143.5)
		(width 0.256)
		(layer "F.Cu")
		(net 693)
	)
	(segment
		(start 234.7255 146.6)
		(end 234.614665 146.710835)
		(width 0.182)
		(layer "F.Cu")
		(net 693)
	)
	(via
		(at 234.7255 146.6)
		(size 0.45)
		(drill 0.2)
		(layers "F.Cu" "B.Cu")
		(net 693)
	)
	(via
		(at 201.985047 143.997173)
		(size 0.45)
		(drill 0.2)
		(layers "F.Cu" "B.Cu")
		(net 693)
	)
	(segment
		(start 215.6 144.2)
		(end 232.6 144.2)
		(width 0.1)
		(layer "In7.Cu")
		(net 693)
	)
	(segment
		(start 215.4 144.4)
		(end 215.6 144.2)
		(width 0.1)
		(layer "In7.Cu")
		(net 693)
	)
	(segment
		(start 202.387874 144.4)
		(end 215.4 144.4)
		(width 0.1)
		(layer "In7.Cu")
		(net 693)
	)
	(segment
		(start 201.985047 143.997173)
		(end 202.387874 144.4)
		(width 0.1)
		(layer "In7.Cu")
		(net 693)
	)
	(segment
		(start 232.6 144.2)
		(end 234.7255 146.3255)
		(width 0.1)
		(layer "In7.Cu")
		(net 693)
	)
	(segment
		(start 234.7255 146.3255)
		(end 234.7255 146.6)
		(width 0.1)
		(layer "In7.Cu")
		(net 693)
	)
	(segment
		(start 203.5 121.5)
		(end 204 121)
		(width 0.256)
		(layer "F.Cu")
		(net 695)
	)
	(segment
		(start 163.905001 90.125001)
		(end 163.270001 90.760001)
		(width 0.256)
		(layer "F.Cu")
		(net 695)
	)
	(via
		(at 163.270001 90.760001)
		(size 0.45)
		(drill 0.2)
		(layers "F.Cu" "B.Cu")
		(net 695)
	)
	(via
		(at 168.3 80.6)
		(size 0.45)
		(drill 0.2)
		(layers "F.Cu" "B.Cu")
		(net 695)
	)
	(via
		(at 204 121)
		(size 0.45)
		(drill 0.2)
		(layers "F.Cu" "B.Cu")
		(net 695)
	)
	(segment
		(start 167.4 83.9)
		(end 167.7 83.6)
		(width 0.1)
		(layer "In3.Cu")
		(net 695)
	)
	(segment
		(start 163.270001 90.760001)
		(end 156.760001 90.760001)
		(width 0.1)
		(layer "In3.Cu")
		(net 695)
	)
	(segment
		(start 156.3 84.2)
		(end 156.6 83.9)
		(width 0.1)
		(layer "In3.Cu")
		(net 695)
	)
	(segment
		(start 156.760001 90.760001)
		(end 156.3 90.3)
		(width 0.1)
		(layer "In3.Cu")
		(net 695)
	)
	(segment
		(start 167.7 81.2)
		(end 168.3 80.6)
		(width 0.1)
		(layer "In3.Cu")
		(net 695)
	)
	(segment
		(start 167.7 83.6)
		(end 167.7 81.2)
		(width 0.1)
		(layer "In3.Cu")
		(net 695)
	)
	(segment
		(start 156.6 83.9)
		(end 167.4 83.9)
		(width 0.1)
		(layer "In3.Cu")
		(net 695)
	)
	(segment
		(start 156.3 90.3)
		(end 156.3 84.2)
		(width 0.1)
		(layer "In3.Cu")
		(net 695)
	)
	(segment
		(start 204 121)
		(end 204.6 121.6)
		(width 0.1)
		(layer "In7.Cu")
		(net 695)
	)
	(segment
		(start 171.3 77.6)
		(end 181.6 77.6)
		(width 0.1)
		(layer "In7.Cu")
		(net 695)
	)
	(segment
		(start 204.8 122.4)
		(end 206.4 122.4)
		(width 0.1)
		(layer "In7.Cu")
		(net 695)
	)
	(segment
		(start 204.6 122.2)
		(end 204.8 122.4)
		(width 0.1)
		(layer "In7.Cu")
		(net 695)
	)
	(segment
		(start 171.3 77.6)
		(end 168.3 80.6)
		(width 0.1)
		(layer "In7.Cu")
		(net 695)
	)
	(segment
		(start 207.4 121.4)
		(end 207.4 103.3)
		(width 0.1)
		(layer "In7.Cu")
		(net 695)
	)
	(segment
		(start 200.7 86.8)
		(end 199.1 85.2)
		(width 0.1)
		(layer "In7.Cu")
		(net 695)
	)
	(segment
		(start 199.1 82.1)
		(end 195.9 78.9)
		(width 0.1)
		(layer "In7.Cu")
		(net 695)
	)
	(segment
		(start 182.9 78.9)
		(end 181.6 77.6)
		(width 0.1)
		(layer "In7.Cu")
		(net 695)
	)
	(segment
		(start 208.1 90.7)
		(end 204.2 86.8)
		(width 0.1)
		(layer "In7.Cu")
		(net 695)
	)
	(segment
		(start 208.1 102.6)
		(end 208.1 90.7)
		(width 0.1)
		(layer "In7.Cu")
		(net 695)
	)
	(segment
		(start 199.1 85.2)
		(end 199.1 82.1)
		(width 0.1)
		(layer "In7.Cu")
		(net 695)
	)
	(segment
		(start 204.2 86.8)
		(end 200.7 86.8)
		(width 0.1)
		(layer "In7.Cu")
		(net 695)
	)
	(segment
		(start 206.4 122.4)
		(end 207.4 121.4)
		(width 0.1)
		(layer "In7.Cu")
		(net 695)
	)
	(segment
		(start 195.9 78.9)
		(end 182.9 78.9)
		(width 0.1)
		(layer "In7.Cu")
		(net 695)
	)
	(segment
		(start 207.4 103.3)
		(end 208.1 102.6)
		(width 0.1)
		(layer "In7.Cu")
		(net 695)
	)
	(segment
		(start 204.6 121.6)
		(end 204.6 122.2)
		(width 0.1)
		(layer "In7.Cu")
		(net 695)
	)
	(segment
		(start 159.450001 80.595001)
		(end 159.450001 81.880001)
		(width 0.1)
		(layer "F.Cu")
		(net 696)
	)
	(segment
		(start 203.5 122.5)
		(end 204 122)
		(width 0.256)
		(layer "F.Cu")
		(net 696)
	)
	(segment
		(start 159.105 80.25)
		(end 159.450001 80.595001)
		(width 0.1)
		(layer "F.Cu")
		(net 696)
	)
	(segment
		(start 159.450001 81.880001)
		(end 158.825001 82.505001)
		(width 0.1)
		(layer "F.Cu")
		(net 696)
	)
	(segment
		(start 158.825001 80.25)
		(end 159.105 80.25)
		(width 0.1)
		(layer "F.Cu")
		(net 696)
	)
	(via
		(at 158.825001 80.25)
		(size 0.45)
		(drill 0.2)
		(layers "F.Cu" "B.Cu")
		(net 696)
	)
	(via
		(at 204 122)
		(size 0.45)
		(drill 0.2)
		(layers "F.Cu" "B.Cu")
		(net 696)
	)
	(segment
		(start 183.2 78.6)
		(end 181.9 77.3)
		(width 0.1)
		(layer "In7.Cu")
		(net 696)
	)
	(segment
		(start 207.6 103.4)
		(end 208.3 102.7)
		(width 0.1)
		(layer "In7.Cu")
		(net 696)
	)
	(segment
		(start 204 122)
		(end 204.6 122.6)
		(width 0.1)
		(layer "In7.Cu")
		(net 696)
	)
	(segment
		(start 199.3 85)
		(end 199.3 81.8)
		(width 0.1)
		(layer "In7.Cu")
		(net 696)
	)
	(segment
		(start 160.050001 81.475)
		(end 158.825001 80.25)
		(width 0.1)
		(layer "In7.Cu")
		(net 696)
	)
	(segment
		(start 204.6 122.6)
		(end 206.5 122.6)
		(width 0.1)
		(layer "In7.Cu")
		(net 696)
	)
	(segment
		(start 204.3 86.6)
		(end 200.9 86.6)
		(width 0.1)
		(layer "In7.Cu")
		(net 696)
	)
	(segment
		(start 181.9 77.3)
		(end 171 77.3)
		(width 0.1)
		(layer "In7.Cu")
		(net 696)
	)
	(segment
		(start 207.6 121.5)
		(end 207.6 103.4)
		(width 0.1)
		(layer "In7.Cu")
		(net 696)
	)
	(segment
		(start 208.3 102.7)
		(end 208.3 90.6)
		(width 0.1)
		(layer "In7.Cu")
		(net 696)
	)
	(segment
		(start 208.3 90.6)
		(end 204.3 86.6)
		(width 0.1)
		(layer "In7.Cu")
		(net 696)
	)
	(segment
		(start 200.9 86.6)
		(end 199.3 85)
		(width 0.1)
		(layer "In7.Cu")
		(net 696)
	)
	(segment
		(start 166.825 81.475)
		(end 160.050001 81.475)
		(width 0.1)
		(layer "In7.Cu")
		(net 696)
	)
	(segment
		(start 206.5 122.6)
		(end 207.6 121.5)
		(width 0.1)
		(layer "In7.Cu")
		(net 696)
	)
	(segment
		(start 171 77.3)
		(end 166.825 81.475)
		(width 0.1)
		(layer "In7.Cu")
		(net 696)
	)
	(segment
		(start 199.3 81.8)
		(end 196.1 78.6)
		(width 0.1)
		(layer "In7.Cu")
		(net 696)
	)
	(segment
		(start 196.1 78.6)
		(end 183.2 78.6)
		(width 0.1)
		(layer "In7.Cu")
		(net 696)
	)
	(segment
		(start 249.6 175.55)
		(end 250.275 175.55)
		(width 0.4)
		(layer "F.Cu")
		(net 697)
	)
	(segment
		(start 250.275 176.2)
		(end 249.6 176.2)
		(width 0.4)
		(layer "F.Cu")
		(net 697)
	)
	(via
		(at 246.55 179.85)
		(size 0.45)
		(drill 0.2)
		(layers "F.Cu" "B.Cu")
		(net 697)
	)
	(via
		(at 238.05 179.85)
		(size 0.45)
		(drill 0.2)
		(layers "F.Cu" "B.Cu")
		(net 697)
	)
	(via
		(at 252 175.5)
		(size 0.45)
		(drill 0.2)
		(layers "F.Cu" "B.Cu")
		(net 697)
	)
	(via
		(at 253.9 180.35)
		(size 0.45)
		(drill 0.2)
		(layers "F.Cu" "B.Cu")
		(net 697)
	)
	(via
		(at 238.55 179.85)
		(size 0.45)
		(drill 0.2)
		(layers "F.Cu" "B.Cu")
		(net 697)
	)
	(via
		(at 252 174.3)
		(size 0.45)
		(drill 0.2)
		(layers "F.Cu" "B.Cu")
		(net 697)
	)
	(via
		(at 246.05 179.85)
		(size 0.45)
		(drill 0.2)
		(layers "F.Cu" "B.Cu")
		(net 697)
	)
	(via
		(at 253.4 180.35)
		(size 0.45)
		(drill 0.2)
		(layers "F.Cu" "B.Cu")
		(net 697)
	)
	(via
		(at 252.9 180.35)
		(size 0.45)
		(drill 0.2)
		(layers "F.Cu" "B.Cu")
		(net 697)
	)
	(via
		(at 247.45 171.85)
		(size 0.45)
		(drill 0.2)
		(layers "F.Cu" "B.Cu")
		(net 697)
	)
	(via
		(at 245.55 179.85)
		(size 0.45)
		(drill 0.2)
		(layers "F.Cu" "B.Cu")
		(net 697)
	)
	(via
		(at 247.95 171.85)
		(size 0.45)
		(drill 0.2)
		(layers "F.Cu" "B.Cu")
		(net 697)
	)
	(via
		(at 253.2 175.5)
		(size 0.45)
		(drill 0.2)
		(layers "F.Cu" "B.Cu")
		(net 697)
	)
	(via
		(at 251.9 180.35)
		(size 0.45)
		(drill 0.2)
		(layers "F.Cu" "B.Cu")
		(net 697)
	)
	(via
		(at 249.6 176.2)
		(size 0.45)
		(drill 0.2)
		(layers "F.Cu" "B.Cu")
		(net 697)
	)
	(via
		(at 253.2 174.3)
		(size 0.45)
		(drill 0.2)
		(layers "F.Cu" "B.Cu")
		(net 697)
	)
	(via
		(at 249.6 175.55)
		(size 0.45)
		(drill 0.2)
		(layers "F.Cu" "B.Cu")
		(net 697)
	)
	(via
		(at 237.55 179.85)
		(size 0.45)
		(drill 0.2)
		(layers "F.Cu" "B.Cu")
		(net 697)
	)
	(via
		(at 252.4 180.35)
		(size 0.45)
		(drill 0.2)
		(layers "F.Cu" "B.Cu")
		(net 697)
	)
	(via
		(at 248.45 171.85)
		(size 0.45)
		(drill 0.2)
		(layers "F.Cu" "B.Cu")
		(net 697)
	)
	(segment
		(start 249.25 173.5)
		(end 249.170998 173.579002)
		(width 0.256)
		(layer "F.Cu")
		(net 698)
	)
	(segment
		(start 248.15 179.7)
		(end 248.15 175.1)
		(width 0.4)
		(layer "F.Cu")
		(net 698)
	)
	(segment
		(start 252.675 183.025)
		(end 256.025 183.025)
		(width 0.4)
		(layer "F.Cu")
		(net 698)
	)
	(segment
		(start 249.25 173.2)
		(end 249.25 173.5)
		(width 0.256)
		(layer "F.Cu")
		(net 698)
	)
	(segment
		(start 249.170998 173.579002)
		(end 247.9 174.85)
		(width 0.256)
		(layer "F.Cu")
		(net 698)
	)
	(segment
		(start 256.13 183.13)
		(end 256.13 183.775)
		(width 0.4)
		(layer "F.Cu")
		(net 698)
	)
	(segment
		(start 256.025 183.025)
		(end 256.13 183.13)
		(width 0.4)
		(layer "F.Cu")
		(net 698)
	)
	(segment
		(start 255.46 183.775)
		(end 256.105 183.775)
		(width 0.4)
		(layer "F.Cu")
		(net 698)
	)
	(segment
		(start 248.15 175.1)
		(end 247.9 174.85)
		(width 0.4)
		(layer "F.Cu")
		(net 698)
	)
	(segment
		(start 250.275 173.6)
		(end 250.254002 173.579002)
		(width 0.256)
		(layer "F.Cu")
		(net 698)
	)
	(segment
		(start 250.254002 173.579002)
		(end 249.170998 173.579002)
		(width 0.256)
		(layer "F.Cu")
		(net 698)
	)
	(via
		(at 249.25 173.2)
		(size 0.45)
		(drill 0.2)
		(layers "F.Cu" "B.Cu")
		(net 698)
	)
	(segment
		(start 250.2 172.25)
		(end 249.25 173.2)
		(width 0.1)
		(layer "B.Cu")
		(net 698)
	)
	(segment
		(start 254.25 172.5)
		(end 254 172.25)
		(width 0.1)
		(layer "B.Cu")
		(net 698)
	)
	(segment
		(start 258.75 173.75)
		(end 256.75 175.75)
		(width 0.1)
		(layer "B.Cu")
		(net 698)
	)
	(segment
		(start 254 172.25)
		(end 250.2 172.25)
		(width 0.1)
		(layer "B.Cu")
		(net 698)
	)
	(segment
		(start 249.25 173.5)
		(end 249.25 173.2)
		(width 0.256)
		(layer "B.Cu")
		(net 698)
	)
	(segment
		(start 257.385 170.34762)
		(end 257.53738 170.5)
		(width 0.1)
		(layer "B.Cu")
		(net 698)
	)
	(segment
		(start 258.75 171)
		(end 258.75 173.75)
		(width 0.1)
		(layer "B.Cu")
		(net 698)
	)
	(segment
		(start 257.53738 170.5)
		(end 258.25 170.5)
		(width 0.1)
		(layer "B.Cu")
		(net 698)
	)
	(segment
		(start 248.8 173.915)
		(end 248.835 173.915)
		(width 0.256)
		(layer "B.Cu")
		(net 698)
	)
	(segment
		(start 254.25 175)
		(end 254.25 172.5)
		(width 0.1)
		(layer "B.Cu")
		(net 698)
	)
	(segment
		(start 248.835 173.915)
		(end 249.25 173.5)
		(width 0.256)
		(layer "B.Cu")
		(net 698)
	)
	(segment
		(start 258.25 170.5)
		(end 258.75 171)
		(width 0.1)
		(layer "B.Cu")
		(net 698)
	)
	(segment
		(start 255 175.75)
		(end 254.25 175)
		(width 0.1)
		(layer "B.Cu")
		(net 698)
	)
	(segment
		(start 256.75 175.75)
		(end 255 175.75)
		(width 0.1)
		(layer "B.Cu")
		(net 698)
	)
	(segment
		(start 253 171.25)
		(end 258 171.25)
		(width 0.4)
		(layer "F.Cu")
		(net 699)
	)
	(segment
		(start 252.45 188.35)
		(end 252.675 188.125)
		(width 0.4)
		(layer "F.Cu")
		(net 699)
	)
	(segment
		(start 258 171.25)
		(end 258.25 171.5)
		(width 0.4)
		(layer "F.Cu")
		(net 699)
	)
	(via
		(at 258.25 171.5)
		(size 0.45)
		(drill 0.2)
		(layers "F.Cu" "B.Cu")
		(net 699)
	)
	(via
		(at 253 171.25)
		(size 0.45)
		(drill 0.2)
		(layers "F.Cu" "B.Cu")
		(net 699)
	)
	(segment
		(start 253.6 171.385)
		(end 253.135 171.385)
		(width 0.1)
		(layer "B.Cu")
		(net 699)
	)
	(segment
		(start 257.55 171.52262)
		(end 258.22738 171.52262)
		(width 0.1)
		(layer "B.Cu")
		(net 699)
	)
	(segment
		(start 258.22738 171.52262)
		(end 258.25 171.5)
		(width 0.1)
		(layer "B.Cu")
		(net 699)
	)
	(segment
		(start 253.135 171.385)
		(end 253 171.25)
		(width 0.1)
		(layer "B.Cu")
		(net 699)
	)
	(segment
		(start 225.2425 157.2)
		(end 225.2425 158.9075)
		(width 0.4)
		(layer "F.Cu")
		(net 700)
	)
	(segment
		(start 225.2425 158.9075)
		(end 224.35 159.8)
		(width 0.4)
		(layer "F.Cu")
		(net 700)
	)
	(segment
		(start 227.45 159.7)
		(end 225.2425 157.4925)
		(width 0.4)
		(layer "F.Cu")
		(net 700)
	)
	(segment
		(start 193.7 171.65)
		(end 193.7 169.685)
		(width 0.4)
		(layer "F.Cu")
		(net 700)
	)
	(segment
		(start 229.85 159.15)
		(end 228.65 159.15)
		(width 0.1)
		(layer "F.Cu")
		(net 700)
	)
	(segment
		(start 192.35 169.65)
		(end 193.665 169.65)
		(width 0.4)
		(layer "F.Cu")
		(net 700)
	)
	(segment
		(start 228.1 159.7)
		(end 228.032121 159.7)
		(width 0.1)
		(layer "F.Cu")
		(net 700)
	)
	(segment
		(start 228.65 159.15)
		(end 228.1 159.7)
		(width 0.1)
		(layer "F.Cu")
		(net 700)
	)
	(segment
		(start 228.032121 159.7)
		(end 227.45 159.7)
		(width 0.4)
		(layer "F.Cu")
		(net 700)
	)
	(segment
		(start 193.665 169.65)
		(end 193.7 169.685)
		(width 0.4)
		(layer "F.Cu")
		(net 700)
	)
	(segment
		(start 225.2425 157.4925)
		(end 225.2425 157.2)
		(width 0.4)
		(layer "F.Cu")
		(net 700)
	)
	(via
		(at 222.15 157.2)
		(size 0.45)
		(drill 0.2)
		(layers "F.Cu" "B.Cu")
		(net 700)
	)
	(via
		(at 222.85 157.2)
		(size 0.45)
		(drill 0.2)
		(layers "F.Cu" "B.Cu")
		(net 700)
	)
	(via
		(at 222.85 157.9)
		(size 0.45)
		(drill 0.2)
		(layers "F.Cu" "B.Cu")
		(net 700)
	)
	(via
		(at 193.7 173.05)
		(size 0.45)
		(drill 0.2)
		(layers "F.Cu" "B.Cu")
		(net 700)
	)
	(via
		(at 193 171.65)
		(size 0.45)
		(drill 0.2)
		(layers "F.Cu" "B.Cu")
		(net 700)
	)
	(via
		(at 223.55 157.2)
		(size 0.45)
		(drill 0.2)
		(layers "F.Cu" "B.Cu")
		(net 700)
	)
	(via
		(at 222.85 156.5)
		(size 0.45)
		(drill 0.2)
		(layers "F.Cu" "B.Cu")
		(net 700)
	)
	(via
		(at 224.35 159.8)
		(size 0.45)
		(drill 0.2)
		(layers "F.Cu" "B.Cu")
		(net 700)
	)
	(via
		(at 193 172.35)
		(size 0.45)
		(drill 0.2)
		(layers "F.Cu" "B.Cu")
		(net 700)
	)
	(via
		(at 265.4 144.6)
		(size 0.45)
		(drill 0.2)
		(layers "F.Cu" "B.Cu")
		(net 700)
	)
	(via
		(at 240.2 157)
		(size 0.45)
		(drill 0.2)
		(layers "F.Cu" "B.Cu")
		(net 700)
	)
	(via
		(at 192.3 171.65)
		(size 0.45)
		(drill 0.2)
		(layers "F.Cu" "B.Cu")
		(net 700)
	)
	(via
		(at 192.3 173.05)
		(size 0.45)
		(drill 0.2)
		(layers "F.Cu" "B.Cu")
		(net 700)
	)
	(via
		(at 223.55 156.5)
		(size 0.45)
		(drill 0.2)
		(layers "F.Cu" "B.Cu")
		(net 700)
	)
	(via
		(at 192.3 172.35)
		(size 0.45)
		(drill 0.2)
		(layers "F.Cu" "B.Cu")
		(net 700)
	)
	(via
		(at 193.7 171.65)
		(size 0.45)
		(drill 0.2)
		(layers "F.Cu" "B.Cu")
		(net 700)
	)
	(via
		(at 222.15 156.5)
		(size 0.45)
		(drill 0.2)
		(layers "F.Cu" "B.Cu")
		(net 700)
	)
	(via
		(at 193.7 172.35)
		(size 0.45)
		(drill 0.2)
		(layers "F.Cu" "B.Cu")
		(net 700)
	)
	(via
		(at 229.85 159.15)
		(size 0.45)
		(drill 0.2)
		(layers "F.Cu" "B.Cu")
		(net 700)
	)
	(via
		(at 223.55 157.9)
		(size 0.45)
		(drill 0.2)
		(layers "F.Cu" "B.Cu")
		(net 700)
	)
	(via
		(at 193 173.05)
		(size 0.45)
		(drill 0.2)
		(layers "F.Cu" "B.Cu")
		(net 700)
	)
	(via
		(at 222.15 157.9)
		(size 0.45)
		(drill 0.2)
		(layers "F.Cu" "B.Cu")
		(net 700)
	)
	(segment
		(start 240.2 157)
		(end 237.5 157)
		(width 0.1)
		(layer "B.Cu")
		(net 700)
	)
	(segment
		(start 230.3 159.6)
		(end 229.85 159.15)
		(width 0.1)
		(layer "B.Cu")
		(net 700)
	)
	(segment
		(start 234.9 159.6)
		(end 230.3 159.6)
		(width 0.1)
		(layer "B.Cu")
		(net 700)
	)
	(segment
		(start 265.4 145.335)
		(end 265.4 144.6)
		(width 0.1)
		(layer "B.Cu")
		(net 700)
	)
	(segment
		(start 265.415 145.35)
		(end 265.4 145.335)
		(width 0.1)
		(layer "B.Cu")
		(net 700)
	)
	(segment
		(start 237.5 157)
		(end 234.9 159.6)
		(width 0.1)
		(layer "B.Cu")
		(net 700)
	)
	(segment
		(start 221.4 158.65)
		(end 222.85 157.2)
		(width 2)
		(layer "In2.Cu")
		(net 700)
	)
	(segment
		(start 196.8 169.6)
		(end 199.425 166.975)
		(width 2)
		(layer "In2.Cu")
		(net 700)
	)
	(segment
		(start 195.1 172.35)
		(end 196.8 170.65)
		(width 2)
		(layer "In2.Cu")
		(net 700)
	)
	(segment
		(start 196.8 170.65)
		(end 196.8 169.6)
		(width 2)
		(layer "In2.Cu")
		(net 700)
	)
	(segment
		(start 221.4 162.2)
		(end 221.4 158.65)
		(width 2)
		(layer "In2.Cu")
		(net 700)
	)
	(segment
		(start 193 172.35)
		(end 195.1 172.35)
		(width 2)
		(layer "In2.Cu")
		(net 700)
	)
	(segment
		(start 216.625 166.975)
		(end 221.4 162.2)
		(width 2)
		(layer "In2.Cu")
		(net 700)
	)
	(segment
		(start 199.425 166.975)
		(end 216.625 166.975)
		(width 2)
		(layer "In2.Cu")
		(net 700)
	)
	(segment
		(start 253.7 152.1)
		(end 259.34 152.1)
		(width 0.1)
		(layer "In3.Cu")
		(net 700)
	)
	(segment
		(start 240.2 157)
		(end 241 156.2)
		(width 0.1)
		(layer "In3.Cu")
		(net 700)
	)
	(segment
		(start 241 156.2)
		(end 249.6 156.2)
		(width 0.1)
		(layer "In3.Cu")
		(net 700)
	)
	(segment
		(start 265.4 146.04)
		(end 265.4 144.6)
		(width 0.1)
		(layer "In3.Cu")
		(net 700)
	)
	(segment
		(start 249.6 156.2)
		(end 253.7 152.1)
		(width 0.1)
		(layer "In3.Cu")
		(net 700)
	)
	(segment
		(start 259.34 152.1)
		(end 265.4 146.04)
		(width 0.1)
		(layer "In3.Cu")
		(net 700)
	)
	(segment
		(start 163.484 184.784)
		(end 162.266 184.784)
		(width 0.182)
		(layer "F.Cu")
		(net 701)
	)
	(segment
		(start 162.266 184.784)
		(end 161.3 185.75)
		(width 0.182)
		(layer "F.Cu")
		(net 701)
	)
	(segment
		(start 163.75 185.05)
		(end 163.484 184.784)
		(width 0.182)
		(layer "F.Cu")
		(net 701)
	)
	(segment
		(start 163.75 185.75)
		(end 163.75 185.05)
		(width 0.182)
		(layer "F.Cu")
		(net 701)
	)
	(segment
		(start 161.3 185.75)
		(end 160.9 185.75)
		(width 0.182)
		(layer "F.Cu")
		(net 701)
	)
	(via
		(at 160.9 185.9745)
		(size 0.45)
		(drill 0.2)
		(layers "F.Cu" "B.Cu")
		(net 701)
	)
	(segment
		(start 160 186.385)
		(end 160.4895 186.385)
		(width 0.1)
		(layer "B.Cu")
		(net 701)
	)
	(segment
		(start 159 186.385)
		(end 160 186.385)
		(width 0.256)
		(layer "B.Cu")
		(net 701)
	)
	(segment
		(start 160.4895 186.385)
		(end 160.9 185.9745)
		(width 0.1)
		(layer "B.Cu")
		(net 701)
	)
	(via
		(at 184.8 169.7)
		(size 0.45)
		(drill 0.2)
		(layers "F.Cu" "B.Cu")
		(free yes)
		(net 702)
	)
	(via
		(at 191.070424 162.080197)
		(size 0.45)
		(drill 0.2)
		(layers "F.Cu" "B.Cu")
		(net 702)
	)
	(via
		(at 187.2 168.8)
		(size 0.45)
		(drill 0.2)
		(layers "F.Cu" "B.Cu")
		(free yes)
		(net 702)
	)
	(via
		(at 193.4 162.9)
		(size 0.45)
		(drill 0.2)
		(layers "F.Cu" "B.Cu")
		(net 702)
	)
	(via
		(at 184.8 168)
		(size 0.45)
		(drill 0.2)
		(layers "F.Cu" "B.Cu")
		(free yes)
		(net 702)
	)
	(via
		(at 187.2 168)
		(size 0.45)
		(drill 0.2)
		(layers "F.Cu" "B.Cu")
		(free yes)
		(net 702)
	)
	(via
		(at 152.8 132.6)
		(size 0.45)
		(drill 0.2)
		(layers "F.Cu" "B.Cu")
		(free yes)
		(net 702)
	)
	(via
		(at 161 182)
		(size 0.45)
		(drill 0.2)
		(layers "F.Cu" "B.Cu")
		(free yes)
		(net 702)
	)
	(via
		(at 188.075 184.7745)
		(size 0.45)
		(drill 0.2)
		(layers "F.Cu" "B.Cu")
		(net 702)
	)
	(via
		(at 193.9 162.9)
		(size 0.45)
		(drill 0.2)
		(layers "F.Cu" "B.Cu")
		(net 702)
	)
	(via
		(at 184.8 168.8)
		(size 0.45)
		(drill 0.2)
		(layers "F.Cu" "B.Cu")
		(free yes)
		(net 702)
	)
	(via
		(at 191.7 162.1)
		(size 0.45)
		(drill 0.2)
		(layers "F.Cu" "B.Cu")
		(net 702)
	)
	(via
		(at 161 181.5)
		(size 0.45)
		(drill 0.2)
		(layers "F.Cu" "B.Cu")
		(free yes)
		(net 702)
	)
	(via
		(at 152.8 135.6)
		(size 0.45)
		(drill 0.2)
		(layers "F.Cu" "B.Cu")
		(free yes)
		(net 702)
	)
	(via
		(at 192.9 163.8)
		(size 0.45)
		(drill 0.2)
		(layers "F.Cu" "B.Cu")
		(net 702)
	)
	(via
		(at 190.6 162.5)
		(size 0.45)
		(drill 0.2)
		(layers "F.Cu" "B.Cu")
		(net 702)
	)
	(via
		(at 161 182.5)
		(size 0.45)
		(drill 0.2)
		(layers "F.Cu" "B.Cu")
		(free yes)
		(net 702)
	)
	(via
		(at 152.8 136.8)
		(size 0.45)
		(drill 0.2)
		(layers "F.Cu" "B.Cu")
		(free yes)
		(net 702)
	)
	(via
		(at 185.3 181.85)
		(size 0.45)
		(drill 0.2)
		(layers "F.Cu" "B.Cu")
		(net 702)
	)
	(via
		(at 161.5 182.5)
		(size 0.45)
		(drill 0.2)
		(layers "F.Cu" "B.Cu")
		(free yes)
		(net 702)
	)
	(via
		(at 192.9 162.9)
		(size 0.45)
		(drill 0.2)
		(layers "F.Cu" "B.Cu")
		(net 702)
	)
	(via
		(at 161.5 181.5)
		(size 0.45)
		(drill 0.2)
		(layers "F.Cu" "B.Cu")
		(free yes)
		(net 702)
	)
	(via
		(at 160.5 182.5)
		(size 0.45)
		(drill 0.2)
		(layers "F.Cu" "B.Cu")
		(free yes)
		(net 702)
	)
	(via
		(at 160 181.5)
		(size 0.45)
		(drill 0.2)
		(layers "F.Cu" "B.Cu")
		(free yes)
		(net 702)
	)
	(via
		(at 191.8 163.8)
		(size 0.45)
		(drill 0.2)
		(layers "F.Cu" "B.Cu")
		(net 702)
	)
	(via
		(at 160.5 182)
		(size 0.45)
		(drill 0.2)
		(layers "F.Cu" "B.Cu")
		(free yes)
		(net 702)
	)
	(via
		(at 160.5 181.5)
		(size 0.45)
		(drill 0.2)
		(layers "F.Cu" "B.Cu")
		(free yes)
		(net 702)
	)
	(via
		(at 186 168.8)
		(size 0.45)
		(drill 0.2)
		(layers "F.Cu" "B.Cu")
		(free yes)
		(net 702)
	)
	(via
		(at 160 182.5)
		(size 0.45)
		(drill 0.2)
		(layers "F.Cu" "B.Cu")
		(free yes)
		(net 702)
	)
	(via
		(at 160 182)
		(size 0.45)
		(drill 0.2)
		(layers "F.Cu" "B.Cu")
		(free yes)
		(net 702)
	)
	(via
		(at 161.5 182)
		(size 0.45)
		(drill 0.2)
		(layers "F.Cu" "B.Cu")
		(free yes)
		(net 702)
	)
	(via
		(at 192.4 162.2)
		(size 0.45)
		(drill 0.2)
		(layers "F.Cu" "B.Cu")
		(net 702)
	)
	(via
		(at 186 168)
		(size 0.45)
		(drill 0.2)
		(layers "F.Cu" "B.Cu")
		(free yes)
		(net 702)
	)
	(via
		(at 186 169.7)
		(size 0.45)
		(drill 0.2)
		(layers "F.Cu" "B.Cu")
		(free yes)
		(net 702)
	)
	(via
		(at 152.8 135)
		(size 0.45)
		(drill 0.2)
		(layers "F.Cu" "B.Cu")
		(free yes)
		(net 702)
	)
	(via
		(at 192.4 163.4)
		(size 0.45)
		(drill 0.2)
		(layers "F.Cu" "B.Cu")
		(net 702)
	)
	(via
		(at 194.4 162.9)
		(size 0.45)
		(drill 0.2)
		(layers "F.Cu" "B.Cu")
		(net 702)
	)
	(via
		(at 152.8 136.2)
		(size 0.45)
		(drill 0.2)
		(layers "F.Cu" "B.Cu")
		(free yes)
		(net 702)
	)
	(via
		(at 152.8 133.2)
		(size 0.45)
		(drill 0.2)
		(layers "F.Cu" "B.Cu")
		(free yes)
		(net 702)
	)
	(via
		(at 187.2 169.7)
		(size 0.45)
		(drill 0.2)
		(layers "F.Cu" "B.Cu")
		(free yes)
		(net 702)
	)
	(via
		(at 152.8 133.8)
		(size 0.45)
		(drill 0.2)
		(layers "F.Cu" "B.Cu")
		(free yes)
		(net 702)
	)
	(via
		(at 194.9 162.9)
		(size 0.45)
		(drill 0.2)
		(layers "F.Cu" "B.Cu")
		(net 702)
	)
	(via
		(at 152.8 134.4)
		(size 0.45)
		(drill 0.2)
		(layers "F.Cu" "B.Cu")
		(free yes)
		(net 702)
	)
	(via
		(at 152.8 137.4)
		(size 0.45)
		(drill 0.2)
		(layers "F.Cu" "B.Cu")
		(free yes)
		(net 702)
	)
	(via
		(at 192.3 164.2)
		(size 0.45)
		(drill 0.2)
		(layers "F.Cu" "B.Cu")
		(net 702)
	)
	(segment
		(start 187.5 183.45)
		(end 187.5 184.1995)
		(width 0.1)
		(layer "B.Cu")
		(net 702)
	)
	(segment
		(start 187.5 184.1995)
		(end 188.075 184.7745)
		(width 0.1)
		(layer "B.Cu")
		(net 702)
	)
	(segment
		(start 185.6 182.15)
		(end 185.3 181.85)
		(width 0.4)
		(layer "B.Cu")
		(net 702)
	)
	(segment
		(start 185.6 183.45)
		(end 185.6 182.15)
		(width 0.4)
		(layer "B.Cu")
		(net 702)
	)
	(segment
		(start 255.385 96.615)
		(end 255.1 96.9)
		(width 0.4)
		(layer "F.Cu")
		(net 703)
	)
	(segment
		(start 231.315 123.685)
		(end 231.7 123.3)
		(width 0.4)
		(locked yes)
		(layer "F.Cu")
		(net 703)
	)
	(segment
		(start 231.3 130.315)
		(end 231.315 130.3)
		(width 0.4)
		(locked yes)
		(layer "F.Cu")
		(net 703)
	)
	(segment
		(start 231.7 123.3)
		(end 233.2 123.3)
		(width 0.4)
		(locked yes)
		(layer "F.Cu")
		(net 703)
	)
	(segment
		(start 235.775 123.85)
		(end 237.35 123.85)
		(width 0.4)
		(locked yes)
		(layer "F.Cu")
		(net 703)
	)
	(segment
		(start 245.8 114.675)
		(end 246.2 114.675)
		(width 0.4)
		(layer "F.Cu")
		(net 703)
	)
	(segment
		(start 235 123.3)
		(end 235.225 123.3)
		(width 0.4)
		(locked yes)
		(layer "F.Cu")
		(net 703)
	)
	(segment
		(start 258.12 119.913)
		(end 258.12 119.88)
		(width 0.114)
		(layer "F.Cu")
		(net 703)
	)
	(segment
		(start 255.385 96)
		(end 255.385 95.985)
		(width 0.1)
		(layer "F.Cu")
		(net 703)
	)
	(segment
		(start 255.385 96)
		(end 255.385 96.615)
		(width 0.4)
		(layer "F.Cu")
		(net 703)
	)
	(segment
		(start 243.975 112.575)
		(end 243.585 112.965)
		(width 0.4)
		(layer "F.Cu")
		(net 703)
	)
	(segment
		(start 231.315 130.3)
		(end 231.315 124.5)
		(width 0.4)
		(locked yes)
		(layer "F.Cu")
		(net 703)
	)
	(segment
		(start 251.7 99.45)
		(end 252.45 99.45)
		(width 0.5)
		(layer "F.Cu")
		(net 703)
	)
	(segment
		(start 245.225 115.25)
		(end 245.8 114.675)
		(width 0.4)
		(layer "F.Cu")
		(net 703)
	)
	(segment
		(start 226 127)
		(end 226 126)
		(width 0.4)
		(layer "F.Cu")
		(net 703)
	)
	(segment
		(start 231.315 124.5)
		(end 231.315 123.685)
		(width 0.4)
		(locked yes)
		(layer "F.Cu")
		(net 703)
	)
	(segment
		(start 241.05 119.55)
		(end 241.95 119.55)
		(width 0.4)
		(layer "F.Cu")
		(net 703)
	)
	(segment
		(start 246.515 114.36)
		(end 246.515 113.9)
		(width 0.4)
		(layer "F.Cu")
		(net 703)
	)
	(segment
		(start 231.3 131.875)
		(end 231.3 130.315)
		(width 0.4)
		(locked yes)
		(layer "F.Cu")
		(net 703)
	)
	(segment
		(start 233.2 123.3)
		(end 235 123.3)
		(width 0.4)
		(locked yes)
		(layer "F.Cu")
		(net 703)
	)
	(segment
		(start 235.225 123.3)
		(end 235.775 123.85)
		(width 0.4)
		(locked yes)
		(layer "F.Cu")
		(net 703)
	)
	(segment
		(start 245.825 112.575)
		(end 243.975 112.575)
		(width 0.4)
		(layer "F.Cu")
		(net 703)
	)
	(segment
		(start 243.585 112.965)
		(end 243.585 113.9)
		(width 0.4)
		(layer "F.Cu")
		(net 703)
	)
	(segment
		(start 245.225 116.525)
		(end 245.225 115.25)
		(width 0.4)
		(layer "F.Cu")
		(net 703)
	)
	(segment
		(start 241.95 119.55)
		(end 242.5 119)
		(width 0.4)
		(layer "F.Cu")
		(net 703)
	)
	(segment
		(start 258.12 119.88)
		(end 257.86 119.62)
		(width 0.114)
		(layer "F.Cu")
		(net 703)
	)
	(segment
		(start 238.2 120.2)
		(end 239.5 118.9)
		(width 0.4)
		(locked yes)
		(layer "F.Cu")
		(net 703)
	)
	(segment
		(start 254.8 95.4)
		(end 251.985 95.4)
		(width 0.1)
		(layer "F.Cu")
		(net 703)
	)
	(segment
		(start 226 126)
		(end 227.5 124.5)
		(width 0.4)
		(layer "F.Cu")
		(net 703)
	)
	(segment
		(start 251.4 101)
		(end 251.4 99.75)
		(width 0.5)
		(layer "F.Cu")
		(net 703)
	)
	(segment
		(start 251.385 95.4)
		(end 251.385 96)
		(width 0.1)
		(layer "F.Cu")
		(net 703)
	)
	(segment
		(start 239.5 118.9)
		(end 240.4 118.9)
		(width 0.4)
		(layer "F.Cu")
		(net 703)
	)
	(segment
		(start 238.2 123)
		(end 238.2 120.2)
		(width 0.4)
		(locked yes)
		(layer "F.Cu")
		(net 703)
	)
	(segment
		(start 227.5 124.5)
		(end 231.315 124.5)
		(width 0.4)
		(layer "F.Cu")
		(net 703)
	)
	(segment
		(start 252.45 99.45)
		(end 252.7 99.2)
		(width 0.5)
		(layer "F.Cu")
		(net 703)
	)
	(segment
		(start 246.2 114.675)
		(end 246.515 114.36)
		(width 0.4)
		(layer "F.Cu")
		(net 703)
	)
	(segment
		(start 251.985 95.4)
		(end 251.385 95.4)
		(width 0.1)
		(layer "F.Cu")
		(net 703)
	)
	(segment
		(start 252.7 99.2)
		(end 253.1 98.8)
		(width 0.5)
		(layer "F.Cu")
		(net 703)
	)
	(segment
		(start 255.385 95.985)
		(end 254.8 95.4)
		(width 0.1)
		(layer "F.Cu")
		(net 703)
	)
	(segment
		(start 237.35 123.85)
		(end 238.2 123)
		(width 0.4)
		(locked yes)
		(layer "F.Cu")
		(net 703)
	)
	(segment
		(start 244.4 117.35)
		(end 245.225 116.525)
		(width 0.4)
		(layer "F.Cu")
		(net 703)
	)
	(segment
		(start 242.5 119)
		(end 242.5 118.9)
		(width 0.4)
		(layer "F.Cu")
		(net 703)
	)
	(segment
		(start 251.4 99.75)
		(end 251.7 99.45)
		(width 0.5)
		(layer "F.Cu")
		(net 703)
	)
	(segment
		(start 240.4 118.9)
		(end 241.05 119.55)
		(width 0.4)
		(layer "F.Cu")
		(net 703)
	)
	(segment
		(start 246.515 113.265)
		(end 245.825 112.575)
		(width 0.4)
		(layer "F.Cu")
		(net 703)
	)
	(segment
		(start 243.9 117.35)
		(end 244.4 117.35)
		(width 0.4)
		(layer "F.Cu")
		(net 703)
	)
	(segment
		(start 246.515 113.9)
		(end 246.515 113.265)
		(width 0.4)
		(layer "F.Cu")
		(net 703)
	)
	(via
		(at 248 112)
		(size 0.45)
		(drill 0.2)
		(layers "F.Cu" "B.Cu")
		(net 703)
	)
	(via
		(at 183 169.8)
		(size 0.45)
		(drill 0.2)
		(layers "F.Cu" "B.Cu")
		(free yes)
		(net 703)
	)
	(via
		(at 243.8 119.2)
		(size 0.45)
		(drill 0.2)
		(layers "F.Cu" "B.Cu")
		(free yes)
		(net 703)
	)
	(via
		(at 257.86 119.62)
		(size 0.45)
		(drill 0.2)
		(layers "F.Cu" "B.Cu")
		(free yes)
		(net 703)
	)
	(via
		(at 243.4 118.6)
		(size 0.45)
		(drill 0.2)
		(layers "F.Cu" "B.Cu")
		(free yes)
		(net 703)
	)
	(via
		(at 255.1 96.9)
		(size 0.45)
		(drill 0.2)
		(layers "F.Cu" "B.Cu")
		(net 703)
	)
	(via
		(at 254.5 120)
		(size 0.45)
		(drill 0.2)
		(layers "F.Cu" "B.Cu")
		(free yes)
		(net 703)
	)
	(via
		(at 243.2 119.2)
		(size 0.45)
		(drill 0.2)
		(layers "F.Cu" "B.Cu")
		(free yes)
		(net 703)
	)
	(via
		(at 183.6 170.4)
		(size 0.45)
		(drill 0.2)
		(layers "F.Cu" "B.Cu")
		(free yes)
		(net 703)
	)
	(via
		(at 253.5 120)
		(size 0.45)
		(drill 0.2)
		(layers "F.Cu" "B.Cu")
		(free yes)
		(net 703)
	)
	(via
		(at 183.6 169.8)
		(size 0.45)
		(drill 0.2)
		(layers "F.Cu" "B.Cu")
		(free yes)
		(net 703)
	)
	(via
		(at 253.1 98.8)
		(size 0.45)
		(drill 0.2)
		(layers "F.Cu" "B.Cu")
		(net 703)
	)
	(via
		(at 243.7 112.6)
		(size 0.45)
		(drill 0.2)
		(layers "F.Cu" "B.Cu")
		(net 703)
	)
	(via
		(at 253 120.5)
		(size 0.45)
		(drill 0.2)
		(layers "F.Cu" "B.Cu")
		(free yes)
		(net 703)
	)
	(via
		(at 183 170.4)
		(size 0.45)
		(drill 0.2)
		(layers "F.Cu" "B.Cu")
		(free yes)
		(net 703)
	)
	(via
		(at 254 120.5)
		(size 0.45)
		(drill 0.2)
		(layers "F.Cu" "B.Cu")
		(free yes)
		(net 703)
	)
	(via
		(at 252.7 99.2)
		(size 0.45)
		(drill 0.2)
		(layers "F.Cu" "B.Cu")
		(net 703)
	)
	(via
		(at 244 118.6)
		(size 0.45)
		(drill 0.2)
		(layers "F.Cu" "B.Cu")
		(free yes)
		(net 703)
	)
	(via
		(at 183.6 171)
		(size 0.45)
		(drill 0.2)
		(layers "F.Cu" "B.Cu")
		(free yes)
		(net 703)
	)
	(via
		(at 183 171)
		(size 0.45)
		(drill 0.2)
		(layers "F.Cu" "B.Cu")
		(free yes)
		(net 703)
	)
	(via
		(at 226 127)
		(size 0.45)
		(drill 0.2)
		(layers "F.Cu" "B.Cu")
		(net 703)
	)
	(segment
		(start 248 112)
		(end 248 112.09)
		(width 0.182)
		(layer "B.Cu")
		(net 703)
	)
	(segment
		(start 225.9 126.285)
		(end 225.9 126.9)
		(width 0.4)
		(layer "B.Cu")
		(net 703)
	)
	(segment
		(start 242.3 113.815)
		(end 242.3 113)
		(width 0.4)
		(layer "B.Cu")
		(net 703)
	)
	(segment
		(start 241.275 113.275)
		(end 241.815 113.815)
		(width 0.4)
		(layer "B.Cu")
		(net 703)
	)
	(segment
		(start 244.7 116.7)
		(end 243.875 116.7)
		(width 0.4)
		(layer "B.Cu")
		(net 703)
	)
	(segment
		(start 242.7 112.6)
		(end 243.7 112.6)
		(width 0.4)
		(layer "B.Cu")
		(net 703)
	)
	(segment
		(start 248 112.09)
		(end 248.51 112.6)
		(width 0.182)
		(layer "B.Cu")
		(net 703)
	)
	(segment
		(start 225.9 126.9)
		(end 226 127)
		(width 0.4)
		(layer "B.Cu")
		(net 703)
	)
	(segment
		(start 245.2 118.2)
		(end 245.2 117.2)
		(width 0.4)
		(layer "B.Cu")
		(net 703)
	)
	(segment
		(start 240.425 113.275)
		(end 241.275 113.275)
		(width 0.4)
		(layer "B.Cu")
		(net 703)
	)
	(segment
		(start 242.3 116.725)
		(end 243.85 116.725)
		(width 0.4)
		(layer "B.Cu")
		(net 703)
	)
	(segment
		(start 242.3 113)
		(end 242.7 112.6)
		(width 0.4)
		(layer "B.Cu")
		(net 703)
	)
	(segment
		(start 244 118.6)
		(end 244.8 118.6)
		(width 0.4)
		(layer "B.Cu")
		(net 703)
	)
	(segment
		(start 241.815 113.815)
		(end 242.3 113.815)
		(width 0.4)
		(layer "B.Cu")
		(net 703)
	)
	(segment
		(start 243.85 116.725)
		(end 243.875 116.7)
		(width 0.4)
		(layer "B.Cu")
		(net 703)
	)
	(segment
		(start 245.2 117.2)
		(end 244.7 116.7)
		(width 0.4)
		(layer "B.Cu")
		(net 703)
	)
	(segment
		(start 244.8 118.6)
		(end 245.2 118.2)
		(width 0.4)
		(layer "B.Cu")
		(net 703)
	)
	(segment
		(start 232.7 161.245)
		(end 232.7 159.93)
		(width 0.4)
		(layer "F.Cu")
		(net 704)
	)
	(segment
		(start 231.7925 158.5425)
		(end 232.7 159.45)
		(width 0.4)
		(layer "F.Cu")
		(net 704)
	)
	(segment
		(start 232.7 159.45)
		(end 232.7 159.93)
		(width 0.4)
		(layer "F.Cu")
		(net 704)
	)
	(segment
		(start 231.7925 157.23)
		(end 231.7925 158.5425)
		(width 0.4)
		(layer "F.Cu")
		(net 704)
	)
	(via
		(at 260 143.55)
		(size 0.45)
		(drill 0.2)
		(layers "F.Cu" "B.Cu")
		(net 704)
	)
	(via
		(at 261.4 147.75)
		(size 0.45)
		(drill 0.2)
		(layers "F.Cu" "B.Cu")
		(free yes)
		(net 704)
	)
	(via
		(at 260.7 148.45)
		(size 0.45)
		(drill 0.2)
		(layers "F.Cu" "B.Cu")
		(free yes)
		(net 704)
	)
	(via
		(at 260.7 143.55)
		(size 0.45)
		(drill 0.2)
		(layers "F.Cu" "B.Cu")
		(net 704)
	)
	(via
		(at 234.2 157.45)
		(size 0.45)
		(drill 0.2)
		(layers "F.Cu" "B.Cu")
		(free yes)
		(net 704)
	)
	(via
		(at 261.4 143.55)
		(size 0.45)
		(drill 0.2)
		(layers "F.Cu" "B.Cu")
		(net 704)
	)
	(via
		(at 260.7 147.75)
		(size 0.45)
		(drill 0.2)
		(layers "F.Cu" "B.Cu")
		(free yes)
		(net 704)
	)
	(via
		(at 260.7 144.25)
		(size 0.45)
		(drill 0.2)
		(layers "F.Cu" "B.Cu")
		(net 704)
	)
	(via
		(at 262.1 148.45)
		(size 0.45)
		(drill 0.2)
		(layers "F.Cu" "B.Cu")
		(free yes)
		(net 704)
	)
	(via
		(at 234.9 158.15)
		(size 0.45)
		(drill 0.2)
		(layers "F.Cu" "B.Cu")
		(free yes)
		(net 704)
	)
	(via
		(at 261.4 144.25)
		(size 0.45)
		(drill 0.2)
		(layers "F.Cu" "B.Cu")
		(net 704)
	)
	(via
		(at 233.5 157.45)
		(size 0.45)
		(drill 0.2)
		(layers "F.Cu" "B.Cu")
		(free yes)
		(net 704)
	)
	(via
		(at 261.4 148.45)
		(size 0.45)
		(drill 0.2)
		(layers "F.Cu" "B.Cu")
		(free yes)
		(net 704)
	)
	(via
		(at 233.5 158.15)
		(size 0.45)
		(drill 0.2)
		(layers "F.Cu" "B.Cu")
		(free yes)
		(net 704)
	)
	(via
		(at 260 147.75)
		(size 0.45)
		(drill 0.2)
		(layers "F.Cu" "B.Cu")
		(free yes)
		(net 704)
	)
	(via
		(at 262.1 143.55)
		(size 0.45)
		(drill 0.2)
		(layers "F.Cu" "B.Cu")
		(net 704)
	)
	(via
		(at 234.2 158.15)
		(size 0.45)
		(drill 0.2)
		(layers "F.Cu" "B.Cu")
		(free yes)
		(net 704)
	)
	(via
		(at 260 144.25)
		(size 0.45)
		(drill 0.2)
		(layers "F.Cu" "B.Cu")
		(net 704)
	)
	(via
		(at 262.1 147.75)
		(size 0.45)
		(drill 0.2)
		(layers "F.Cu" "B.Cu")
		(free yes)
		(net 704)
	)
	(via
		(at 260 148.45)
		(size 0.45)
		(drill 0.2)
		(layers "F.Cu" "B.Cu")
		(free yes)
		(net 704)
	)
	(via
		(at 262.1 144.25)
		(size 0.45)
		(drill 0.2)
		(layers "F.Cu" "B.Cu")
		(net 704)
	)
	(via
		(at 234.9 157.45)
		(size 0.45)
		(drill 0.2)
		(layers "F.Cu" "B.Cu")
		(free yes)
		(net 704)
	)
	(segment
		(start 260.485 100.75)
		(end 261 100.75)
		(width 0.4)
		(layer "F.Cu")
		(net 705)
	)
	(segment
		(start 257.15 100.75)
		(end 259.715 100.75)
		(width 0.4)
		(layer "F.Cu")
		(net 705)
	)
	(segment
		(start 254.3 99.45)
		(end 254.3 100.885)
		(width 0.4)
		(layer "F.Cu")
		(net 705)
	)
	(segment
		(start 254.7 99.45)
		(end 255.3 100.05)
		(width 0.4)
		(layer "F.Cu")
		(net 705)
	)
	(segment
		(start 256.45 100.05)
		(end 257.15 100.75)
		(width 0.4)
		(layer "F.Cu")
		(net 705)
	)
	(segment
		(start 260.485 100.75)
		(end 259.715 100.75)
		(width 0.182)
		(layer "F.Cu")
		(net 705)
	)
	(segment
		(start 261 100.75)
		(end 261.2 100.55)
		(width 0.4)
		(layer "F.Cu")
		(net 705)
	)
	(segment
		(start 254.3 100.885)
		(end 254.415 101)
		(width 0.4)
		(layer "F.Cu")
		(net 705)
	)
	(segment
		(start 253.5 101)
		(end 254.415 101)
		(width 0.4)
		(layer "F.Cu")
		(net 705)
	)
	(segment
		(start 255.3 100.05)
		(end 256.45 100.05)
		(width 0.4)
		(layer "F.Cu")
		(net 705)
	)
	(segment
		(start 254.3 99.45)
		(end 254.7 99.45)
		(width 0.4)
		(layer "F.Cu")
		(net 705)
	)
	(via
		(at 261.2 100.55)
		(size 0.45)
		(drill 0.2)
		(layers "F.Cu" "B.Cu")
		(net 705)
	)
	(segment
		(start 262.375 104.1)
		(end 261.4 104.1)
		(width 0.4)
		(layer "In2.Cu")
		(net 705)
	)
	(segment
		(start 260.2 102.9)
		(end 260.2 100.9)
		(width 0.4)
		(layer "In2.Cu")
		(net 705)
	)
	(segment
		(start 260.2 102.9)
		(end 261.4 104.1)
		(width 0.4)
		(layer "In2.Cu")
		(net 705)
	)
	(segment
		(start 260.45 100.65)
		(end 260.55 100.55)
		(width 0.4)
		(layer "In2.Cu")
		(net 705)
	)
	(segment
		(start 260.2 100.9)
		(end 260.45 100.65)
		(width 0.4)
		(layer "In2.Cu")
		(net 705)
	)
	(segment
		(start 260.55 100.55)
		(end 261.2 100.55)
		(width 0.4)
		(layer "In2.Cu")
		(net 705)
	)
	(segment
		(start 198.95 104.685)
		(end 198.135 104.685)
		(width 0.182)
		(layer "F.Cu")
		(net 706)
	)
	(segment
		(start 197.8 104.35)
		(end 197.65 104.2)
		(width 0.182)
		(layer "F.Cu")
		(net 706)
	)
	(segment
		(start 197.8 107)
		(end 197.8 104.35)
		(width 0.182)
		(layer "F.Cu")
		(net 706)
	)
	(segment
		(start 198.135 104.685)
		(end 197.65 104.2)
		(width 0.182)
		(layer "F.Cu")
		(net 706)
	)
	(segment
		(start 251.15 131.9625)
		(end 251.15 131.55)
		(width 0.256)
		(layer "F.Cu")
		(net 707)
	)
	(segment
		(start 245.675 140.575)
		(end 245.6 140.65)
		(width 0.4)
		(layer "F.Cu")
		(net 707)
	)
	(segment
		(start 259.15 135.2)
		(end 258.985 135.035)
		(width 0.256)
		(layer "F.Cu")
		(net 707)
	)
	(segment
		(start 257.025 135.75)
		(end 257.025 135.58)
		(width 0.4)
		(layer "F.Cu")
		(net 707)
	)
	(segment
		(start 255.95 140.6)
		(end 254.9 139.55)
		(width 0.4)
		(layer "F.Cu")
		(net 707)
	)
	(segment
		(start 239.55 132.3)
		(end 239.55 133.05)
		(width 0.177)
		(layer "F.Cu")
		(net 707)
	)
	(segment
		(start 251.15 131.55)
		(end 250.645 131.045)
		(width 0.256)
		(layer "F.Cu")
		(net 707)
	)
	(segment
		(start 239.85 140)
		(end 240.05 140.2)
		(width 0.177)
		(layer "F.Cu")
		(net 707)
	)
	(segment
		(start 248.65 139.8375)
		(end 248.65 140.8)
		(width 0.4)
		(layer "F.Cu")
		(net 707)
	)
	(segment
		(start 239.5 146.95)
		(end 239.75 147.2)
		(width 0.177)
		(layer "F.Cu")
		(net 707)
	)
	(segment
		(start 262.375 132.075)
		(end 262.7 132.4)
		(width 0.1)
		(layer "F.Cu")
		(net 707)
	)
	(segment
		(start 262.7 132.4)
		(end 262.7 133.6)
		(width 0.1)
		(layer "F.Cu")
		(net 707)
	)
	(segment
		(start 240 132.7)
		(end 240 133.1)
		(width 0.182)
		(layer "F.Cu")
		(net 707)
	)
	(segment
		(start 260.3 133.215)
		(end 259.39 133.215)
		(width 0.1)
		(layer "F.Cu")
		(net 707)
	)
	(segment
		(start 239.55 133.05)
		(end 239.8 133.3)
		(width 0.177)
		(layer "F.Cu")
		(net 707)
	)
	(segment
		(start 250.275 131.105)
		(end 250.645 130.735)
		(width 0.4)
		(layer "F.Cu")
		(net 707)
	)
	(segment
		(start 239.925 146.2)
		(end 239.925 147.025)
		(width 0.182)
		(layer "F.Cu")
		(net 707)
	)
	(segment
		(start 258.985 135.035)
		(end 257.57 135.035)
		(width 0.256)
		(layer "F.Cu")
		(net 707)
	)
	(segment
		(start 248.65 141.05)
		(end 248.7 141.1)
		(width 0.4)
		(layer "F.Cu")
		(net 707)
	)
	(segment
		(start 250.645 131.045)
		(end 250.645 130.735)
		(width 0.256)
		(layer "F.Cu")
		(net 707)
	)
	(segment
		(start 248.65 140.8)
		(end 248.65 141.05)
		(width 0.4)
		(layer "F.Cu")
		(net 707)
	)
	(segment
		(start 240.05 140.2295)
		(end 240.05 140.2)
		(width 0.182)
		(layer "F.Cu")
		(net 707)
	)
	(segment
		(start 239.85 139.2)
		(end 239.85 140)
		(width 0.177)
		(layer "F.Cu")
		(net 707)
	)
	(segment
		(start 257.025 135.99)
		(end 257.57 136.535)
		(width 0.4)
		(layer "F.Cu")
		(net 707)
	)
	(segment
		(start 239.925 147.025)
		(end 239.75 147.2)
		(width 0.182)
		(layer "F.Cu")
		(net 707)
	)
	(segment
		(start 255.95 141.43)
		(end 255.95 140.6)
		(width 0.4)
		(layer "F.Cu")
		(net 707)
	)
	(segment
		(start 239.5 146.2)
		(end 239.5 146.95)
		(width 0.177)
		(layer "F.Cu")
		(net 707)
	)
	(segment
		(start 261.35 135.35)
		(end 260.9 135.35)
		(width 0.198)
		(layer "F.Cu")
		(net 707)
	)
	(segment
		(start 257.025 135.58)
		(end 257.57 135.035)
		(width 0.4)
		(layer "F.Cu")
		(net 707)
	)
	(segment
		(start 254.93 133.835)
		(end 255.64 133.125)
		(width 0.1)
		(layer "F.Cu")
		(net 707)
	)
	(segment
		(start 257.325 133.125)
		(end 257.575 133.375)
		(width 0.1)
		(layer "F.Cu")
		(net 707)
	)
	(segment
		(start 260.3 133.215)
		(end 261.44 132.075)
		(width 0.1)
		(layer "F.Cu")
		(net 707)
	)
	(segment
		(start 257.025 135.75)
		(end 257.025 135.99)
		(width 0.4)
		(layer "F.Cu")
		(net 707)
	)
	(segment
		(start 245.6 140.65)
		(end 245.6 141.1)
		(width 0.4)
		(layer "F.Cu")
		(net 707)
	)
	(segment
		(start 245.585 141.115)
		(end 245.6 141.1)
		(width 0.4)
		(layer "F.Cu")
		(net 707)
	)
	(segment
		(start 243.85 137.025)
		(end 243.65 137.225)
		(width 0.1)
		(layer "F.Cu")
		(net 707)
	)
	(segment
		(start 260.3 135.2)
		(end 259.15 135.2)
		(width 0.256)
		(layer "F.Cu")
		(net 707)
	)
	(segment
		(start 257.575 133.375)
		(end 257.57 133.38)
		(width 0.1)
		(layer "F.Cu")
		(net 707)
	)
	(segment
		(start 245.675 140.575)
		(end 245.65 140.55)
		(width 0.4)
		(layer "F.Cu")
		(net 707)
	)
	(segment
		(start 240 133.1)
		(end 239.8 133.3)
		(width 0.182)
		(layer "F.Cu")
		(net 707)
	)
	(segment
		(start 261.44 132.075)
		(end 262.375 132.075)
		(width 0.1)
		(layer "F.Cu")
		(net 707)
	)
	(segment
		(start 257.45 141.55)
		(end 256.07 141.55)
		(width 0.4)
		(layer "F.Cu")
		(net 707)
	)
	(segment
		(start 260.75 135.2)
		(end 260.3 135.2)
		(width 0.198)
		(layer "F.Cu")
		(net 707)
	)
	(segment
		(start 256.07 141.55)
		(end 255.95 141.43)
		(width 0.4)
		(layer "F.Cu")
		(net 707)
	)
	(segment
		(start 245.65 140.55)
		(end 245.65 139.8375)
		(width 0.4)
		(layer "F.Cu")
		(net 707)
	)
	(segment
		(start 260.9 135.35)
		(end 260.75 135.2)
		(width 0.198)
		(layer "F.Cu")
		(net 707)
	)
	(segment
		(start 244.4625 136.15)
		(end 243.85 136.15)
		(width 0.1)
		(layer "F.Cu")
		(net 707)
	)
	(segment
		(start 259.39 133.215)
		(end 257.57 135.035)
		(width 0.1)
		(layer "F.Cu")
		(net 707)
	)
	(segment
		(start 243.85 136.15)
		(end 243.85 137.025)
		(width 0.1)
		(layer "F.Cu")
		(net 707)
	)
	(segment
		(start 244.6 141.115)
		(end 245.585 141.115)
		(width 0.4)
		(layer "F.Cu")
		(net 707)
	)
	(segment
		(start 255.64 133.125)
		(end 257.325 133.125)
		(width 0.1)
		(layer "F.Cu")
		(net 707)
	)
	(segment
		(start 250.275 131.15)
		(end 250.275 131.105)
		(width 0.4)
		(layer "F.Cu")
		(net 707)
	)
	(segment
		(start 243.85 136.15)
		(end 243.3 135.6)
		(width 0.1)
		(layer "F.Cu")
		(net 707)
	)
	(segment
		(start 257.57 133.38)
		(end 257.57 135.035)
		(width 0.1)
		(layer "F.Cu")
		(net 707)
	)
	(segment
		(start 239.88 140.3995)
		(end 240.05 140.2295)
		(width 0.182)
		(layer "F.Cu")
		(net 707)
	)
	(via
		(at 239.88 140.3995)
		(size 0.45)
		(drill 0.2)
		(layers "F.Cu" "B.Cu")
		(net 707)
	)
	(via
		(at 248.65 139.838)
		(size 0.45)
		(drill 0.2)
		(layers "F.Cu" "B.Cu")
		(net 707)
	)
	(via
		(at 243.65 137.225)
		(size 0.45)
		(drill 0.2)
		(layers "F.Cu" "B.Cu")
		(net 707)
	)
	(via
		(at 254.9 139.55)
		(size 0.45)
		(drill 0.2)
		(layers "F.Cu" "B.Cu")
		(net 707)
	)
	(via
		(at 257.025 135.75)
		(size 0.45)
		(drill 0.2)
		(layers "F.Cu" "B.Cu")
		(net 707)
	)
	(via
		(at 256.1 128.6)
		(size 0.45)
		(drill 0.2)
		(layers "F.Cu" "B.Cu")
		(net 707)
	)
	(via
		(at 245.675 140.575)
		(size 0.45)
		(drill 0.2)
		(layers "F.Cu" "B.Cu")
		(net 707)
	)
	(via
		(at 250.275 131.15)
		(size 0.45)
		(drill 0.2)
		(layers "F.Cu" "B.Cu")
		(net 707)
	)
	(via
		(at 239.925 146.2)
		(size 0.45)
		(drill 0.2)
		(layers "F.Cu" "B.Cu")
		(net 707)
	)
	(via
		(at 240 132.7)
		(size 0.45)
		(drill 0.2)
		(layers "F.Cu" "B.Cu")
		(net 707)
	)
	(segment
		(start 239.325 134.8)
		(end 239.325 133.775)
		(width 0.1)
		(layer "B.Cu")
		(net 707)
	)
	(segment
		(start 259.25 123.4875)
		(end 259.25 124.45)
		(width 0.4)
		(layer "B.Cu")
		(net 707)
	)
	(segment
		(start 259.25 124.45)
		(end 259.35 124.55)
		(width 0.4)
		(layer "B.Cu")
		(net 707)
	)
	(segment
		(start 240.0795 140.2)
		(end 241.985 140.2)
		(width 0.4)
		(layer "B.Cu")
		(net 707)
	)
	(segment
		(start 239.88 140.3995)
		(end 240.0795 140.2)
		(width 0.4)
		(layer "B.Cu")
		(net 707)
	)
	(segment
		(start 258.85 125.05)
		(end 258.85 125.1)
		(width 0.4)
		(layer "B.Cu")
		(net 707)
	)
	(segment
		(start 238.58 145.27)
		(end 239.51 146.2)
		(width 0.4)
		(layer "B.Cu")
		(net 707)
	)
	(segment
		(start 243.65 137.225)
		(end 243.65 136.3)
		(width 0.1)
		(layer "B.Cu")
		(net 707)
	)
	(segment
		(start 256.2 125.15)
		(end 258.8 125.15)
		(width 0.4)
		(layer "B.Cu")
		(net 707)
	)
	(segment
		(start 255.5 125.85)
		(end 256.2 125.15)
		(width 0.4)
		(layer "B.Cu")
		(net 707)
	)
	(segment
		(start 238.58 141.6995)
		(end 238.58 145.27)
		(width 0.4)
		(layer "B.Cu")
		(net 707)
	)
	(segment
		(start 239.51 146.2)
		(end 239.925 146.2)
		(width 0.4)
		(layer "B.Cu")
		(net 707)
	)
	(segment
		(start 245.4 140.85)
		(end 245.675 140.575)
		(width 0.4)
		(layer "B.Cu")
		(net 707)
	)
	(segment
		(start 239.325 133.775)
		(end 240 133.1)
		(width 0.1)
		(layer "B.Cu")
		(net 707)
	)
	(segment
		(start 259.25 123.4)
		(end 259.25 123.4875)
		(width 0.1)
		(layer "B.Cu")
		(net 707)
	)
	(segment
		(start 240.225 135.7)
		(end 239.325 134.8)
		(width 0.1)
		(layer "B.Cu")
		(net 707)
	)
	(segment
		(start 239.88 140.3995)
		(end 238.58 141.6995)
		(width 0.4)
		(layer "B.Cu")
		(net 707)
	)
	(segment
		(start 242.3 140.665)
		(end 242.485 140.85)
		(width 0.4)
		(layer "B.Cu")
		(net 707)
	)
	(segment
		(start 241.985 140.2)
		(end 242.35 140.565)
		(width 0.4)
		(layer "B.Cu")
		(net 707)
	)
	(segment
		(start 258.75 122.9)
		(end 259.25 123.4)
		(width 0.1)
		(layer "B.Cu")
		(net 707)
	)
	(segment
		(start 259.35 124.55)
		(end 258.85 125.05)
		(width 0.4)
		(layer "B.Cu")
		(net 707)
	)
	(segment
		(start 255.5 128)
		(end 256.1 128.6)
		(width 0.4)
		(layer "B.Cu")
		(net 707)
	)
	(segment
		(start 255.5 125.85)
		(end 255.5 128)
		(width 0.4)
		(layer "B.Cu")
		(net 707)
	)
	(segment
		(start 243.05 135.7)
		(end 240.225 135.7)
		(width 0.1)
		(layer "B.Cu")
		(net 707)
	)
	(segment
		(start 240 133.1)
		(end 240 132.7)
		(width 0.1)
		(layer "B.Cu")
		(net 707)
	)
	(segment
		(start 258.85 125.1)
		(end 258.8 125.15)
		(width 0.4)
		(layer "B.Cu")
		(net 707)
	)
	(segment
		(start 258.75 122.8125)
		(end 258.75 122.9)
		(width 0.1)
		(layer "B.Cu")
		(net 707)
	)
	(segment
		(start 242.485 140.85)
		(end 245.4 140.85)
		(width 0.4)
		(layer "B.Cu")
		(net 707)
	)
	(segment
		(start 243.65 136.3)
		(end 243.05 135.7)
		(width 0.1)
		(layer "B.Cu")
		(net 707)
	)
	(segment
		(start 245.675 140.575)
		(end 245 140.575)
		(width 0.4)
		(layer "In2.Cu")
		(net 707)
	)
	(segment
		(start 242.6 134.85)
		(end 242.6 134.425)
		(width 0.4)
		(layer "In2.Cu")
		(net 707)
	)
	(segment
		(start 240 132.7)
		(end 240 133)
		(width 0.4)
		(layer "In2.Cu")
		(net 707)
	)
	(segment
		(start 245.025 137.75)
		(end 245.325 138.05)
		(width 0.4)
		(layer "In2.Cu")
		(net 707)
	)
	(segment
		(start 242.6 134.425)
		(end 241.75 133.575)
		(width 0.4)
		(layer "In2.Cu")
		(net 707)
	)
	(segment
		(start 244.75 140.825)
		(end 243.7 140.825)
		(width 0.4)
		(layer "In2.Cu")
		(net 707)
	)
	(segment
		(start 240.325 133.325)
		(end 241.775 133.325)
		(width 0.4)
		(layer "In2.Cu")
		(net 707)
	)
	(segment
		(start 252.775 138.05)
		(end 253.275 137.55)
		(width 0.4)
		(layer "In2.Cu")
		(net 707)
	)
	(segment
		(start 242.35 132.05)
		(end 242.35 131.65)
		(width 0.4)
		(layer "In2.Cu")
		(net 707)
	)
	(segment
		(start 245 140.575)
		(end 244.75 140.825)
		(width 0.4)
		(layer "In2.Cu")
		(net 707)
	)
	(segment
		(start 253.275 137.925)
		(end 253.4 138.05)
		(width 0.4)
		(layer "In2.Cu")
		(net 707)
	)
	(segment
		(start 253.4 138.05)
		(end 252.775 138.05)
		(width 0.4)
		(layer "In2.Cu")
		(net 707)
	)
	(segment
		(start 256.1 128.6)
		(end 254.95 129.75)
		(width 0.4)
		(layer "In2.Cu")
		(net 707)
	)
	(segment
		(start 243.05 140.175)
		(end 243.05 139.15)
		(width 0.4)
		(layer "In2.Cu")
		(net 707)
	)
	(segment
		(start 254.9 139.55)
		(end 253.4 138.05)
		(width 0.4)
		(layer "In2.Cu")
		(net 707)
	)
	(segment
		(start 241.775 133.325)
		(end 241.75 133.3)
		(width 0.4)
		(layer "In2.Cu")
		(net 707)
	)
	(segment
		(start 254.95 129.75)
		(end 251.3 129.75)
		(width 0.4)
		(layer "In2.Cu")
		(net 707)
	)
	(segment
		(start 241.75 133.575)
		(end 241.75 133.325)
		(width 0.4)
		(layer "In2.Cu")
		(net 707)
	)
	(segment
		(start 253.275 135.525)
		(end 254.075 134.725)
		(width 0.4)
		(layer "In2.Cu")
		(net 707)
	)
	(segment
		(start 253.275 137.55)
		(end 253.275 135.525)
		(width 0.4)
		(layer "In2.Cu")
		(net 707)
	)
	(segment
		(start 250.275 130.775)
		(end 250.275 131.15)
		(width 0.4)
		(layer "In2.Cu")
		(net 707)
	)
	(segment
		(start 248.65 139.838)
		(end 247.913 140.575)
		(width 0.4)
		(layer "In2.Cu")
		(net 707)
	)
	(segment
		(start 245.3 131.65)
		(end 245.3 131.775)
		(width 0.4)
		(layer "In2.Cu")
		(net 707)
	)
	(segment
		(start 247.913 140.575)
		(end 245.675 140.575)
		(width 0.4)
		(layer "In2.Cu")
		(net 707)
	)
	(segment
		(start 245.025 133.65)
		(end 245.025 137.75)
		(width 0.4)
		(layer "In2.Cu")
		(net 707)
	)
	(segment
		(start 243.65 137.225)
		(end 243.65 135.9)
		(width 0.4)
		(layer "In2.Cu")
		(net 707)
	)
	(segment
		(start 242.8 136.625)
		(end 243.3 136.625)
		(width 0.4)
		(layer "In2.Cu")
		(net 707)
	)
	(segment
		(start 254.075 134.725)
		(end 255.8 134.725)
		(width 0.4)
		(layer "In2.Cu")
		(net 707)
	)
	(segment
		(start 253.275 137.55)
		(end 253.275 137.925)
		(width 0.4)
		(layer "In2.Cu")
		(net 707)
	)
	(segment
		(start 242.275 138.375)
		(end 242.275 137.15)
		(width 0.4)
		(layer "In2.Cu")
		(net 707)
	)
	(segment
		(start 249.075 132.5)
		(end 250.275 131.3)
		(width 0.4)
		(layer "In2.Cu")
		(net 707)
	)
	(segment
		(start 243.65 135.9)
		(end 242.6 134.85)
		(width 0.4)
		(layer "In2.Cu")
		(net 707)
	)
	(segment
		(start 245.025 133.5)
		(end 245.025 133.65)
		(width 0.4)
		(layer "In2.Cu")
		(net 707)
	)
	(segment
		(start 255.8 134.725)
		(end 256.825 135.75)
		(width 0.4)
		(layer "In2.Cu")
		(net 707)
	)
	(segment
		(start 245.325 138.05)
		(end 252.775 138.05)
		(width 0.4)
		(layer "In2.Cu")
		(net 707)
	)
	(segment
		(start 242.35 131.65)
		(end 243.4 130.6)
		(width 0.4)
		(layer "In2.Cu")
		(net 707)
	)
	(segment
		(start 243.65 136.975)
		(end 243.65 137.225)
		(width 0.4)
		(layer "In2.Cu")
		(net 707)
	)
	(segment
		(start 256.825 135.75)
		(end 257.025 135.75)
		(width 0.4)
		(layer "In2.Cu")
		(net 707)
	)
	(segment
		(start 251.3 129.75)
		(end 250.275 130.775)
		(width 0.4)
		(layer "In2.Cu")
		(net 707)
	)
	(segment
		(start 243.05 139.15)
		(end 242.275 138.375)
		(width 0.4)
		(layer "In2.Cu")
		(net 707)
	)
	(segment
		(start 243.4 130.6)
		(end 244.25 130.6)
		(width 0.4)
		(layer "In2.Cu")
		(net 707)
	)
	(segment
		(start 242.275 137.15)
		(end 242.8 136.625)
		(width 0.4)
		(layer "In2.Cu")
		(net 707)
	)
	(segment
		(start 244.25 130.6)
		(end 245.3 131.65)
		(width 0.4)
		(layer "In2.Cu")
		(net 707)
	)
	(segment
		(start 243.7 140.825)
		(end 243.05 140.175)
		(width 0.4)
		(layer "In2.Cu")
		(net 707)
	)
	(segment
		(start 250.275 131.3)
		(end 250.275 131.15)
		(width 0.4)
		(layer "In2.Cu")
		(net 707)
	)
	(segment
		(start 240 133)
		(end 240.325 133.325)
		(width 0.4)
		(layer "In2.Cu")
		(net 707)
	)
	(segment
		(start 241.75 132.65)
		(end 242.35 132.05)
		(width 0.4)
		(layer "In2.Cu")
		(net 707)
	)
	(segment
		(start 241.75 133.3)
		(end 241.75 132.65)
		(width 0.4)
		(layer "In2.Cu")
		(net 707)
	)
	(segment
		(start 245.3 131.775)
		(end 246.025 132.5)
		(width 0.4)
		(layer "In2.Cu")
		(net 707)
	)
	(segment
		(start 246.025 132.5)
		(end 245.025 133.5)
		(width 0.4)
		(layer "In2.Cu")
		(net 707)
	)
	(segment
		(start 243.3 136.625)
		(end 243.65 136.975)
		(width 0.4)
		(layer "In2.Cu")
		(net 707)
	)
	(segment
		(start 246.025 132.5)
		(end 249.075 132.5)
		(width 0.4)
		(layer "In2.Cu")
		(net 707)
	)
	(segment
		(start 194.5 101.465)
		(end 195.415 101.465)
		(width 0.182)
		(layer "F.Cu")
		(net 708)
	)
	(segment
		(start 197.075 106.275)
		(end 197.075 105.525)
		(width 0.182)
		(layer "F.Cu")
		(net 708)
	)
	(segment
		(start 196.7 105.15)
		(end 196.7 102.75)
		(width 0.182)
		(layer "F.Cu")
		(net 708)
	)
	(segment
		(start 197.075 105.525)
		(end 196.7 105.15)
		(width 0.182)
		(layer "F.Cu")
		(net 708)
	)
	(segment
		(start 195.415 101.465)
		(end 195.85 101.9)
		(width 0.182)
		(layer "F.Cu")
		(net 708)
	)
	(segment
		(start 196.7 102.75)
		(end 195.85 101.9)
		(width 0.182)
		(layer "F.Cu")
		(net 708)
	)
	(segment
		(start 197.8 108)
		(end 198.6 108)
		(width 0.182)
		(layer "F.Cu")
		(net 709)
	)
	(segment
		(start 198.6 108)
		(end 199.4 107.2)
		(width 0.182)
		(layer "F.Cu")
		(net 709)
	)
	(segment
		(start 252.71 138.15)
		(end 253.595 139.035)
		(width 0.182)
		(layer "F.Cu")
		(net 710)
	)
	(segment
		(start 256.63 139.035)
		(end 256.945 139.35)
		(width 0.182)
		(layer "F.Cu")
		(net 710)
	)
	(segment
		(start 258.4075 139.935)
		(end 257.53 139.935)
		(width 0.182)
		(layer "F.Cu")
		(net 710)
	)
	(segment
		(start 252.3375 138.15)
		(end 252.71 138.15)
		(width 0.182)
		(layer "F.Cu")
		(net 710)
	)
	(segment
		(start 253.595 139.035)
		(end 256.63 139.035)
		(width 0.182)
		(layer "F.Cu")
		(net 710)
	)
	(segment
		(start 257.53 139.935)
		(end 256.945 139.35)
		(width 0.182)
		(layer "F.Cu")
		(net 710)
	)
	(segment
		(start 255.49 134.39)
		(end 255.957 134.857)
		(width 0.182)
		(layer "F.Cu")
		(net 711)
	)
	(segment
		(start 253.945 134.935)
		(end 254.49 134.39)
		(width 0.182)
		(layer "F.Cu")
		(net 711)
	)
	(segment
		(start 253.73 135.15)
		(end 253.945 134.935)
		(width 0.198)
		(layer "F.Cu")
		(net 711)
	)
	(segment
		(start 254.49 134.39)
		(end 255.49 134.39)
		(width 0.182)
		(layer "F.Cu")
		(net 711)
	)
	(segment
		(start 255.96 135.032)
		(end 255.957 135.035)
		(width 0.182)
		(layer "F.Cu")
		(net 711)
	)
	(segment
		(start 255.96 133.834)
		(end 255.96 135.032)
		(width 0.182)
		(layer "F.Cu")
		(net 711)
	)
	(segment
		(start 255.957 134.857)
		(end 255.957 135.035)
		(width 0.182)
		(layer "F.Cu")
		(net 711)
	)
	(segment
		(start 252.3375 135.15)
		(end 253.73 135.15)
		(width 0.198)
		(layer "F.Cu")
		(net 711)
	)
	(segment
		(start 255.861 133.735)
		(end 255.96 133.834)
		(width 0.182)
		(layer "F.Cu")
		(net 711)
	)
	(segment
		(start 243.6 141.115)
		(end 243.6 139.925)
		(width 0.4)
		(layer "F.Cu")
		(net 712)
	)
	(segment
		(start 243.575 133.65)
		(end 243.325 133.4)
		(width 0.201)
		(layer "F.Cu")
		(net 712)
	)
	(segment
		(start 245.15 139.8375)
		(end 244.8875 139.8375)
		(width 0.4)
		(layer "F.Cu")
		(net 712)
	)
	(segment
		(start 253.965 139.635)
		(end 254.1 139.5)
		(width 0.182)
		(layer "F.Cu")
		(net 712)
	)
	(segment
		(start 244.4625 133.65)
		(end 243.575 133.65)
		(width 0.201)
		(layer "F.Cu")
		(net 712)
	)
	(segment
		(start 243.6 139.925)
		(end 243.65 139.875)
		(width 0.4)
		(layer "F.Cu")
		(net 712)
	)
	(segment
		(start 252.3375 138.65)
		(end 252.71 138.65)
		(width 0.182)
		(layer "F.Cu")
		(net 712)
	)
	(segment
		(start 252.71 138.65)
		(end 253.545 139.485)
		(width 0.182)
		(layer "F.Cu")
		(net 712)
	)
	(segment
		(start 243.8 139.725)
		(end 243.65 139.875)
		(width 0.4)
		(layer "F.Cu")
		(net 712)
	)
	(segment
		(start 253.545 139.635)
		(end 253.965 139.635)
		(width 0.182)
		(layer "F.Cu")
		(net 712)
	)
	(segment
		(start 243.05 133.075)
		(end 243.325 133.35)
		(width 0.201)
		(layer "F.Cu")
		(net 712)
	)
	(segment
		(start 243.325 133.35)
		(end 243.325 133.4)
		(width 0.201)
		(layer "F.Cu")
		(net 712)
	)
	(segment
		(start 253.545 139.485)
		(end 253.545 139.635)
		(width 0.182)
		(layer "F.Cu")
		(net 712)
	)
	(segment
		(start 244.775 139.725)
		(end 243.8 139.725)
		(width 0.4)
		(layer "F.Cu")
		(net 712)
	)
	(segment
		(start 244.8875 139.8375)
		(end 244.775 139.725)
		(width 0.4)
		(layer "F.Cu")
		(net 712)
	)
	(via
		(at 243.65 139.875)
		(size 0.45)
		(drill 0.2)
		(layers "F.Cu" "B.Cu")
		(net 712)
	)
	(via
		(at 254.1 139.5)
		(size 0.45)
		(drill 0.2)
		(layers "F.Cu" "B.Cu")
		(net 712)
	)
	(via
		(at 243.05 133.075)
		(size 0.45)
		(drill 0.2)
		(layers "F.Cu" "B.Cu")
		(net 712)
	)
	(segment
		(start 243.05 133.075)
		(end 243.775 133.075)
		(width 0.4)
		(layer "In2.Cu")
		(net 712)
	)
	(segment
		(start 244.3 133.6)
		(end 244.3 138.675)
		(width 0.4)
		(layer "In2.Cu")
		(net 712)
	)
	(segment
		(start 243.775 133.075)
		(end 244.3 133.6)
		(width 0.4)
		(layer "In2.Cu")
		(net 712)
	)
	(segment
		(start 244.3 138.675)
		(end 253.275 138.675)
		(width 0.4)
		(layer "In2.Cu")
		(net 712)
	)
	(segment
		(start 243.65 139.875)
		(end 243.65 139.325)
		(width 0.4)
		(layer "In2.Cu")
		(net 712)
	)
	(segment
		(start 253.275 138.675)
		(end 254.1 139.5)
		(width 0.4)
		(layer "In2.Cu")
		(net 712)
	)
	(segment
		(start 243.65 139.325)
		(end 244.3 138.675)
		(width 0.4)
		(layer "In2.Cu")
		(net 712)
	)
	(segment
		(start 253.795 138.735)
		(end 252.71 137.65)
		(width 0.182)
		(layer "F.Cu")
		(net 713)
	)
	(segment
		(start 260.7075 138.135)
		(end 261.465 138.135)
		(width 0.182)
		(layer "F.Cu")
		(net 713)
	)
	(segment
		(start 252.71 137.65)
		(end 252.3375 137.65)
		(width 0.182)
		(layer "F.Cu")
		(net 713)
	)
	(segment
		(start 260.595 138.135)
		(end 259.745 138.985)
		(width 0.198)
		(layer "F.Cu")
		(net 713)
	)
	(segment
		(start 257.545 138.985)
		(end 257.295 138.735)
		(width 0.182)
		(layer "F.Cu")
		(net 713)
	)
	(segment
		(start 257.295 138.735)
		(end 253.795 138.735)
		(width 0.182)
		(layer "F.Cu")
		(net 713)
	)
	(segment
		(start 260.7075 138.135)
		(end 260.595 138.135)
		(width 0.182)
		(layer "F.Cu")
		(net 713)
	)
	(segment
		(start 261.465 138.135)
		(end 262.145 138.815)
		(width 0.182)
		(layer "F.Cu")
		(net 713)
	)
	(segment
		(start 259.745 138.985)
		(end 257.545 138.985)
		(width 0.182)
		(layer "F.Cu")
		(net 713)
	)
	(segment
		(start 256.12 137.575)
		(end 255.86 137.835)
		(width 0.198)
		(layer "F.Cu")
		(net 714)
	)
	(segment
		(start 255.86 137.835)
		(end 255.41 137.385)
		(width 0.198)
		(layer "F.Cu")
		(net 714)
	)
	(segment
		(start 252.3375 137.15)
		(end 253.16 137.15)
		(width 0.198)
		(layer "F.Cu")
		(net 714)
	)
	(segment
		(start 253.16 137.15)
		(end 253.945 137.935)
		(width 0.198)
		(layer "F.Cu")
		(net 714)
	)
	(segment
		(start 255.41 137.385)
		(end 254.495 137.385)
		(width 0.198)
		(layer "F.Cu")
		(net 714)
	)
	(segment
		(start 254.495 137.385)
		(end 253.945 137.935)
		(width 0.198)
		(layer "F.Cu")
		(net 714)
	)
	(segment
		(start 256.12 136.535)
		(end 256.12 137.575)
		(width 0.198)
		(layer "F.Cu")
		(net 714)
	)
	(segment
		(start 264.375 124.85)
		(end 264.85 124.85)
		(width 0.4)
		(layer "F.Cu")
		(net 715)
	)
	(segment
		(start 264.85 124.85)
		(end 264.875 124.825)
		(width 0.4)
		(layer "F.Cu")
		(net 715)
	)
	(segment
		(start 247.675 117.35)
		(end 246.5 117.35)
		(width 0.4)
		(layer "F.Cu")
		(net 715)
	)
	(segment
		(start 264.85 128.7)
		(end 264.15 129.4)
		(width 0.4)
		(layer "F.Cu")
		(net 715)
	)
	(segment
		(start 265.625 127.4)
		(end 264.85 128.175)
		(width 0.4)
		(layer "F.Cu")
		(net 715)
	)
	(segment
		(start 263.61 124.6)
		(end 264.125 124.6)
		(width 0.4)
		(layer "F.Cu")
		(net 715)
	)
	(segment
		(start 262.45 129.4)
		(end 263.61 129.4)
		(width 0.4)
		(layer "F.Cu")
		(net 715)
	)
	(segment
		(start 261.9 120.9)
		(end 259.875 118.875)
		(width 0.4)
		(layer "F.Cu")
		(net 715)
	)
	(segment
		(start 262.1 124.6)
		(end 261.9 124.4)
		(width 0.4)
		(layer "F.Cu")
		(net 715)
	)
	(segment
		(start 264.85 128.175)
		(end 264.85 128.7)
		(width 0.4)
		(layer "F.Cu")
		(net 715)
	)
	(segment
		(start 265.3 124.825)
		(end 265.625 125.15)
		(width 0.4)
		(layer "F.Cu")
		(net 715)
	)
	(segment
		(start 262.05 130.125)
		(end 262.05 129.8)
		(width 0.4)
		(layer "F.Cu")
		(net 715)
	)
	(segment
		(start 246.6 118.9)
		(end 246.6 117.45)
		(width 0.4)
		(layer "F.Cu")
		(net 715)
	)
	(segment
		(start 262.185 130.26)
		(end 262.05 130.125)
		(width 0.4)
		(layer "F.Cu")
		(net 715)
	)
	(segment
		(start 264.15 129.4)
		(end 263.61 129.4)
		(width 0.4)
		(layer "F.Cu")
		(net 715)
	)
	(segment
		(start 264.875 124.825)
		(end 265.3 124.825)
		(width 0.4)
		(layer "F.Cu")
		(net 715)
	)
	(segment
		(start 246.6 117.45)
		(end 246.5 117.35)
		(width 0.4)
		(layer "F.Cu")
		(net 715)
	)
	(segment
		(start 262.05 129.8)
		(end 262.45 129.4)
		(width 0.4)
		(layer "F.Cu")
		(net 715)
	)
	(segment
		(start 262.185 130.7)
		(end 262.185 130.26)
		(width 0.4)
		(layer "F.Cu")
		(net 715)
	)
	(segment
		(start 263.61 124.6)
		(end 262.1 124.6)
		(width 0.4)
		(layer "F.Cu")
		(net 715)
	)
	(segment
		(start 249.2 118.875)
		(end 247.675 117.35)
		(width 0.4)
		(layer "F.Cu")
		(net 715)
	)
	(segment
		(start 264.125 124.6)
		(end 264.375 124.85)
		(width 0.4)
		(layer "F.Cu")
		(net 715)
	)
	(segment
		(start 261.9 124.4)
		(end 261.9 120.9)
		(width 0.4)
		(layer "F.Cu")
		(net 715)
	)
	(segment
		(start 259.875 118.875)
		(end 249.2 118.875)
		(width 0.4)
		(layer "F.Cu")
		(net 715)
	)
	(segment
		(start 245.585 118.9)
		(end 246.6 118.9)
		(width 0.4)
		(layer "F.Cu")
		(net 715)
	)
	(segment
		(start 265.625 125.15)
		(end 265.625 127.4)
		(width 0.4)
		(layer "F.Cu")
		(net 715)
	)
	(segment
		(start 225.885 149.55)
		(end 229.7 149.55)
		(width 0.182)
		(layer "F.Cu")
		(net 716)
	)
	(segment
		(start 229.7 149.55)
		(end 230.885 148.365)
		(width 0.182)
		(layer "F.Cu")
		(net 716)
	)
	(segment
		(start 224.3375 149.55)
		(end 225.215 149.55)
		(width 0.182)
		(layer "F.Cu")
		(net 716)
	)
	(segment
		(start 230.885 148.365)
		(end 230.885 147.4)
		(width 0.182)
		(layer "F.Cu")
		(net 716)
	)
	(segment
		(start 225.215 149.55)
		(end 225.55 149.215)
		(width 0.182)
		(layer "F.Cu")
		(net 716)
	)
	(segment
		(start 225.55 149.215)
		(end 225.885 149.55)
		(width 0.182)
		(layer "F.Cu")
		(net 716)
	)
	(segment
		(start 204.15 98.45)
		(end 203.699 97.999)
		(width 0.182)
		(layer "F.Cu")
		(net 717)
	)
	(segment
		(start 206.64 98.85)
		(end 206.15 98.85)
		(width 0.182)
		(layer "F.Cu")
		(net 717)
	)
	(segment
		(start 206.15 97.6)
		(end 205.7 97.15)
		(width 0.177)
		(layer "F.Cu")
		(net 717)
	)
	(segment
		(start 204.877149 96.6)
		(end 206.841252 96.6)
		(width 0.182)
		(layer "F.Cu")
		(net 717)
	)
	(segment
		(start 206.15 98.85)
		(end 206.15 97.6)
		(width 0.177)
		(layer "F.Cu")
		(net 717)
	)
	(segment
		(start 206.906252 98.583748)
		(end 206.64 98.85)
		(width 0.182)
		(layer "F.Cu")
		(net 717)
	)
	(segment
		(start 206.04 98.96)
		(end 206.15 98.85)
		(width 0.177)
		(layer "F.Cu")
		(net 717)
	)
	(segment
		(start 206.891252 96.55)
		(end 206.891252 97.535)
		(width 0.182)
		(layer "F.Cu")
		(net 717)
	)
	(segment
		(start 206.906252 97.55)
		(end 206.906252 98.583748)
		(width 0.182)
		(layer "F.Cu")
		(net 717)
	)
	(segment
		(start 206.841252 96.6)
		(end 206.891252 96.55)
		(width 0.182)
		(layer "F.Cu")
		(net 717)
	)
	(segment
		(start 206.891252 97.535)
		(end 206.906252 97.55)
		(width 0.182)
		(layer "F.Cu")
		(net 717)
	)
	(segment
		(start 204.877149 91.1)
		(end 206.9 91.1)
		(width 0.182)
		(layer "F.Cu")
		(net 717)
	)
	(segment
		(start 204.15 98.45)
		(end 204.66 98.96)
		(width 0.177)
		(layer "F.Cu")
		(net 717)
	)
	(segment
		(start 203.699 97.999)
		(end 203.699 97.349)
		(width 0.182)
		(layer "F.Cu")
		(net 717)
	)
	(segment
		(start 204.66 98.96)
		(end 206.04 98.96)
		(width 0.165)
		(layer "F.Cu")
		(net 717)
	)
	(via
		(at 206.9 91.1)
		(size 0.45)
		(drill 0.2)
		(layers "F.Cu" "B.Cu")
		(net 717)
	)
	(via
		(at 205.7 97.15)
		(size 0.45)
		(drill 0.2)
		(layers "F.Cu" "B.Cu")
		(net 717)
	)
	(segment
		(start 204.95 96.4)
		(end 205.7 97.15)
		(width 0.177)
		(layer "B.Cu")
		(net 717)
	)
	(segment
		(start 204.95 91.5)
		(end 204.95 96.4)
		(width 0.177)
		(layer "B.Cu")
		(net 717)
	)
	(segment
		(start 206.9 91.1)
		(end 205.35 91.1)
		(width 0.177)
		(layer "B.Cu")
		(net 717)
	)
	(segment
		(start 205.35 91.1)
		(end 204.95 91.5)
		(width 0.177)
		(layer "B.Cu")
		(net 717)
	)
	(segment
		(start 204.603752 100.5375)
		(end 205.953752 101.8875)
		(width 0.182)
		(layer "F.Cu")
		(net 718)
	)
	(segment
		(start 205.953752 101.8875)
		(end 206.288752 101.5525)
		(width 0.182)
		(layer "F.Cu")
		(net 718)
	)
	(segment
		(start 203.2125 99.611248)
		(end 204.138752 100.5375)
		(width 0.182)
		(layer "F.Cu")
		(net 718)
	)
	(segment
		(start 203.2125 97.289649)
		(end 203.2125 99.611248)
		(width 0.182)
		(layer "F.Cu")
		(net 718)
	)
	(segment
		(start 204.138752 100.5375)
		(end 204.603752 100.5375)
		(width 0.182)
		(layer "F.Cu")
		(net 718)
	)
	(segment
		(start 206.288752 101.5525)
		(end 207.353752 101.5525)
		(width 0.182)
		(layer "F.Cu")
		(net 718)
	)
	(segment
		(start 225.615 150.185)
		(end 225.8 150)
		(width 0.182)
		(layer "F.Cu")
		(net 719)
	)
	(segment
		(start 228.05 150.55)
		(end 227.5 150)
		(width 0.182)
		(layer "F.Cu")
		(net 719)
	)
	(segment
		(start 227.765 150.985)
		(end 228.2 150.55)
		(width 0.182)
		(layer "F.Cu")
		(net 719)
	)
	(segment
		(start 224.3375 150.05)
		(end 225.415 150.05)
		(width 0.182)
		(layer "F.Cu")
		(net 719)
	)
	(segment
		(start 225.415 150.05)
		(end 225.55 150.185)
		(width 0.182)
		(layer "F.Cu")
		(net 719)
	)
	(segment
		(start 225.8 150)
		(end 227.5 150)
		(width 0.182)
		(layer "F.Cu")
		(net 719)
	)
	(segment
		(start 227.765 151.9)
		(end 227.765 150.985)
		(width 0.182)
		(layer "F.Cu")
		(net 719)
	)
	(segment
		(start 228.2 150.55)
		(end 228.05 150.55)
		(width 0.182)
		(layer "F.Cu")
		(net 719)
	)
	(segment
		(start 225.55 150.185)
		(end 225.615 150.185)
		(width 0.182)
		(layer "F.Cu")
		(net 719)
	)
	(segment
		(start 205.04 101.691748)
		(end 205.04 103.3)
		(width 0.182)
		(layer "F.Cu")
		(net 720)
	)
	(segment
		(start 203.679752 101.0485)
		(end 204.396752 101.0485)
		(width 0.182)
		(layer "F.Cu")
		(net 720)
	)
	(segment
		(start 202.8 99.82)
		(end 203.156252 100.176252)
		(width 0.177)
		(layer "F.Cu")
		(net 720)
	)
	(segment
		(start 204.665 103.675)
		(end 203.641252 103.675)
		(width 0.182)
		(layer "F.Cu")
		(net 720)
	)
	(segment
		(start 203.156252 100.176252)
		(end 203.156252 100.525)
		(width 0.177)
		(layer "F.Cu")
		(net 720)
	)
	(segment
		(start 205.04 103.3)
		(end 204.665 103.675)
		(width 0.182)
		(layer "F.Cu")
		(net 720)
	)
	(segment
		(start 203.168752 104.1475)
		(end 203.641252 103.675)
		(width 0.177)
		(layer "F.Cu")
		(net 720)
	)
	(segment
		(start 202.7 98.12)
		(end 202.8 98.22)
		(width 0.177)
		(layer "F.Cu")
		(net 720)
	)
	(segment
		(start 202.8 98.22)
		(end 202.8 99.82)
		(width 0.177)
		(layer "F.Cu")
		(net 720)
	)
	(segment
		(start 203.168752 104.331248)
		(end 203.168752 104.1475)
		(width 0.177)
		(layer "F.Cu")
		(net 720)
	)
	(segment
		(start 202.7 97.277149)
		(end 202.7 98.12)
		(width 0.177)
		(layer "F.Cu")
		(net 720)
	)
	(segment
		(start 203.168752 104.331248)
		(end 203.168752 105.0375)
		(width 0.182)
		(layer "F.Cu")
		(net 720)
	)
	(segment
		(start 203.168752 100.5375)
		(end 203.679752 101.0485)
		(width 0.182)
		(layer "F.Cu")
		(net 720)
	)
	(segment
		(start 204.396752 101.0485)
		(end 205.04 101.691748)
		(width 0.182)
		(layer "F.Cu")
		(net 720)
	)
	(segment
		(start 221 152.9)
		(end 221 153.5)
		(width 0.256)
		(layer "F.Cu")
		(net 721)
	)
	(segment
		(start 221.494 154.66)
		(end 222.355 154.66)
		(width 0.4)
		(layer "F.Cu")
		(net 721)
	)
	(segment
		(start 225.25 155.5)
		(end 225.25 153.25)
		(width 0.4)
		(layer "F.Cu")
		(net 721)
	)
	(segment
		(start 221.15 152.75)
		(end 221 152.9)
		(width 0.256)
		(layer "F.Cu")
		(net 721)
	)
	(segment
		(start 225.65 151.55)
		(end 225.7 151.6)
		(width 0.256)
		(layer "F.Cu")
		(net 721)
	)
	(segment
		(start 221.15 152.2375)
		(end 221.15 152.75)
		(width 0.256)
		(layer "F.Cu")
		(net 721)
	)
	(segment
		(start 224.95 152.95)
		(end 224.95 151.55)
		(width 0.4)
		(layer "F.Cu")
		(net 721)
	)
	(segment
		(start 221.494 154.66)
		(end 221.1 154.266)
		(width 0.256)
		(layer "F.Cu")
		(net 721)
	)
	(segment
		(start 221.1 154.266)
		(end 221.1 153.6)
		(width 0.256)
		(layer "F.Cu")
		(net 721)
	)
	(segment
		(start 222.4 154.615)
		(end 222.615 154.615)
		(width 0.4)
		(layer "F.Cu")
		(net 721)
	)
	(segment
		(start 224.95 151.55)
		(end 225.65 151.55)
		(width 0.256)
		(layer "F.Cu")
		(net 721)
	)
	(segment
		(start 225.25 153.25)
		(end 224.95 152.95)
		(width 0.4)
		(layer "F.Cu")
		(net 721)
	)
	(segment
		(start 223.5 155.5)
		(end 225.25 155.5)
		(width 0.4)
		(layer "F.Cu")
		(net 721)
	)
	(segment
		(start 222.355 154.66)
		(end 222.4 154.615)
		(width 0.4)
		(layer "F.Cu")
		(net 721)
	)
	(segment
		(start 221 153.5)
		(end 221.1 153.6)
		(width 0.256)
		(layer "F.Cu")
		(net 721)
	)
	(segment
		(start 224.3375 151.55)
		(end 224.95 151.55)
		(width 0.256)
		(layer "F.Cu")
		(net 721)
	)
	(segment
		(start 222.615 154.615)
		(end 223.5 155.5)
		(width 0.4)
		(layer "F.Cu")
		(net 721)
	)
	(via
		(at 253.825 167.285)
		(size 0.45)
		(drill 0.2)
		(layers "F.Cu" "B.Cu")
		(net 721)
	)
	(via
		(at 225.25 155.5)
		(size 0.45)
		(drill 0.2)
		(layers "F.Cu" "B.Cu")
		(net 721)
	)
	(via
		(at 251.7 162.85)
		(size 0.45)
		(drill 0.2)
		(layers "F.Cu" "B.Cu")
		(net 721)
	)
	(via
		(at 254.275 160.2)
		(size 0.45)
		(drill 0.2)
		(layers "F.Cu" "B.Cu")
		(net 721)
	)
	(via
		(at 243.6 166)
		(size 0.45)
		(drill 0.2)
		(layers "F.Cu" "B.Cu")
		(net 721)
	)
	(via
		(at 257.2 167.285)
		(size 0.45)
		(drill 0.2)
		(layers "F.Cu" "B.Cu")
		(net 721)
	)
	(segment
		(start 254.275 160.39)
		(end 255 161.115)
		(width 0.256)
		(layer "B.Cu")
		(net 721)
	)
	(segment
		(start 251.5 162.1)
		(end 251.5 162.65)
		(width 0.256)
		(layer "B.Cu")
		(net 721)
	)
	(segment
		(start 254.275 160.2)
		(end 254.275 160.39)
		(width 0.256)
		(layer "B.Cu")
		(net 721)
	)
	(segment
		(start 251.5 162.65)
		(end 251.7 162.85)
		(width 0.256)
		(layer "B.Cu")
		(net 721)
	)
	(segment
		(start 254.275 160.34)
		(end 253.5 161.115)
		(width 0.256)
		(layer "B.Cu")
		(net 721)
	)
	(segment
		(start 244.215 166)
		(end 243.6 166)
		(width 0.256)
		(layer "B.Cu")
		(net 721)
	)
	(segment
		(start 254.275 160.2)
		(end 254.275 160.34)
		(width 0.256)
		(layer "B.Cu")
		(net 721)
	)
	(segment
		(start 225.9 156.15)
		(end 225.25 155.5)
		(width 0.4)
		(layer "In2.Cu")
		(net 721)
	)
	(segment
		(start 228.5 174.5)
		(end 225.1 171.1)
		(width 0.4)
		(layer "In2.Cu")
		(net 721)
	)
	(segment
		(start 225.9 160.9)
		(end 225.9 156.15)
		(width 0.4)
		(layer "In2.Cu")
		(net 721)
	)
	(segment
		(start 225.1 161.7)
		(end 225.9 160.9)
		(width 0.4)
		(layer "In2.Cu")
		(net 721)
	)
	(segment
		(start 240.25 174.5)
		(end 228.5 174.5)
		(width 0.4)
		(layer "In2.Cu")
		(net 721)
	)
	(segment
		(start 225.1 171.1)
		(end 225.1 161.7)
		(width 0.4)
		(layer "In2.Cu")
		(net 721)
	)
	(segment
		(start 226.7 147.985)
		(end 225.715 147.985)
		(width 0.256)
		(layer "F.Cu")
		(net 722)
	)
	(segment
		(start 225.7 148)
		(end 224.9 148)
		(width 0.256)
		(layer "F.Cu")
		(net 722)
	)
	(segment
		(start 224.3375 148.5625)
		(end 224.3375 149.05)
		(width 0.256)
		(layer "F.Cu")
		(net 722)
	)
	(segment
		(start 225.715 147.985)
		(end 225.7 148)
		(width 0.256)
		(layer "F.Cu")
		(net 722)
	)
	(segment
		(start 224.9 148)
		(end 224.3375 148.5625)
		(width 0.256)
		(layer "F.Cu")
		(net 722)
	)
	(segment
		(start 266.072 171.628)
		(end 265.9 171.8)
		(width 0.256)
		(layer "B.Cu")
		(net 723)
	)
	(segment
		(start 266.072 170.009)
		(end 266.072 171.628)
		(width 0.256)
		(layer "B.Cu")
		(net 723)
	)
	(segment
		(start 265.885 171.815)
		(end 265.9 171.8)
		(width 0.256)
		(layer "B.Cu")
		(net 723)
	)
	(segment
		(start 265.885 173)
		(end 265.885 171.815)
		(width 0.256)
		(layer "B.Cu")
		(net 723)
	)
	(segment
		(start 222.0805 152.924422)
		(end 222.229 153.072922)
		(width 0.153)
		(layer "F.Cu")
		(net 724)
	)
	(segment
		(start 222.15 152.2375)
		(end 222.0805 152.307)
		(width 0.153)
		(layer "F.Cu")
		(net 724)
	)
	(segment
		(start 222.0805 152.307)
		(end 222.0805 152.924422)
		(width 0.153)
		(layer "F.Cu")
		(net 724)
	)
	(via
		(at 222.229 153.072922)
		(size 0.45)
		(drill 0.2)
		(layers "F.Cu" "B.Cu")
		(net 724)
	)
	(segment
		(start 255 162.085)
		(end 255 163.001)
		(width 0.182)
		(layer "B.Cu")
		(net 724)
	)
	(segment
		(start 255 163.001)
		(end 255.531 163.532)
		(width 0.182)
		(layer "B.Cu")
		(net 724)
	)
	(segment
		(start 255 162.085)
		(end 256.1 162.085)
		(width 0.182)
		(layer "B.Cu")
		(net 724)
	)
	(segment
		(start 232.227512 155.075)
		(end 235.027512 155.075)
		(width 0.1)
		(layer "In7.Cu")
		(net 724)
	)
	(segment
		(start 256.05 161.275)
		(end 256.427512 161.275)
		(width 0.1)
		(layer "In7.Cu")
		(net 724)
	)
	(segment
		(start 235.027512 155.075)
		(end 236.025 156.072488)
		(width 0.1)
		(layer "In7.Cu")
		(net 724)
	)
	(segment
		(start 256.427512 161.275)
		(end 256.725 161.572488)
		(width 0.1)
		(layer "In7.Cu")
		(net 724)
	)
	(segment
		(start 241.875 160.725)
		(end 241.875 160.387113)
		(width 0.1)
		(layer "In7.Cu")
		(net 724)
	)
	(segment
		(start 256.553512 163.532)
		(end 255.531 163.532)
		(width 0.1)
		(layer "In7.Cu")
		(net 724)
	)
	(segment
		(start 255.75 161.957399)
		(end 255.75 161.575)
		(width 0.1)
		(layer "In7.Cu")
		(net 724)
	)
	(segment
		(start 236.827512 161.275)
		(end 241.325 161.275)
		(width 0.1)
		(layer "In7.Cu")
		(net 724)
	)
	(segment
		(start 222.229 153.072922)
		(end 222.075 152.918922)
		(width 0.1)
		(layer "In7.Cu")
		(net 724)
	)
	(segment
		(start 222.472488 151.675)
		(end 228.827512 151.675)
		(width 0.1)
		(layer "In7.Cu")
		(net 724)
	)
	(segment
		(start 228.827512 151.675)
		(end 232.227512 155.075)
		(width 0.1)
		(layer "In7.Cu")
		(net 724)
	)
	(segment
		(start 256.725 161.572488)
		(end 256.725 163.360512)
		(width 0.1)
		(layer "In7.Cu")
		(net 724)
	)
	(segment
		(start 222.075 152.918922)
		(end 222.075 152.072488)
		(width 0.1)
		(layer "In7.Cu")
		(net 724)
	)
	(segment
		(start 244.325 161.275)
		(end 245.449271 161.275)
		(width 0.1)
		(layer "In7.Cu")
		(net 724)
	)
	(segment
		(start 222.075 152.072488)
		(end 222.472488 151.675)
		(width 0.1)
		(layer "In7.Cu")
		(net 724)
	)
	(segment
		(start 255.15 161.575)
		(end 255.15 161.957399)
		(width 0.1)
		(layer "In7.Cu")
		(net 724)
	)
	(segment
		(start 236.025 156.072488)
		(end 236.025 160.472488)
		(width 0.1)
		(layer "In7.Cu")
		(net 724)
	)
	(segment
		(start 243.375 160.725)
		(end 243.375 160.387113)
		(width 0.1)
		(layer "In7.Cu")
		(net 724)
	)
	(segment
		(start 236.025 160.472488)
		(end 236.827512 161.275)
		(width 0.1)
		(layer "In7.Cu")
		(net 724)
	)
	(segment
		(start 243.775 160.387113)
		(end 243.775 160.725)
		(width 0.1)
		(layer "In7.Cu")
		(net 724)
	)
	(segment
		(start 242.275 160.387113)
		(end 242.275 160.725)
		(width 0.1)
		(layer "In7.Cu")
		(net 724)
	)
	(segment
		(start 245.449271 161.275)
		(end 254.85 161.275)
		(width 0.1)
		(layer "In7.Cu")
		(net 724)
	)
	(segment
		(start 256.725 163.360512)
		(end 256.553512 163.532)
		(width 0.1)
		(layer "In7.Cu")
		(net 724)
	)
	(arc
		(start 241.875 160.387113)
		(mid 241.933579 160.245692)
		(end 242.075 160.187113)
		(width 0.1)
		(layer "In7.Cu")
		(net 724)
	)
	(arc
		(start 255.15 161.957399)
		(mid 255.237868 162.169531)
		(end 255.45 162.257399)
		(width 0.1)
		(layer "In7.Cu")
		(net 724)
	)
	(arc
		(start 242.275 160.725)
		(mid 242.436091 161.113909)
		(end 242.825 161.275)
		(width 0.1)
		(layer "In7.Cu")
		(net 724)
	)
	(arc
		(start 242.825 161.275)
		(mid 243.213909 161.113909)
		(end 243.375 160.725)
		(width 0.1)
		(layer "In7.Cu")
		(net 724)
	)
	(arc
		(start 243.375 160.387113)
		(mid 243.433579 160.245692)
		(end 243.575 160.187113)
		(width 0.1)
		(layer "In7.Cu")
		(net 724)
	)
	(arc
		(start 241.325 161.275)
		(mid 241.713909 161.113909)
		(end 241.875 160.725)
		(width 0.1)
		(layer "In7.Cu")
		(net 724)
	)
	(arc
		(start 243.775 160.725)
		(mid 243.936091 161.113909)
		(end 244.325 161.275)
		(width 0.1)
		(layer "In7.Cu")
		(net 724)
	)
	(arc
		(start 242.075 160.187113)
		(mid 242.216421 160.245692)
		(end 242.275 160.387113)
		(width 0.1)
		(layer "In7.Cu")
		(net 724)
	)
	(arc
		(start 255.45 162.257399)
		(mid 255.662132 162.169531)
		(end 255.75 161.957399)
		(width 0.1)
		(layer "In7.Cu")
		(net 724)
	)
	(arc
		(start 243.575 160.187113)
		(mid 243.716421 160.245692)
		(end 243.775 160.387113)
		(width 0.1)
		(layer "In7.Cu")
		(net 724)
	)
	(arc
		(start 254.85 161.275)
		(mid 255.062132 161.362868)
		(end 255.15 161.575)
		(width 0.1)
		(layer "In7.Cu")
		(net 724)
	)
	(arc
		(start 255.75 161.575)
		(mid 255.837868 161.362868)
		(end 256.05 161.275)
		(width 0.1)
		(layer "In7.Cu")
		(net 724)
	)
	(segment
		(start 221.7195 152.924422)
		(end 221.571 153.072922)
		(width 0.153)
		(layer "F.Cu")
		(net 725)
	)
	(segment
		(start 221.7195 152.307)
		(end 221.7195 152.924422)
		(width 0.153)
		(layer "F.Cu")
		(net 725)
	)
	(segment
		(start 221.65 152.2375)
		(end 221.7195 152.307)
		(width 0.153)
		(layer "F.Cu")
		(net 725)
	)
	(via
		(at 221.571 153.072922)
		(size 0.45)
		(drill 0.2)
		(layers "F.Cu" "B.Cu")
		(net 725)
	)
	(segment
		(start 256.801 165.916)
		(end 257.2 166.315)
		(width 0.182)
		(layer "B.Cu")
		(net 725)
	)
	(segment
		(start 256.801 164.802)
		(end 256.801 165.916)
		(width 0.182)
		(layer "B.Cu")
		(net 725)
	)
	(segment
		(start 257.2 166.315)
		(end 258.2 166.315)
		(width 0.182)
		(layer "B.Cu")
		(net 725)
	)
	(segment
		(start 235.172488 154.725)
		(end 236.375 155.927512)
		(width 0.1)
		(layer "In7.Cu")
		(net 725)
	)
	(segment
		(start 236.375 160.327512)
		(end 236.972488 160.925)
		(width 0.1)
		(layer "In7.Cu")
		(net 725)
	)
	(segment
		(start 236.972488 160.925)
		(end 241.325 160.925)
		(width 0.1)
		(layer "In7.Cu")
		(net 725)
	)
	(segment
		(start 256.572488 160.925)
		(end 257.075 161.427512)
		(width 0.1)
		(layer "In7.Cu")
		(net 725)
	)
	(segment
		(start 228.972488 151.325)
		(end 232.372488 154.725)
		(width 0.1)
		(layer "In7.Cu")
		(net 725)
	)
	(segment
		(start 257.075 161.427512)
		(end 257.075 163.505488)
		(width 0.1)
		(layer "In7.Cu")
		(net 725)
	)
	(segment
		(start 242.625 160.387113)
		(end 242.625 160.725)
		(width 0.1)
		(layer "In7.Cu")
		(net 725)
	)
	(segment
		(start 236.375 155.927512)
		(end 236.375 160.327512)
		(width 0.1)
		(layer "In7.Cu")
		(net 725)
	)
	(segment
		(start 221.725 152.918922)
		(end 221.725 151.927512)
		(width 0.1)
		(layer "In7.Cu")
		(net 725)
	)
	(segment
		(start 222.327512 151.325)
		(end 228.972488 151.325)
		(width 0.1)
		(layer "In7.Cu")
		(net 725)
	)
	(segment
		(start 243.025 160.725)
		(end 243.025 160.387113)
		(width 0.1)
		(layer "In7.Cu")
		(net 725)
	)
	(segment
		(start 256.801 163.779488)
		(end 256.801 164.802)
		(width 0.1)
		(layer "In7.Cu")
		(net 725)
	)
	(segment
		(start 241.525 160.725)
		(end 241.525 160.387113)
		(width 0.1)
		(layer "In7.Cu")
		(net 725)
	)
	(segment
		(start 244.125 160.387113)
		(end 244.125 160.725)
		(width 0.1)
		(layer "In7.Cu")
		(net 725)
	)
	(segment
		(start 245.449271 160.925)
		(end 256.572488 160.925)
		(width 0.1)
		(layer "In7.Cu")
		(net 725)
	)
	(segment
		(start 221.571 153.072922)
		(end 221.725 152.918922)
		(width 0.1)
		(layer "In7.Cu")
		(net 725)
	)
	(segment
		(start 221.725 151.927512)
		(end 222.327512 151.325)
		(width 0.1)
		(layer "In7.Cu")
		(net 725)
	)
	(segment
		(start 257.075 163.505488)
		(end 256.801 163.779488)
		(width 0.1)
		(layer "In7.Cu")
		(net 725)
	)
	(segment
		(start 232.372488 154.725)
		(end 235.172488 154.725)
		(width 0.1)
		(layer "In7.Cu")
		(net 725)
	)
	(segment
		(start 244.325 160.925)
		(end 245.449271 160.925)
		(width 0.1)
		(layer "In7.Cu")
		(net 725)
	)
	(arc
		(start 242.625 160.725)
		(mid 242.683579 160.866421)
		(end 242.825 160.925)
		(width 0.1)
		(layer "In7.Cu")
		(net 725)
	)
	(arc
		(start 243.025 160.387113)
		(mid 243.186091 159.998204)
		(end 243.575 159.837113)
		(width 0.1)
		(layer "In7.Cu")
		(net 725)
	)
	(arc
		(start 242.075 159.837113)
		(mid 242.463909 159.998204)
		(end 242.625 160.387113)
		(width 0.1)
		(layer "In7.Cu")
		(net 725)
	)
	(arc
		(start 243.575 159.837113)
		(mid 243.963909 159.998204)
		(end 244.125 160.387113)
		(width 0.1)
		(layer "In7.Cu")
		(net 725)
	)
	(arc
		(start 241.525 160.387113)
		(mid 241.686091 159.998204)
		(end 242.075 159.837113)
		(width 0.1)
		(layer "In7.Cu")
		(net 725)
	)
	(arc
		(start 242.825 160.925)
		(mid 242.966421 160.866421)
		(end 243.025 160.725)
		(width 0.1)
		(layer "In7.Cu")
		(net 725)
	)
	(arc
		(start 241.325 160.925)
		(mid 241.466421 160.866421)
		(end 241.525 160.725)
		(width 0.1)
		(layer "In7.Cu")
		(net 725)
	)
	(arc
		(start 244.125 160.725)
		(mid 244.183579 160.866421)
		(end 244.325 160.925)
		(width 0.1)
		(layer "In7.Cu")
		(net 725)
	)
	(segment
		(start 223.0805 153.467093)
		(end 223.229 153.615593)
		(width 0.153)
		(layer "F.Cu")
		(net 726)
	)
	(segment
		(start 223.15 152.2375)
		(end 223.0805 152.307)
		(width 0.153)
		(layer "F.Cu")
		(net 726)
	)
	(segment
		(start 223.0805 152.307)
		(end 223.0805 153.467093)
		(width 0.153)
		(layer "F.Cu")
		(net 726)
	)
	(via
		(at 223.229 153.615593)
		(size 0.45)
		(drill 0.2)
		(layers "F.Cu" "B.Cu")
		(net 726)
	)
	(segment
		(start 252.5 162.085)
		(end 252.5 163.041)
		(width 0.182)
		(layer "B.Cu")
		(net 726)
	)
	(segment
		(start 252.5 163.041)
		(end 252.991 163.532)
		(width 0.182)
		(layer "B.Cu")
		(net 726)
	)
	(segment
		(start 252.5 162.085)
		(end 253.5 162.085)
		(width 0.182)
		(layer "B.Cu")
		(net 726)
	)
	(segment
		(start 231.332204 156.378455)
		(end 231.332204 156.378454)
		(width 0.1)
		(layer "In7.Cu")
		(net 726)
	)
	(segment
		(start 227.527512 154.075)
		(end 230.051255 156.598742)
		(width 0.1)
		(layer "In7.Cu")
		(net 726)
	)
	(segment
		(start 224.627512 152.775)
		(end 225.927512 154.075)
		(width 0.1)
		(layer "In7.Cu")
		(net 726)
	)
	(segment
		(start 223.075 153.461593)
		(end 223.075 153.172488)
		(width 0.1)
		(layer "In7.Cu")
		(net 726)
	)
	(segment
		(start 249.475 163.057399)
		(end 249.475 162.675)
		(width 0.1)
		(layer "In7.Cu")
		(net 726)
	)
	(segment
		(start 223.229 153.615593)
		(end 223.075 153.461593)
		(width 0.1)
		(layer "In7.Cu")
		(net 726)
	)
	(segment
		(start 231.139113 158.41002)
		(end 231.139113 158.410021)
		(width 0.1)
		(layer "In7.Cu")
		(net 726)
	)
	(segment
		(start 230.829075 156.598744)
		(end 230.829073 156.598743)
		(width 0.1)
		(layer "In7.Cu")
		(net 726)
	)
	(segment
		(start 253.827512 162.375)
		(end 254.125 162.672488)
		(width 0.1)
		(layer "In7.Cu")
		(net 726)
	)
	(segment
		(start 232.702901 159.25039)
		(end 232.702902 159.25039)
		(width 0.1)
		(layer "In7.Cu")
		(net 726)
	)
	(segment
		(start 242.675 163.025)
		(end 242.675 162.55)
		(width 0.1)
		(layer "In7.Cu")
		(net 726)
	)
	(segment
		(start 249.775 162.375)
		(end 253.827512 162.375)
		(width 0.1)
		(layer "In7.Cu")
		(net 726)
	)
	(segment
		(start 231.332204 156.661296)
		(end 230.361296 157.632203)
		(width 0.1)
		(layer "In7.Cu")
		(net 726)
	)
	(segment
		(start 254.125 163.420512)
		(end 254.013512 163.532)
		(width 0.1)
		(layer "In7.Cu")
		(net 726)
	)
	(segment
		(start 232.702902 159.25039)
		(end 235.827512 162.375)
		(width 0.1)
		(layer "In7.Cu")
		(net 726)
	)
	(segment
		(start 231.624566 157.924566)
		(end 232.110021 157.439114)
		(width 0.1)
		(layer "In7.Cu")
		(net 726)
	)
	(segment
		(start 244.075 163.025)
		(end 244.075 162.55)
		(width 0.1)
		(layer "In7.Cu")
		(net 726)
	)
	(segment
		(start 232.392862 157.721957)
		(end 232.392863 157.721956)
		(width 0.1)
		(layer "In7.Cu")
		(net 726)
	)
	(segment
		(start 244.25 162.375)
		(end 244.415323 162.375)
		(width 0.1)
		(layer "In7.Cu")
		(net 726)
	)
	(segment
		(start 241.625 162.55)
		(end 241.625 163.025)
		(width 0.1)
		(layer "In7.Cu")
		(net 726)
	)
	(segment
		(start 235.827512 162.375)
		(end 241.45 162.375)
		(width 0.1)
		(layer "In7.Cu")
		(net 726)
	)
	(segment
		(start 254.013512 163.532)
		(end 252.991 163.532)
		(width 0.1)
		(layer "In7.Cu")
		(net 726)
	)
	(segment
		(start 232.392863 157.721956)
		(end 231.421954 158.692861)
		(width 0.1)
		(layer "In7.Cu")
		(net 726)
	)
	(segment
		(start 223.075 153.172488)
		(end 223.472488 152.775)
		(width 0.1)
		(layer "In7.Cu")
		(net 726)
	)
	(segment
		(start 232.199771 159.470678)
		(end 232.199771 159.470679)
		(width 0.1)
		(layer "In7.Cu")
		(net 726)
	)
	(segment
		(start 232.199771 159.470679)
		(end 232.420059 159.25039)
		(width 0.1)
		(layer "In7.Cu")
		(net 726)
	)
	(segment
		(start 231.332203 156.661297)
		(end 231.332204 156.661296)
		(width 0.1)
		(layer "In7.Cu")
		(net 726)
	)
	(segment
		(start 254.125 162.672488)
		(end 254.125 163.420512)
		(width 0.1)
		(layer "In7.Cu")
		(net 726)
	)
	(segment
		(start 231.139113 158.410021)
		(end 231.624566 157.924566)
		(width 0.1)
		(layer "In7.Cu")
		(net 726)
	)
	(segment
		(start 248.875 162.675)
		(end 248.875 163.057399)
		(width 0.1)
		(layer "In7.Cu")
		(net 726)
	)
	(segment
		(start 243.025 162.55)
		(end 243.025 163.025)
		(width 0.1)
		(layer "In7.Cu")
		(net 726)
	)
	(segment
		(start 223.472488 152.775)
		(end 224.627512 152.775)
		(width 0.1)
		(layer "In7.Cu")
		(net 726)
	)
	(segment
		(start 230.829073 156.598743)
		(end 231.049362 156.378455)
		(width 0.1)
		(layer "In7.Cu")
		(net 726)
	)
	(segment
		(start 244.415323 162.375)
		(end 248.575 162.375)
		(width 0.1)
		(layer "In7.Cu")
		(net 726)
	)
	(segment
		(start 225.927512 154.075)
		(end 227.527512 154.075)
		(width 0.1)
		(layer "In7.Cu")
		(net 726)
	)
	(arc
		(start 243.55 163.55)
		(mid 243.921231 163.396231)
		(end 244.075 163.025)
		(width 0.1)
		(layer "In7.Cu")
		(net 726)
	)
	(arc
		(start 232.110021 157.439114)
		(mid 232.251441 157.380535)
		(end 232.392863 157.439114)
		(width 0.1)
		(layer "In7.Cu")
		(net 726)
	)
	(arc
		(start 248.875 163.057399)
		(mid 248.962868 163.269531)
		(end 249.175 163.357399)
		(width 0.1)
		(layer "In7.Cu")
		(net 726)
	)
	(arc
		(start 244.075 162.55)
		(mid 244.126256 162.426256)
		(end 244.25 162.375)
		(width 0.1)
		(layer "In7.Cu")
		(net 726)
	)
	(arc
		(start 249.175 163.357399)
		(mid 249.387132 163.269531)
		(end 249.475 163.057399)
		(width 0.1)
		(layer "In7.Cu")
		(net 726)
	)
	(arc
		(start 242.85 162.375)
		(mid 242.973744 162.426256)
		(end 243.025 162.55)
		(width 0.1)
		(layer "In7.Cu")
		(net 726)
	)
	(arc
		(start 232.420059 159.25039)
		(mid 232.56148 159.191812)
		(end 232.702901 159.25039)
		(width 0.1)
		(layer "In7.Cu")
		(net 726)
	)
	(arc
		(start 249.475 162.675)
		(mid 249.562868 162.462868)
		(end 249.775 162.375)
		(width 0.1)
		(layer "In7.Cu")
		(net 726)
	)
	(arc
		(start 231.421954 158.692861)
		(mid 231.260863 159.08177)
		(end 231.421954 159.470679)
		(width 0.1)
		(layer "In7.Cu")
		(net 726)
	)
	(arc
		(start 241.625 163.025)
		(mid 241.778769 163.396231)
		(end 242.15 163.55)
		(width 0.1)
		(layer "In7.Cu")
		(net 726)
	)
	(arc
		(start 248.575 162.375)
		(mid 248.787132 162.462868)
		(end 248.875 162.675)
		(width 0.1)
		(layer "In7.Cu")
		(net 726)
	)
	(arc
		(start 231.421954 159.470679)
		(mid 231.810863 159.63177)
		(end 232.199771 159.470678)
		(width 0.1)
		(layer "In7.Cu")
		(net 726)
	)
	(arc
		(start 231.049362 156.378455)
		(mid 231.190782 156.319876)
		(end 231.332204 156.378455)
		(width 0.1)
		(layer "In7.Cu")
		(net 726)
	)
	(arc
		(start 242.675 162.55)
		(mid 242.726256 162.426256)
		(end 242.85 162.375)
		(width 0.1)
		(layer "In7.Cu")
		(net 726)
	)
	(arc
		(start 230.361296 157.632203)
		(mid 230.200205 158.021112)
		(end 230.361296 158.410021)
		(width 0.1)
		(layer "In7.Cu")
		(net 726)
	)
	(arc
		(start 231.332204 156.378454)
		(mid 231.390782 156.519876)
		(end 231.332203 156.661297)
		(width 0.1)
		(layer "In7.Cu")
		(net 726)
	)
	(arc
		(start 242.15 163.55)
		(mid 242.521231 163.396231)
		(end 242.675 163.025)
		(width 0.1)
		(layer "In7.Cu")
		(net 726)
	)
	(arc
		(start 230.051255 156.598742)
		(mid 230.440166 156.759835)
		(end 230.829075 156.598744)
		(width 0.1)
		(layer "In7.Cu")
		(net 726)
	)
	(arc
		(start 230.361296 158.410021)
		(mid 230.750205 158.571112)
		(end 231.139113 158.41002)
		(width 0.1)
		(layer "In7.Cu")
		(net 726)
	)
	(arc
		(start 243.025 163.025)
		(mid 243.178769 163.396231)
		(end 243.55 163.55)
		(width 0.1)
		(layer "In7.Cu")
		(net 726)
	)
	(arc
		(start 241.45 162.375)
		(mid 241.573744 162.426256)
		(end 241.625 162.55)
		(width 0.1)
		(layer "In7.Cu")
		(net 726)
	)
	(arc
		(start 232.392863 157.439114)
		(mid 232.451441 157.580536)
		(end 232.392862 157.721957)
		(width 0.1)
		(layer "In7.Cu")
		(net 726)
	)
	(segment
		(start 199.15 89.85)
		(end 199.15 89.025)
		(width 0.256)
		(layer "F.Cu")
		(net 727)
	)
	(segment
		(start 196.491252 93.65)
		(end 196.391252 93.55)
		(width 0.182)
		(layer "F.Cu")
		(net 727)
	)
	(segment
		(start 203.7 88.875)
		(end 203.75 88.825)
		(width 0.182)
		(layer "F.Cu")
		(net 727)
	)
	(segment
		(start 201.125 88.825)
		(end 201.05 88.75)
		(width 0.256)
		(layer "F.Cu")
		(net 727)
	)
	(segment
		(start 200.75 103.84)
		(end 200.75 103.15)
		(width 0.4)
		(layer "F.Cu")
		(net 727)
	)
	(segment
		(start 196.45165 91.489602)
		(end 196.391252 91.55)
		(width 0.182)
		(layer "F.Cu")
		(net 727)
	)
	(segment
		(start 199.438073 98.653179)
		(end 199.438073 98.204219)
		(width 0.4)
		(layer "F.Cu")
		(net 727)
	)
	(segment
		(start 199.35 88.825)
		(end 198.365 88.825)
		(width 0.256)
		(layer "F.Cu")
		(net 727)
	)
	(segment
		(start 199.15 89.025)
		(end 199.35 88.825)
		(width 0.256)
		(layer "F.Cu")
		(net 727)
	)
	(segment
		(start 200.75 103.15)
		(end 199.3 101.7)
		(width 0.4)
		(layer "F.Cu")
		(net 727)
	)
	(segment
		(start 197.071948 91.6)
		(end 196.96155 91.489602)
		(width 0.182)
		(layer "F.Cu")
		(net 727)
	)
	(segment
		(start 198.022851 91.6)
		(end 197.071948 91.6)
		(width 0.182)
		(layer "F.Cu")
		(net 727)
	)
	(segment
		(start 198.4 99.3)
		(end 198.85 98.85)
		(width 0.4)
		(layer "F.Cu")
		(net 727)
	)
	(segment
		(start 203.75 88.825)
		(end 203.975 88.825)
		(width 0.256)
		(layer "F.Cu")
		(net 727)
	)
	(segment
		(start 201.669 104.759)
		(end 200.75 103.84)
		(width 0.4)
		(layer "F.Cu")
		(net 727)
	)
	(segment
		(start 203.7 90.422851)
		(end 203.7 88.875)
		(width 0.182)
		(layer "F.Cu")
		(net 727)
	)
	(segment
		(start 201.7 90.422851)
		(end 201.7 88.875)
		(width 0.182)
		(layer "F.Cu")
		(net 727)
	)
	(segment
		(start 199.3 101.2)
		(end 198.4 100.3)
		(width 0.4)
		(layer "F.Cu")
		(net 727)
	)
	(segment
		(start 201.85 104.759)
		(end 201.669 104.759)
		(width 0.4)
		(layer "F.Cu")
		(net 727)
	)
	(segment
		(start 198.365 88.825)
		(end 198.35 88.81)
		(width 0.256)
		(layer "F.Cu")
		(net 727)
	)
	(segment
		(start 201.7 88.875)
		(end 201.65 88.825)
		(width 0.182)
		(layer "F.Cu")
		(net 727)
	)
	(segment
		(start 199.3 101.7)
		(end 199.3 101.2)
		(width 0.4)
		(layer "F.Cu")
		(net 727)
	)
	(segment
		(start 196.96155 91.489602)
		(end 196.45165 91.489602)
		(width 0.182)
		(layer "F.Cu")
		(net 727)
	)
	(segment
		(start 199.2 90.422851)
		(end 199.2 89.9)
		(width 0.256)
		(layer "F.Cu")
		(net 727)
	)
	(segment
		(start 199.7 97.277149)
		(end 199.7 97.9)
		(width 0.4)
		(layer "F.Cu")
		(net 727)
	)
	(segment
		(start 201.65 88.825)
		(end 201.125 88.825)
		(width 0.256)
		(layer "F.Cu")
		(net 727)
	)
	(segment
		(start 199.438073 98.161927)
		(end 199.438073 98.204219)
		(width 0.4)
		(layer "F.Cu")
		(net 727)
	)
	(segment
		(start 199.7 97.9)
		(end 199.438073 98.161927)
		(width 0.4)
		(layer "F.Cu")
		(net 727)
	)
	(segment
		(start 196.991252 93.65)
		(end 196.491252 93.65)
		(width 0.182)
		(layer "F.Cu")
		(net 727)
	)
	(segment
		(start 199.2 89.9)
		(end 199.15 89.85)
		(width 0.256)
		(layer "F.Cu")
		(net 727)
	)
	(segment
		(start 198.4 100.3)
		(end 198.4 99.3)
		(width 0.4)
		(layer "F.Cu")
		(net 727)
	)
	(segment
		(start 203.975 88.825)
		(end 204.45 88.35)
		(width 0.256)
		(layer "F.Cu")
		(net 727)
	)
	(segment
		(start 199.241252 98.85)
		(end 199.438073 98.653179)
		(width 0.4)
		(layer "F.Cu")
		(net 727)
	)
	(segment
		(start 197.041252 93.6)
		(end 196.991252 93.65)
		(width 0.182)
		(layer "F.Cu")
		(net 727)
	)
	(segment
		(start 198.85 98.85)
		(end 199.241252 98.85)
		(width 0.4)
		(layer "F.Cu")
		(net 727)
	)
	(segment
		(start 198.022851 93.6)
		(end 197.041252 93.6)
		(width 0.182)
		(layer "F.Cu")
		(net 727)
	)
	(via
		(at 166.5 170.3)
		(size 0.45)
		(drill 0.2)
		(layers "F.Cu" "B.Cu")
		(free yes)
		(net 727)
	)
	(via
		(at 197.5 86.88)
		(size 0.45)
		(drill 0.2)
		(layers "F.Cu" "B.Cu")
		(free yes)
		(net 727)
	)
	(via
		(at 165.9 170.3)
		(size 0.45)
		(drill 0.2)
		(layers "F.Cu" "B.Cu")
		(free yes)
		(net 727)
	)
	(via
		(at 217.8 92.35)
		(size 0.45)
		(drill 0.2)
		(layers "F.Cu" "B.Cu")
		(free yes)
		(net 727)
	)
	(via
		(at 198.35 88.81)
		(size 0.45)
		(drill 0.2)
		(layers "F.Cu" "B.Cu")
		(net 727)
	)
	(via
		(at 165.9 170.9)
		(size 0.45)
		(drill 0.2)
		(layers "F.Cu" "B.Cu")
		(free yes)
		(net 727)
	)
	(via
		(at 196.991252 93.65)
		(size 0.45)
		(drill 0.2)
		(layers "F.Cu" "B.Cu")
		(net 727)
	)
	(via
		(at 201.05 88.75)
		(size 0.45)
		(drill 0.2)
		(layers "F.Cu" "B.Cu")
		(net 727)
	)
	(via
		(at 204.45 88.35)
		(size 0.45)
		(drill 0.2)
		(layers "F.Cu" "B.Cu")
		(net 727)
	)
	(via
		(at 216.7 92.55)
		(size 0.45)
		(drill 0.2)
		(layers "F.Cu" "B.Cu")
		(free yes)
		(net 727)
	)
	(via
		(at 167.1 170.9)
		(size 0.45)
		(drill 0.2)
		(layers "F.Cu" "B.Cu")
		(free yes)
		(net 727)
	)
	(via
		(at 167.1 170.3)
		(size 0.45)
		(drill 0.2)
		(layers "F.Cu" "B.Cu")
		(free yes)
		(net 727)
	)
	(via
		(at 199.438073 98.204219)
		(size 0.45)
		(drill 0.2)
		(layers "F.Cu" "B.Cu")
		(net 727)
	)
	(via
		(at 218.25 91.95)
		(size 0.45)
		(drill 0.2)
		(layers "F.Cu" "B.Cu")
		(free yes)
		(net 727)
	)
	(via
		(at 217.25 92.55)
		(size 0.45)
		(drill 0.2)
		(layers "F.Cu" "B.Cu")
		(free yes)
		(net 727)
	)
	(via
		(at 217.25 92)
		(size 0.45)
		(drill 0.2)
		(layers "F.Cu" "B.Cu")
		(free yes)
		(net 727)
	)
	(via
		(at 196.96155 91.489602)
		(size 0.45)
		(drill 0.2)
		(layers "F.Cu" "B.Cu")
		(net 727)
	)
	(via
		(at 216.7 92)
		(size 0.45)
		(drill 0.2)
		(layers "F.Cu" "B.Cu")
		(free yes)
		(net 727)
	)
	(via
		(at 217.75 91.8)
		(size 0.45)
		(drill 0.2)
		(layers "F.Cu" "B.Cu")
		(free yes)
		(net 727)
	)
	(via
		(at 166.5 170.9)
		(size 0.45)
		(drill 0.2)
		(layers "F.Cu" "B.Cu")
		(free yes)
		(net 727)
	)
	(segment
		(start 197.12 86.88)
		(end 197.009803 86.990197)
		(width 0.1)
		(layer "B.Cu")
		(net 727)
	)
	(segment
		(start 197.5 86.88)
		(end 197.12 86.88)
		(width 0.1)
		(layer "B.Cu")
		(net 727)
	)
	(segment
		(start 204.877149 92.6)
		(end 206.841252 92.6)
		(width 0.182)
		(layer "F.Cu")
		(net 728)
	)
	(segment
		(start 204.23 92.87)
		(end 204.5 92.6)
		(width 0.256)
		(layer "F.Cu")
		(net 728)
	)
	(segment
		(start 201.85 102.27)
		(end 201.85 102.98)
		(width 0.256)
		(layer "F.Cu")
		(net 728)
	)
	(segment
		(start 204.271 95.099)
		(end 204.23 95.14)
		(width 0.256)
		(layer "F.Cu")
		(net 728)
	)
	(segment
		(start 202.2 97.277149)
		(end 202.2 101.92)
		(width 0.256)
		(layer "F.Cu")
		(net 728)
	)
	(segment
		(start 202.2 101.92)
		(end 201.85 102.27)
		(width 0.256)
		(layer "F.Cu")
		(net 728)
	)
	(segment
		(start 202.41 96.63)
		(end 204.04 96.63)
		(width 0.256)
		(layer "F.Cu")
		(net 728)
	)
	(segment
		(start 204.5 92.6)
		(end 204.949 92.6)
		(width 0.256)
		(layer "F.Cu")
		(net 728)
	)
	(segment
		(start 204.23 95.14)
		(end 204.23 92.87)
		(width 0.256)
		(layer "F.Cu")
		(net 728)
	)
	(segment
		(start 202.199 96.841)
		(end 202.41 96.63)
		(width 0.256)
		(layer "F.Cu")
		(net 728)
	)
	(segment
		(start 204.949 95.099)
		(end 204.271 95.099)
		(width 0.256)
		(layer "F.Cu")
		(net 728)
	)
	(segment
		(start 206.741252 95.1)
		(end 206.891252 95.25)
		(width 0.182)
		(layer "F.Cu")
		(net 728)
	)
	(segment
		(start 204.877149 95.1)
		(end 206.741252 95.1)
		(width 0.182)
		(layer "F.Cu")
		(net 728)
	)
	(segment
		(start 202.199 97.349)
		(end 202.199 96.841)
		(width 0.256)
		(layer "F.Cu")
		(net 728)
	)
	(segment
		(start 206.891252 95.6225)
		(end 206.891252 95.25)
		(width 0.177)
		(layer "F.Cu")
		(net 728)
	)
	(segment
		(start 204.04 96.63)
		(end 204.23 96.44)
		(width 0.256)
		(layer "F.Cu")
		(net 728)
	)
	(segment
		(start 204.23 96.44)
		(end 204.23 95.14)
		(width 0.256)
		(layer "F.Cu")
		(net 728)
	)
	(segment
		(start 206.841252 92.6)
		(end 206.891252 92.65)
		(width 0.182)
		(layer "F.Cu")
		(net 728)
	)
	(segment
		(start 222.65 152.2375)
		(end 222.7195 152.307)
		(width 0.153)
		(layer "F.Cu")
		(net 729)
	)
	(segment
		(start 222.7195 152.307)
		(end 222.7195 153.467093)
		(width 0.153)
		(layer "F.Cu")
		(net 729)
	)
	(segment
		(start 222.7195 153.467093)
		(end 222.571 153.615593)
		(width 0.153)
		(layer "F.Cu")
		(net 729)
	)
	(via
		(at 222.571 153.615593)
		(size 0.45)
		(drill 0.2)
		(layers "F.Cu" "B.Cu")
		(net 729)
	)
	(segment
		(start 254.8 166.315)
		(end 253.8 166.315)
		(width 0.182)
		(layer "B.Cu")
		(net 729)
	)
	(segment
		(start 253.8 165.263)
		(end 254.261 164.802)
		(width 0.182)
		(layer "B.Cu")
		(net 729)
	)
	(segment
		(start 253.8 166.315)
		(end 253.8 165.263)
		(width 0.182)
		(layer "B.Cu")
		(net 729)
	)
	(segment
		(start 244.415323 162.025)
		(end 253.972488 162.025)
		(width 0.1)
		(layer "In7.Cu")
		(net 729)
	)
	(segment
		(start 254.475 163.565488)
		(end 254.261 163.779488)
		(width 0.1)
		(layer "In7.Cu")
		(net 729)
	)
	(segment
		(start 253.972488 162.025)
		(end 254.475 162.527512)
		(width 0.1)
		(layer "In7.Cu")
		(net 729)
	)
	(segment
		(start 230.581586 156.351256)
		(end 230.801875 156.130968)
		(width 0.1)
		(layer "In7.Cu")
		(net 729)
	)
	(segment
		(start 243.725 163.025)
		(end 243.725 162.55)
		(width 0.1)
		(layer "In7.Cu")
		(net 729)
	)
	(segment
		(start 235.972488 162.025)
		(end 241.45 162.025)
		(width 0.1)
		(layer "In7.Cu")
		(net 729)
	)
	(segment
		(start 223.327512 152.425)
		(end 224.772488 152.425)
		(width 0.1)
		(layer "In7.Cu")
		(net 729)
	)
	(segment
		(start 230.891626 158.162533)
		(end 231.862531 157.191624)
		(width 0.1)
		(layer "In7.Cu")
		(net 729)
	)
	(segment
		(start 232.64035 157.969443)
		(end 232.64035 157.969442)
		(width 0.1)
		(layer "In7.Cu")
		(net 729)
	)
	(segment
		(start 231.952285 159.22319)
		(end 231.952284 159.223191)
		(width 0.1)
		(layer "In7.Cu")
		(net 729)
	)
	(segment
		(start 222.725 153.461593)
		(end 222.725 153.027512)
		(width 0.1)
		(layer "In7.Cu")
		(net 729)
	)
	(segment
		(start 232.950389 159.002902)
		(end 235.972488 162.025)
		(width 0.1)
		(layer "In7.Cu")
		(net 729)
	)
	(segment
		(start 244.25 162.025)
		(end 244.415323 162.025)
		(width 0.1)
		(layer "In7.Cu")
		(net 729)
	)
	(segment
		(start 241.975 162.55)
		(end 241.975 163.025)
		(width 0.1)
		(layer "In7.Cu")
		(net 729)
	)
	(segment
		(start 231.579692 156.908785)
		(end 230.608784 157.879691)
		(width 0.1)
		(layer "In7.Cu")
		(net 729)
	)
	(segment
		(start 232.95039 159.002902)
		(end 232.950389 159.002902)
		(width 0.1)
		(layer "In7.Cu")
		(net 729)
	)
	(segment
		(start 222.725 153.027512)
		(end 223.327512 152.425)
		(width 0.1)
		(layer "In7.Cu")
		(net 729)
	)
	(segment
		(start 254.261 163.779488)
		(end 254.261 164.802)
		(width 0.1)
		(layer "In7.Cu")
		(net 729)
	)
	(segment
		(start 232.64035 157.969442)
		(end 232.154897 158.454896)
		(width 0.1)
		(layer "In7.Cu")
		(net 729)
	)
	(segment
		(start 254.475 162.527512)
		(end 254.475 163.565488)
		(width 0.1)
		(layer "In7.Cu")
		(net 729)
	)
	(segment
		(start 243.375 162.55)
		(end 243.375 163.025)
		(width 0.1)
		(layer "In7.Cu")
		(net 729)
	)
	(segment
		(start 232.154897 158.454896)
		(end 232.154895 158.454895)
		(width 0.1)
		(layer "In7.Cu")
		(net 729)
	)
	(segment
		(start 230.891627 158.162532)
		(end 230.891626 158.162533)
		(width 0.1)
		(layer "In7.Cu")
		(net 729)
	)
	(segment
		(start 222.571 153.615593)
		(end 222.725 153.461593)
		(width 0.1)
		(layer "In7.Cu")
		(net 729)
	)
	(segment
		(start 231.579693 156.130968)
		(end 231.579691 156.130967)
		(width 0.1)
		(layer "In7.Cu")
		(net 729)
	)
	(segment
		(start 224.772488 152.425)
		(end 226.072488 153.725)
		(width 0.1)
		(layer "In7.Cu")
		(net 729)
	)
	(segment
		(start 226.072488 153.725)
		(end 227.672488 153.725)
		(width 0.1)
		(layer "In7.Cu")
		(net 729)
	)
	(segment
		(start 231.952284 159.223191)
		(end 232.172572 159.002902)
		(width 0.1)
		(layer "In7.Cu")
		(net 729)
	)
	(segment
		(start 231.57969 156.908784)
		(end 231.579692 156.908785)
		(width 0.1)
		(layer "In7.Cu")
		(net 729)
	)
	(segment
		(start 227.672488 153.725)
		(end 230.298742 156.351255)
		(width 0.1)
		(layer "In7.Cu")
		(net 729)
	)
	(segment
		(start 232.154895 158.454895)
		(end 231.669442 158.940349)
		(width 0.1)
		(layer "In7.Cu")
		(net 729)
	)
	(segment
		(start 242.325 163.025)
		(end 242.325 162.55)
		(width 0.1)
		(layer "In7.Cu")
		(net 729)
	)
	(segment
		(start 230.581588 156.351257)
		(end 230.581586 156.351256)
		(width 0.1)
		(layer "In7.Cu")
		(net 729)
	)
	(arc
		(start 241.45 162.025)
		(mid 241.821231 162.178769)
		(end 241.975 162.55)
		(width 0.1)
		(layer "In7.Cu")
		(net 729)
	)
	(arc
		(start 231.669442 159.223191)
		(mid 231.810864 159.281769)
		(end 231.952285 159.22319)
		(width 0.1)
		(layer "In7.Cu")
		(net 729)
	)
	(arc
		(start 231.862531 157.191624)
		(mid 232.25144 157.030533)
		(end 232.640351 157.191626)
		(width 0.1)
		(layer "In7.Cu")
		(net 729)
	)
	(arc
		(start 243.55 163.2)
		(mid 243.673744 163.148744)
		(end 243.725 163.025)
		(width 0.1)
		(layer "In7.Cu")
		(net 729)
	)
	(arc
		(start 230.608784 158.162533)
		(mid 230.750206 158.221111)
		(end 230.891627 158.162532)
		(width 0.1)
		(layer "In7.Cu")
		(net 729)
	)
	(arc
		(start 231.669442 158.940349)
		(mid 231.610864 159.08177)
		(end 231.669442 159.223191)
		(width 0.1)
		(layer "In7.Cu")
		(net 729)
	)
	(arc
		(start 242.325 162.55)
		(mid 242.478769 162.178769)
		(end 242.85 162.025)
		(width 0.1)
		(layer "In7.Cu")
		(net 729)
	)
	(arc
		(start 241.975 163.025)
		(mid 242.026256 163.148744)
		(end 242.15 163.2)
		(width 0.1)
		(layer "In7.Cu")
		(net 729)
	)
	(arc
		(start 230.608784 157.879691)
		(mid 230.550206 158.021112)
		(end 230.608784 158.162533)
		(width 0.1)
		(layer "In7.Cu")
		(net 729)
	)
	(arc
		(start 243.375 163.025)
		(mid 243.426256 163.148744)
		(end 243.55 163.2)
		(width 0.1)
		(layer "In7.Cu")
		(net 729)
	)
	(arc
		(start 232.172572 159.002902)
		(mid 232.561481 158.841811)
		(end 232.95039 159.002902)
		(width 0.1)
		(layer "In7.Cu")
		(net 729)
	)
	(arc
		(start 231.579691 156.130967)
		(mid 231.740782 156.519876)
		(end 231.57969 156.908784)
		(width 0.1)
		(layer "In7.Cu")
		(net 729)
	)
	(arc
		(start 230.298742 156.351255)
		(mid 230.440165 156.409835)
		(end 230.581588 156.351257)
		(width 0.1)
		(layer "In7.Cu")
		(net 729)
	)
	(arc
		(start 230.801875 156.130968)
		(mid 231.190784 155.969877)
		(end 231.579693 156.130968)
		(width 0.1)
		(layer "In7.Cu")
		(net 729)
	)
	(arc
		(start 242.15 163.2)
		(mid 242.273744 163.148744)
		(end 242.325 163.025)
		(width 0.1)
		(layer "In7.Cu")
		(net 729)
	)
	(arc
		(start 242.85 162.025)
		(mid 243.221231 162.178769)
		(end 243.375 162.55)
		(width 0.1)
		(layer "In7.Cu")
		(net 729)
	)
	(arc
		(start 232.640351 157.191626)
		(mid 232.801442 157.580535)
		(end 232.64035 157.969443)
		(width 0.1)
		(layer "In7.Cu")
		(net 729)
	)
	(arc
		(start 243.725 162.55)
		(mid 243.878769 162.178769)
		(end 244.25 162.025)
		(width 0.1)
		(layer "In7.Cu")
		(net 729)
	)
	(segment
		(start 245.2 158)
		(end 246.443 158)
		(width 0.4)
		(layer "B.Cu")
		(net 730)
	)
	(segment
		(start 246.443 158)
		(end 246.641 158.198)
		(width 0.4)
		(layer "B.Cu")
		(net 730)
	)
	(segment
		(start 157.5325 173.97)
		(end 157.5325 174.8325)
		(width 0.182)
		(layer "F.Cu")
		(net 731)
	)
	(via
		(at 157.5325 174.8325)
		(size 0.45)
		(drill 0.2)
		(layers "F.Cu" "B.Cu")
		(net 731)
	)
	(segment
		(start 157.5125 174.17)
		(end 157.5125 174.8125)
		(width 0.182)
		(layer "B.Cu")
		(net 731)
	)
	(segment
		(start 157.5125 174.8125)
		(end 157.5325 174.8325)
		(width 0.182)
		(layer "B.Cu")
		(net 731)
	)
	(segment
		(start 174.4 174.9)
		(end 174.4875 174.8125)
		(width 0.182)
		(layer "F.Cu")
		(net 732)
	)
	(segment
		(start 174.4875 174.8125)
		(end 174.4875 173.9625)
		(width 0.182)
		(layer "F.Cu")
		(net 732)
	)
	(via
		(at 174.4 174.9)
		(size 0.45)
		(drill 0.2)
		(layers "F.Cu" "B.Cu")
		(net 732)
	)
	(segment
		(start 174.21 177.04)
		(end 174.21 175.09)
		(width 0.182)
		(layer "B.Cu")
		(net 732)
	)
	(segment
		(start 174.43 177.26)
		(end 174.21 177.04)
		(width 0.182)
		(layer "B.Cu")
		(net 732)
	)
	(segment
		(start 174.5 174.2475)
		(end 174.5 174.8)
		(width 0.182)
		(layer "B.Cu")
		(net 732)
	)
	(segment
		(start 174.845 177.26)
		(end 174.43 177.26)
		(width 0.182)
		(layer "B.Cu")
		(net 732)
	)
	(segment
		(start 174.5 174.8)
		(end 174.4 174.9)
		(width 0.182)
		(layer "B.Cu")
		(net 732)
	)
	(segment
		(start 174.21 175.09)
		(end 174.4 174.9)
		(width 0.182)
		(layer "B.Cu")
		(net 732)
	)
	(segment
		(start 157.2 164)
		(end 154.6 164)
		(width 0.4)
		(layer "F.Cu")
		(net 733)
	)
	(segment
		(start 157.25 164.05)
		(end 157.2 164)
		(width 0.4)
		(layer "F.Cu")
		(net 733)
	)
	(segment
		(start 154.6 164)
		(end 153.6 165)
		(width 0.4)
		(layer "F.Cu")
		(net 733)
	)
	(segment
		(start 153.6 165)
		(end 153.6 168.0025)
		(width 0.4)
		(layer "F.Cu")
		(net 733)
	)
	(segment
		(start 153.6 168.0025)
		(end 154.3125 168.715)
		(width 0.4)
		(layer "F.Cu")
		(net 733)
	)
	(segment
		(start 164.8 167.3775)
		(end 164.0625 168.115)
		(width 0.4)
		(layer "F.Cu")
		(net 734)
	)
	(segment
		(start 163.85 164.05)
		(end 164.8 165)
		(width 0.4)
		(layer "F.Cu")
		(net 734)
	)
	(segment
		(start 164.8 165)
		(end 164.8 167.3775)
		(width 0.4)
		(layer "F.Cu")
		(net 734)
	)
	(segment
		(start 161.25 164.05)
		(end 163.85 164.05)
		(width 0.4)
		(layer "F.Cu")
		(net 734)
	)
	(segment
		(start 171.1275 168.8275)
		(end 171.25 168.8275)
		(width 0.4)
		(layer "F.Cu")
		(net 735)
	)
	(segment
		(start 170.5 168.2)
		(end 171.1275 168.8275)
		(width 0.4)
		(layer "F.Cu")
		(net 735)
	)
	(segment
		(start 174.2 164)
		(end 171.6 164)
		(width 0.4)
		(layer "F.Cu")
		(net 735)
	)
	(segment
		(start 170.5 165.1)
		(end 170.5 168.2)
		(width 0.4)
		(layer "F.Cu")
		(net 735)
	)
	(segment
		(start 171.6 164)
		(end 170.5 165.1)
		(width 0.4)
		(layer "F.Cu")
		(net 735)
	)
	(segment
		(start 181.8 167.4775)
		(end 181.05 168.2275)
		(width 0.4)
		(layer "F.Cu")
		(net 736)
	)
	(segment
		(start 181.8 165)
		(end 181.8 167.4775)
		(width 0.4)
		(layer "F.Cu")
		(net 736)
	)
	(segment
		(start 178.2 164)
		(end 180.8 164)
		(width 0.4)
		(layer "F.Cu")
		(net 736)
	)
	(segment
		(start 180.8 164)
		(end 181.8 165)
		(width 0.4)
		(layer "F.Cu")
		(net 736)
	)
	(segment
		(start 195.615 164.695)
		(end 195.615 165.1)
		(width 0.177)
		(layer "F.Cu")
		(net 741)
	)
	(segment
		(start 195.099999 164.179999)
		(end 195.615 164.695)
		(width 0.177)
		(layer "F.Cu")
		(net 741)
	)
	(segment
		(start 195.099999 163.749999)
		(end 195.099999 164.179999)
		(width 0.177)
		(layer "F.Cu")
		(net 741)
	)
	(segment
		(start 152.175 147.1)
		(end 151.235 147.1)
		(width 0.201)
		(layer "F.Cu")
		(net 742)
	)
	(segment
		(start 152.305 147.23)
		(end 152.175 147.1)
		(width 0.201)
		(layer "F.Cu")
		(net 742)
	)
	(segment
		(start 152.695 147.23)
		(end 152.305 147.23)
		(width 0.201)
		(layer "F.Cu")
		(net 742)
	)
	(segment
		(start 152.825 147.1)
		(end 152.695 147.23)
		(width 0.201)
		(layer "F.Cu")
		(net 742)
	)
	(segment
		(start 151.67 148.15)
		(end 151.2 147.68)
		(width 0.4)
		(layer "F.Cu")
		(net 742)
	)
	(segment
		(start 151.2 147.68)
		(end 151.2 147.135)
		(width 0.4)
		(layer "F.Cu")
		(net 742)
	)
	(segment
		(start 152.015 148.15)
		(end 151.67 148.15)
		(width 0.4)
		(layer "F.Cu")
		(net 742)
	)
	(segment
		(start 151.235 147.1)
		(end 151.2 147.135)
		(width 0.201)
		(layer "F.Cu")
		(net 742)
	)
	(segment
		(start 155.1 140.5)
		(end 155.2 140.4)
		(width 0.4)
		(layer "F.Cu")
		(net 743)
	)
	(segment
		(start 155.1 141.5)
		(end 155.2 141.6)
		(width 0.4)
		(layer "F.Cu")
		(net 743)
	)
	(segment
		(start 155.2 141.6)
		(end 155.6 141.6)
		(width 0.4)
		(layer "F.Cu")
		(net 743)
	)
	(segment
		(start 155.2 140.4)
		(end 155.6 140.4)
		(width 0.4)
		(layer "F.Cu")
		(net 743)
	)
	(via
		(at 152 170.25)
		(size 0.45)
		(drill 0.2)
		(layers "F.Cu" "B.Cu")
		(free yes)
		(net 743)
	)
	(via
		(at 151 170.25)
		(size 0.45)
		(drill 0.2)
		(layers "F.Cu" "B.Cu")
		(free yes)
		(net 743)
	)
	(via
		(at 155.6 141.6)
		(size 0.45)
		(drill 0.2)
		(layers "F.Cu" "B.Cu")
		(net 743)
	)
	(via
		(at 151.5 170.75)
		(size 0.45)
		(drill 0.2)
		(layers "F.Cu" "B.Cu")
		(free yes)
		(net 743)
	)
	(via
		(at 152.5 170.75)
		(size 0.45)
		(drill 0.2)
		(layers "F.Cu" "B.Cu")
		(free yes)
		(net 743)
	)
	(via
		(at 155.6 140.4)
		(size 0.45)
		(drill 0.2)
		(layers "F.Cu" "B.Cu")
		(net 743)
	)
	(segment
		(start 157.775 157)
		(end 156.71 157)
		(width 0.201)
		(layer "F.Cu")
		(net 744)
	)
	(segment
		(start 156.71 158)
		(end 156.71 155.81)
		(width 0.201)
		(layer "F.Cu")
		(net 744)
	)
	(segment
		(start 156.71 155.81)
		(end 156.6 155.7)
		(width 0.201)
		(layer "F.Cu")
		(net 744)
	)
	(segment
		(start 153.53 145.15)
		(end 156.2 145.15)
		(width 0.201)
		(layer "F.Cu")
		(net 747)
	)
	(segment
		(start 152.825 145.855)
		(end 153.53 145.15)
		(width 0.201)
		(layer "F.Cu")
		(net 747)
	)
	(segment
		(start 156.2 146.165)
		(end 156.765 146.165)
		(width 0.4)
		(layer "F.Cu")
		(net 747)
	)
	(segment
		(start 152.825 146.2)
		(end 152.825 145.855)
		(width 0.201)
		(layer "F.Cu")
		(net 747)
	)
	(segment
		(start 156.765 146.165)
		(end 157.2 146.6)
		(width 0.4)
		(layer "F.Cu")
		(net 747)
	)
	(segment
		(start 156.2 145.15)
		(end 156.2 146.165)
		(width 0.4)
		(layer "F.Cu")
		(net 747)
	)
	(segment
		(start 157.2 146.6)
		(end 157.75 146.6)
		(width 0.4)
		(layer "F.Cu")
		(net 747)
	)
	(segment
		(start 194.6 163.749999)
		(end 194.6 164.319824)
		(width 0.177)
		(layer "F.Cu")
		(net 749)
	)
	(segment
		(start 194.6 164.319824)
		(end 195.1315 164.851324)
		(width 0.177)
		(layer "F.Cu")
		(net 749)
	)
	(segment
		(start 195.1315 165.7165)
		(end 195.615 166.2)
		(width 0.177)
		(layer "F.Cu")
		(net 749)
	)
	(segment
		(start 195.1315 164.851324)
		(end 195.1315 165.7165)
		(width 0.177)
		(layer "F.Cu")
		(net 749)
	)
	(segment
		(start 157.475 153.275)
		(end 157.9 153.275)
		(width 0.4)
		(layer "F.Cu")
		(net 750)
	)
	(segment
		(start 156.6 154.7)
		(end 157.1 154.7)
		(width 0.4)
		(layer "F.Cu")
		(net 750)
	)
	(segment
		(start 157.1 154.7)
		(end 157.25 154.55)
		(width 0.4)
		(layer "F.Cu")
		(net 750)
	)
	(segment
		(start 157.05 153.7)
		(end 157.25 153.5)
		(width 0.4)
		(layer "F.Cu")
		(net 750)
	)
	(segment
		(start 157.25 154.55)
		(end 157.25 153.5)
		(width 0.4)
		(layer "F.Cu")
		(net 750)
	)
	(segment
		(start 156.6 153.7)
		(end 157.05 153.7)
		(width 0.4)
		(layer "F.Cu")
		(net 750)
	)
	(segment
		(start 157.25 153.5)
		(end 157.475 153.275)
		(width 0.4)
		(layer "F.Cu")
		(net 750)
	)
	(segment
		(start 193.599999 163.749999)
		(end 193.6 164.5)
		(width 0.177)
		(layer "F.Cu")
		(net 751)
	)
	(segment
		(start 193.6 165.115)
		(end 192.6 165.115)
		(width 0.177)
		(layer "F.Cu")
		(net 751)
	)
	(segment
		(start 193.6 165.115)
		(end 193.6 164.5)
		(width 0.177)
		(layer "F.Cu")
		(net 751)
	)
	(via
		(at 193.6 164.5)
		(size 0.45)
		(drill 0.2)
		(layers "F.Cu" "B.Cu")
		(net 751)
	)
	(via
		(at 198.25 156.5)
		(size 0.45)
		(drill 0.2)
		(layers "F.Cu" "B.Cu")
		(net 751)
	)
	(segment
		(start 194.04 165.04)
		(end 197.46 165.04)
		(width 0.4)
		(layer "B.Cu")
		(net 751)
	)
	(segment
		(start 193.6 164.6)
		(end 194.04 165.04)
		(width 0.4)
		(layer "B.Cu")
		(net 751)
	)
	(segment
		(start 197.46 165.04)
		(end 198.25 164.25)
		(width 0.4)
		(layer "B.Cu")
		(net 751)
	)
	(segment
		(start 193.6 164.5)
		(end 193.6 164.6)
		(width 0.4)
		(layer "B.Cu")
		(net 751)
	)
	(segment
		(start 198.25 164.25)
		(end 198.25 156.5)
		(width 0.4)
		(layer "B.Cu")
		(net 751)
	)
	(segment
		(start 227 139.625)
		(end 229.675 139.625)
		(width 0.182)
		(layer "F.Cu")
		(net 752)
	)
	(segment
		(start 229.915 140.635)
		(end 230.3 140.25)
		(width 0.182)
		(layer "F.Cu")
		(net 752)
	)
	(segment
		(start 229.915 141.6)
		(end 229.915 140.635)
		(width 0.182)
		(layer "F.Cu")
		(net 752)
	)
	(segment
		(start 229.675 139.625)
		(end 230.3 140.25)
		(width 0.182)
		(layer "F.Cu")
		(net 752)
	)
	(segment
		(start 227 138.975)
		(end 227.925 138.975)
		(width 0.182)
		(layer "F.Cu")
		(net 753)
	)
	(segment
		(start 227.925 138.975)
		(end 228.15 139.2)
		(width 0.182)
		(layer "F.Cu")
		(net 753)
	)
	(segment
		(start 228.15 139.2)
		(end 231.85 139.2)
		(width 0.182)
		(layer "F.Cu")
		(net 753)
	)
	(segment
		(start 233.085 137.1)
		(end 233.085 137.965)
		(width 0.182)
		(layer "F.Cu")
		(net 753)
	)
	(segment
		(start 231.85 139.2)
		(end 232.6 138.45)
		(width 0.182)
		(layer "F.Cu")
		(net 753)
	)
	(segment
		(start 233.085 137.965)
		(end 232.6 138.45)
		(width 0.182)
		(layer "F.Cu")
		(net 753)
	)
	(segment
		(start 210.285 74.955)
		(end 209.52 75.72)
		(width 0.182)
		(layer "F.Cu")
		(net 754)
	)
	(segment
		(start 210.81 74.955)
		(end 210.285 74.955)
		(width 0.182)
		(layer "F.Cu")
		(net 754)
	)
	(segment
		(start 266.385 146.85)
		(end 267.55 146.85)
		(width 0.177)
		(layer "B.Cu")
		(net 755)
	)
	(segment
		(start 238.17 177.43)
		(end 237.85 177.75)
		(width 0.4)
		(layer "F.Cu")
		(net 756)
	)
	(segment
		(start 238.17 176.35)
		(end 238.17 177.43)
		(width 0.4)
		(layer "F.Cu")
		(net 756)
	)
	(segment
		(start 234.6 177.75)
		(end 234.27 177.42)
		(width 0.4)
		(layer "F.Cu")
		(net 756)
	)
	(segment
		(start 234.27 177.42)
		(end 234.27 176.35)
		(width 0.4)
		(layer "F.Cu")
		(net 756)
	)
	(segment
		(start 235.95 179)
		(end 235.95 177.75)
		(width 0.4)
		(layer "F.Cu")
		(net 756)
	)
	(segment
		(start 235.95 177.75)
		(end 234.6 177.75)
		(width 0.4)
		(layer "F.Cu")
		(net 756)
	)
	(segment
		(start 237.85 177.75)
		(end 235.95 177.75)
		(width 0.4)
		(layer "F.Cu")
		(net 756)
	)
	(segment
		(start 231.73 176.35)
		(end 231.73 178.88)
		(width 0.4)
		(layer "F.Cu")
		(net 757)
	)
	(segment
		(start 235.63 174.98)
		(end 235.15 174.5)
		(width 0.4)
		(layer "F.Cu")
		(net 757)
	)
	(segment
		(start 235.63 176.35)
		(end 235.63 174.98)
		(width 0.4)
		(layer "F.Cu")
		(net 757)
	)
	(segment
		(start 231.73 178.88)
		(end 231.85 179)
		(width 0.4)
		(layer "F.Cu")
		(net 757)
	)
	(segment
		(start 232.2 174.5)
		(end 231.73 174.97)
		(width 0.4)
		(layer "F.Cu")
		(net 757)
	)
	(segment
		(start 235.15 174.5)
		(end 232.2 174.5)
		(width 0.4)
		(layer "F.Cu")
		(net 757)
	)
	(segment
		(start 231.73 174.97)
		(end 231.73 176.35)
		(width 0.4)
		(layer "F.Cu")
		(net 757)
	)
	(via
		(at 235.63 172.65)
		(size 0.45)
		(drill 0.2)
		(layers "F.Cu" "B.Cu")
		(net 758)
	)
	(segment
		(start 233.75 161.25)
		(end 235.532 159.468)
		(width 0.4)
		(layer "In4.Cu")
		(net 758)
	)
	(segment
		(start 233.75 170.77)
		(end 233.75 161.25)
		(width 0.4)
		(layer "In4.Cu")
		(net 758)
	)
	(segment
		(start 235.532 159.468)
		(end 237.751 159.468)
		(width 0.4)
		(layer "In4.Cu")
		(net 758)
	)
	(segment
		(start 235.63 172.65)
		(end 233.75 170.77)
		(width 0.4)
		(layer "In4.Cu")
		(net 758)
	)
	(via
		(at 238.17 172.65)
		(size 0.45)
		(drill 0.2)
		(layers "F.Cu" "B.Cu")
		(net 759)
	)
	(segment
		(start 235.75 166.75)
		(end 235.75 162.25)
		(width 0.4)
		(layer "In4.Cu")
		(net 759)
	)
	(segment
		(start 238.17 169.17)
		(end 235.75 166.75)
		(width 0.4)
		(layer "In4.Cu")
		(net 759)
	)
	(segment
		(start 235.75 162.25)
		(end 236.5 161.5)
		(width 0.4)
		(layer "In4.Cu")
		(net 759)
	)
	(segment
		(start 238.17 172.65)
		(end 238.17 169.17)
		(width 0.4)
		(layer "In4.Cu")
		(net 759)
	)
	(segment
		(start 242.25 161)
		(end 242.25 158.887)
		(width 0.4)
		(layer "In4.Cu")
		(net 759)
	)
	(segment
		(start 241.75 161.5)
		(end 242.25 161)
		(width 0.4)
		(layer "In4.Cu")
		(net 759)
	)
	(segment
		(start 236.5 161.5)
		(end 241.75 161.5)
		(width 0.4)
		(layer "In4.Cu")
		(net 759)
	)
	(segment
		(start 242.25 158.887)
		(end 241.561 158.198)
		(width 0.4)
		(layer "In4.Cu")
		(net 759)
	)
	(via
		(at 234.3 172.6)
		(size 0.45)
		(drill 0.2)
		(layers "F.Cu" "B.Cu")
		(net 760)
	)
	(segment
		(start 234 162.5)
		(end 234 172.3)
		(width 0.4)
		(layer "In2.Cu")
		(net 760)
	)
	(segment
		(start 238.509 161.25)
		(end 235.25 161.25)
		(width 0.4)
		(layer "In2.Cu")
		(net 760)
	)
	(segment
		(start 234 172.3)
		(end 234.3 172.6)
		(width 0.4)
		(layer "In2.Cu")
		(net 760)
	)
	(segment
		(start 235.25 161.25)
		(end 234 162.5)
		(width 0.4)
		(layer "In2.Cu")
		(net 760)
	)
	(segment
		(start 240.291 159.468)
		(end 238.509 161.25)
		(width 0.4)
		(layer "In2.Cu")
		(net 760)
	)
	(segment
		(start 231.73 172.63)
		(end 231.7 172.6)
		(width 0.4)
		(layer "F.Cu")
		(net 761)
	)
	(segment
		(start 231.73 172.65)
		(end 231.73 172.63)
		(width 0.4)
		(layer "F.Cu")
		(net 761)
	)
	(via
		(at 231.7 172.6)
		(size 0.45)
		(drill 0.2)
		(layers "F.Cu" "B.Cu")
		(net 761)
	)
	(segment
		(start 234.07 160.08)
		(end 234.92 160.08)
		(width 0.4)
		(layer "In2.Cu")
		(net 761)
	)
	(segment
		(start 232.25 161.9)
		(end 234.07 160.08)
		(width 0.4)
		(layer "In2.Cu")
		(net 761)
	)
	(segment
		(start 234.92 160.08)
		(end 236.802 158.198)
		(width 0.4)
		(layer "In2.Cu")
		(net 761)
	)
	(segment
		(start 232.25 172.05)
		(end 232.25 161.9)
		(width 0.4)
		(layer "In2.Cu")
		(net 761)
	)
	(segment
		(start 231.7 172.6)
		(end 232.25 172.05)
		(width 0.4)
		(layer "In2.Cu")
		(net 761)
	)
	(segment
		(start 236.802 158.198)
		(end 239.021 158.198)
		(width 0.4)
		(layer "In2.Cu")
		(net 761)
	)
	(segment
		(start 243.95 177.8)
		(end 243.9 177.75)
		(width 0.4)
		(layer "F.Cu")
		(net 762)
	)
	(segment
		(start 243.9 177.75)
		(end 242.45 177.75)
		(width 0.4)
		(layer "F.Cu")
		(net 762)
	)
	(segment
		(start 245.97 176.35)
		(end 245.97 177.38)
		(width 0.4)
		(layer "F.Cu")
		(net 762)
	)
	(segment
		(start 242.07 177.37)
		(end 242.07 176.35)
		(width 0.4)
		(layer "F.Cu")
		(net 762)
	)
	(segment
		(start 242.45 177.75)
		(end 242.07 177.37)
		(width 0.4)
		(layer "F.Cu")
		(net 762)
	)
	(segment
		(start 245.97 177.38)
		(end 245.6 177.75)
		(width 0.4)
		(layer "F.Cu")
		(net 762)
	)
	(segment
		(start 245.6 177.75)
		(end 243.9 177.75)
		(width 0.4)
		(layer "F.Cu")
		(net 762)
	)
	(segment
		(start 243.95 179)
		(end 243.95 177.8)
		(width 0.4)
		(layer "F.Cu")
		(net 762)
	)
	(segment
		(start 239.53 178.58)
		(end 239.95 179)
		(width 0.4)
		(layer "F.Cu")
		(net 763)
	)
	(segment
		(start 239.53 174.97)
		(end 240 174.5)
		(width 0.4)
		(layer "F.Cu")
		(net 763)
	)
	(segment
		(start 239.53 176.35)
		(end 239.53 174.97)
		(width 0.4)
		(layer "F.Cu")
		(net 763)
	)
	(segment
		(start 239.53 176.35)
		(end 239.53 178.58)
		(width 0.4)
		(layer "F.Cu")
		(net 763)
	)
	(segment
		(start 243.43 174.98)
		(end 243.43 176.35)
		(width 0.4)
		(layer "F.Cu")
		(net 763)
	)
	(segment
		(start 240 174.5)
		(end 242.95 174.5)
		(width 0.4)
		(layer "F.Cu")
		(net 763)
	)
	(segment
		(start 242.95 174.5)
		(end 243.43 174.98)
		(width 0.4)
		(layer "F.Cu")
		(net 763)
	)
	(via
		(at 239.53 172.65)
		(size 0.45)
		(drill 0.2)
		(layers "F.Cu" "B.Cu")
		(net 764)
	)
	(segment
		(start 237.751 166.251)
		(end 239.53 168.03)
		(width 0.4)
		(layer "In2.Cu")
		(net 764)
	)
	(segment
		(start 237.751 163.532)
		(end 237.751 166.251)
		(width 0.4)
		(layer "In2.Cu")
		(net 764)
	)
	(segment
		(start 239.53 168.03)
		(end 239.53 172.65)
		(width 0.4)
		(layer "In2.Cu")
		(net 764)
	)
	(via
		(at 242.07 172.65)
		(size 0.45)
		(drill 0.2)
		(layers "F.Cu" "B.Cu")
		(net 765)
	)
	(segment
		(start 242.07 172.65)
		(end 241.561 172.141)
		(width 0.4)
		(layer "In2.Cu")
		(net 765)
	)
	(segment
		(start 241.561 172.141)
		(end 241.561 164.802)
		(width 0.4)
		(layer "In2.Cu")
		(net 765)
	)
	(segment
		(start 245.97 172.63)
		(end 246 172.6)
		(width 0.4)
		(layer "F.Cu")
		(net 766)
	)
	(segment
		(start 245.97 172.65)
		(end 245.97 172.63)
		(width 0.4)
		(layer "F.Cu")
		(net 766)
	)
	(via
		(at 246 172.6)
		(size 0.45)
		(drill 0.2)
		(layers "F.Cu" "B.Cu")
		(net 766)
	)
	(segment
		(start 240.291 163.532)
		(end 240.291 166.891)
		(width 0.4)
		(layer "In4.Cu")
		(net 766)
	)
	(segment
		(start 240.291 166.891)
		(end 246 172.6)
		(width 0.4)
		(layer "In4.Cu")
		(net 766)
	)
	(via
		(at 243.43 172.65)
		(size 0.45)
		(drill 0.2)
		(layers "F.Cu" "B.Cu")
		(net 767)
	)
	(segment
		(start 239.021 167.671)
		(end 243.43 172.08)
		(width 0.4)
		(layer "In4.Cu")
		(net 767)
	)
	(segment
		(start 243.43 172.08)
		(end 243.43 172.65)
		(width 0.4)
		(layer "In4.Cu")
		(net 767)
	)
	(segment
		(start 239.021 164.802)
		(end 239.021 167.671)
		(width 0.4)
		(layer "In4.Cu")
		(net 767)
	)
	(segment
		(start 259.35 95.8)
		(end 260.75 95.8)
		(width 0.1)
		(layer "F.Cu")
		(net 768)
	)
	(segment
		(start 227.65 166.1)
		(end 227.5 166.25)
		(width 0.1)
		(layer "F.Cu")
		(net 769)
	)
	(segment
		(start 227.65 165.36)
		(end 227.65 166.1)
		(width 0.1)
		(layer "F.Cu")
		(net 769)
	)
	(via
		(at 232.98 163.42)
		(size 0.45)
		(drill 0.2)
		(layers "F.Cu" "B.Cu")
		(net 769)
	)
	(via
		(at 227.5 166.25)
		(size 0.45)
		(drill 0.2)
		(layers "F.Cu" "B.Cu")
		(net 769)
	)
	(via
		(at 265.775 150)
		(size 0.45)
		(drill 0.2)
		(layers "F.Cu" "B.Cu")
		(net 769)
	)
	(segment
		(start 268.75 149.5)
		(end 269.05 149.2)
		(width 0.1)
		(layer "B.Cu")
		(net 769)
	)
	(segment
		(start 228.075 163.375)
		(end 227.5 163.95)
		(width 0.1)
		(layer "B.Cu")
		(net 769)
	)
	(segment
		(start 227.5 163.95)
		(end 227.5 166.25)
		(width 0.1)
		(layer "B.Cu")
		(net 769)
	)
	(segment
		(start 266.275 149.5)
		(end 268.75 149.5)
		(width 0.1)
		(layer "B.Cu")
		(net 769)
	)
	(segment
		(start 232.98 163.42)
		(end 232.935 163.375)
		(width 0.1)
		(layer "B.Cu")
		(net 769)
	)
	(segment
		(start 265.775 150)
		(end 266.275 149.5)
		(width 0.1)
		(layer "B.Cu")
		(net 769)
	)
	(segment
		(start 269.05 149.2)
		(end 269.05 148.3)
		(width 0.1)
		(layer "B.Cu")
		(net 769)
	)
	(segment
		(start 232.935 163.375)
		(end 228.075 163.375)
		(width 0.1)
		(layer "B.Cu")
		(net 769)
	)
	(segment
		(start 232.98 163.42)
		(end 233.15 163.25)
		(width 0.1)
		(layer "In3.Cu")
		(net 769)
	)
	(segment
		(start 265.425 151.2)
		(end 265.775 150.85)
		(width 0.1)
		(layer "In3.Cu")
		(net 769)
	)
	(segment
		(start 233.784316 163.25)
		(end 236.034316 161)
		(width 0.1)
		(layer "In3.Cu")
		(net 769)
	)
	(segment
		(start 259.625 152.8)
		(end 261.225 151.2)
		(width 0.1)
		(layer "In3.Cu")
		(net 769)
	)
	(segment
		(start 233.15 163.25)
		(end 233.784316 163.25)
		(width 0.1)
		(layer "In3.Cu")
		(net 769)
	)
	(segment
		(start 236.034316 161)
		(end 241.725 161)
		(width 0.1)
		(layer "In3.Cu")
		(net 769)
	)
	(segment
		(start 261.225 151.2)
		(end 265.425 151.2)
		(width 0.1)
		(layer "In3.Cu")
		(net 769)
	)
	(segment
		(start 254.7 153.2)
		(end 255.1 152.8)
		(width 0.1)
		(layer "In3.Cu")
		(net 769)
	)
	(segment
		(start 265.775 150.85)
		(end 265.775 150)
		(width 0.1)
		(layer "In3.Cu")
		(net 769)
	)
	(segment
		(start 254.7 155.6)
		(end 254.7 153.2)
		(width 0.1)
		(layer "In3.Cu")
		(net 769)
	)
	(segment
		(start 255.1 152.8)
		(end 259.625 152.8)
		(width 0.1)
		(layer "In3.Cu")
		(net 769)
	)
	(segment
		(start 245.75 156.975)
		(end 253.325 156.975)
		(width 0.1)
		(layer "In3.Cu")
		(net 769)
	)
	(segment
		(start 253.325 156.975)
		(end 254.7 155.6)
		(width 0.1)
		(layer "In3.Cu")
		(net 769)
	)
	(segment
		(start 241.725 161)
		(end 245.75 156.975)
		(width 0.1)
		(layer "In3.Cu")
		(net 769)
	)
	(segment
		(start 259.35 79)
		(end 260.75 79)
		(width 0.1)
		(layer "F.Cu")
		(net 770)
	)
	(segment
		(start 225.98 162.68)
		(end 226.47 162.68)
		(width 0.1)
		(layer "F.Cu")
		(net 771)
	)
	(via
		(at 265.9 149.2)
		(size 0.45)
		(drill 0.2)
		(layers "F.Cu" "B.Cu")
		(net 771)
	)
	(via
		(at 225.98 162.68)
		(size 0.45)
		(drill 0.2)
		(layers "F.Cu" "B.Cu")
		(net 771)
	)
	(via
		(at 233.025 162.85)
		(size 0.45)
		(drill 0.2)
		(layers "F.Cu" "B.Cu")
		(net 771)
	)
	(segment
		(start 268.435 147.465)
		(end 269.05 146.85)
		(width 0.1)
		(layer "B.Cu")
		(net 771)
	)
	(segment
		(start 265.9 149.2)
		(end 268.36 149.2)
		(width 0.1)
		(layer "B.Cu")
		(net 771)
	)
	(segment
		(start 225.98 162.68)
		(end 226.11 162.55)
		(width 0.1)
		(layer "B.Cu")
		(net 771)
	)
	(segment
		(start 268.36 149.2)
		(end 268.435 149.125)
		(width 0.1)
		(layer "B.Cu")
		(net 771)
	)
	(segment
		(start 232.725 162.55)
		(end 233.025 162.85)
		(width 0.1)
		(layer "B.Cu")
		(net 771)
	)
	(segment
		(start 226.11 162.55)
		(end 232.725 162.55)
		(width 0.1)
		(layer "B.Cu")
		(net 771)
	)
	(segment
		(start 268.435 149.125)
		(end 268.435 147.465)
		(width 0.1)
		(layer "B.Cu")
		(net 771)
	)
	(segment
		(start 241.2 160.8)
		(end 242.9 159.1)
		(width 0.1)
		(layer "In3.Cu")
		(net 771)
	)
	(segment
		(start 263.2 149.5)
		(end 265.2 149.5)
		(width 0.1)
		(layer "In3.Cu")
		(net 771)
	)
	(segment
		(start 265.2 149.5)
		(end 265.5 149.2)
		(width 0.1)
		(layer "In3.Cu")
		(net 771)
	)
	(segment
		(start 254.1 152.3)
		(end 259.5 152.3)
		(width 0.1)
		(layer "In3.Cu")
		(net 771)
	)
	(segment
		(start 242.9 159.1)
		(end 242.9 157)
		(width 0.1)
		(layer "In3.Cu")
		(net 771)
	)
	(segment
		(start 249.9 156.5)
		(end 254.1 152.3)
		(width 0.1)
		(layer "In3.Cu")
		(net 771)
	)
	(segment
		(start 262.1 149.7)
		(end 263 149.7)
		(width 0.1)
		(layer "In3.Cu")
		(net 771)
	)
	(segment
		(start 243.4 156.5)
		(end 249.9 156.5)
		(width 0.1)
		(layer "In3.Cu")
		(net 771)
	)
	(segment
		(start 263 149.7)
		(end 263.2 149.5)
		(width 0.1)
		(layer "In3.Cu")
		(net 771)
	)
	(segment
		(start 233.901474 162.85)
		(end 235.951474 160.8)
		(width 0.1)
		(layer "In3.Cu")
		(net 771)
	)
	(segment
		(start 242.9 157)
		(end 243.4 156.5)
		(width 0.1)
		(layer "In3.Cu")
		(net 771)
	)
	(segment
		(start 265.5 149.2)
		(end 265.9 149.2)
		(width 0.1)
		(layer "In3.Cu")
		(net 771)
	)
	(segment
		(start 259.5 152.3)
		(end 262.1 149.7)
		(width 0.1)
		(layer "In3.Cu")
		(net 771)
	)
	(segment
		(start 235.951474 160.8)
		(end 241.2 160.8)
		(width 0.1)
		(layer "In3.Cu")
		(net 771)
	)
	(segment
		(start 233.025 162.85)
		(end 233.901474 162.85)
		(width 0.1)
		(layer "In3.Cu")
		(net 771)
	)
	(segment
		(start 259.35 83.8)
		(end 260.75 83.8)
		(width 0.1)
		(layer "F.Cu")
		(net 772)
	)
	(segment
		(start 263.5 79)
		(end 262.25 79)
		(width 0.1)
		(layer "F.Cu")
		(net 773)
	)
	(via
		(at 263.5 79)
		(size 0.45)
		(drill 0.2)
		(layers "F.Cu" "B.Cu")
		(net 773)
	)
	(segment
		(start 261.985 79)
		(end 263.5 79)
		(width 0.1)
		(layer "B.Cu")
		(net 773)
	)
	(segment
		(start 263.5 83.8)
		(end 262.25 83.8)
		(width 0.1)
		(layer "F.Cu")
		(net 775)
	)
	(via
		(at 263.5 83.8)
		(size 0.45)
		(drill 0.2)
		(layers "F.Cu" "B.Cu")
		(net 775)
	)
	(segment
		(start 261.985 83.8)
		(end 263.5 83.8)
		(width 0.1)
		(layer "B.Cu")
		(net 775)
	)
	(segment
		(start 263.5 86.2)
		(end 262.25 86.2)
		(width 0.1)
		(layer "F.Cu")
		(net 777)
	)
	(via
		(at 263.5 86.2)
		(size 0.45)
		(drill 0.2)
		(layers "F.Cu" "B.Cu")
		(net 777)
	)
	(segment
		(start 261.985 86.2)
		(end 263.5 86.2)
		(width 0.1)
		(layer "B.Cu")
		(net 777)
	)
	(segment
		(start 263.5 88.6)
		(end 262.25 88.6)
		(width 0.1)
		(layer "F.Cu")
		(net 779)
	)
	(via
		(at 263.5 88.6)
		(size 0.45)
		(drill 0.2)
		(layers "F.Cu" "B.Cu")
		(net 779)
	)
	(segment
		(start 261.985 88.6)
		(end 263.5 88.6)
		(width 0.1)
		(layer "B.Cu")
		(net 779)
	)
	(segment
		(start 263.5 91)
		(end 262.25 91)
		(width 0.1)
		(layer "F.Cu")
		(net 781)
	)
	(via
		(at 263.5 91)
		(size 0.45)
		(drill 0.2)
		(layers "F.Cu" "B.Cu")
		(net 781)
	)
	(segment
		(start 261.985 91)
		(end 263.5 91)
		(width 0.1)
		(layer "B.Cu")
		(net 781)
	)
	(segment
		(start 263.5 93.4)
		(end 262.25 93.4)
		(width 0.1)
		(layer "F.Cu")
		(net 783)
	)
	(via
		(at 263.5 93.4)
		(size 0.45)
		(drill 0.2)
		(layers "F.Cu" "B.Cu")
		(net 783)
	)
	(segment
		(start 261.985 93.4)
		(end 263.5 93.4)
		(width 0.1)
		(layer "B.Cu")
		(net 783)
	)
	(segment
		(start 263.5 95.8)
		(end 262.25 95.8)
		(width 0.1)
		(layer "F.Cu")
		(net 785)
	)
	(via
		(at 263.5 95.8)
		(size 0.45)
		(drill 0.2)
		(layers "F.Cu" "B.Cu")
		(net 785)
	)
	(segment
		(start 261.985 95.8)
		(end 263.5 95.8)
		(width 0.1)
		(layer "B.Cu")
		(net 785)
	)
	(segment
		(start 259.35 81.4)
		(end 260.75 81.4)
		(width 0.1)
		(layer "F.Cu")
		(net 787)
	)
	(segment
		(start 263.5 81.4)
		(end 262.25 81.4)
		(width 0.1)
		(layer "F.Cu")
		(net 789)
	)
	(via
		(at 263.5 81.4)
		(size 0.45)
		(drill 0.2)
		(layers "F.Cu" "B.Cu")
		(net 789)
	)
	(segment
		(start 261.985 81.4)
		(end 263.5 81.4)
		(width 0.1)
		(layer "B.Cu")
		(net 789)
	)
	(segment
		(start 265.16 139.985)
		(end 265.835 139.31)
		(width 0.182)
		(layer "F.Cu")
		(net 790)
	)
	(segment
		(start 264.7 139.985)
		(end 265.16 139.985)
		(width 0.182)
		(layer "F.Cu")
		(net 790)
	)
	(segment
		(start 265.565 138.085)
		(end 265.85 137.8)
		(width 0.182)
		(layer "F.Cu")
		(net 791)
	)
	(segment
		(start 264.7 138.085)
		(end 265.565 138.085)
		(width 0.182)
		(layer "F.Cu")
		(net 791)
	)
	(segment
		(start 265.165 136.085)
		(end 265.85 135.4)
		(width 0.182)
		(layer "F.Cu")
		(net 792)
	)
	(segment
		(start 264.7 136.085)
		(end 265.165 136.085)
		(width 0.182)
		(layer "F.Cu")
		(net 792)
	)
	(segment
		(start 265.165 133.215)
		(end 265.85 133.9)
		(width 0.182)
		(layer "F.Cu")
		(net 793)
	)
	(segment
		(start 264.7 133.215)
		(end 265.165 133.215)
		(width 0.182)
		(layer "F.Cu")
		(net 793)
	)
	(segment
		(start 251.9325 114.5)
		(end 250.55 114.5)
		(width 0.182)
		(layer "B.Cu")
		(net 794)
	)
	(segment
		(start 250.55 114.5)
		(end 250.25 114.2)
		(width 0.182)
		(layer "B.Cu")
		(net 794)
	)
	(segment
		(start 250.4 112.3)
		(end 250.1 112.6)
		(width 0.182)
		(layer "B.Cu")
		(net 795)
	)
	(segment
		(start 248.55 114.15)
		(end 250.1 112.6)
		(width 0.182)
		(layer "B.Cu")
		(net 795)
	)
	(segment
		(start 251.2 112.3)
		(end 250.4 112.3)
		(width 0.182)
		(layer "B.Cu")
		(net 795)
	)
	(segment
		(start 248.55 114.2)
		(end 248.55 114.15)
		(width 0.182)
		(layer "B.Cu")
		(net 795)
	)
	(segment
		(start 164.75 184.95)
		(end 164.75 185.7)
		(width 0.182)
		(layer "F.Cu")
		(net 797)
	)
	(segment
		(start 164.75 185.7)
		(end 164.7 185.75)
		(width 0.182)
		(layer "F.Cu")
		(net 797)
	)
	(via
		(at 164.75 184.95)
		(size 0.45)
		(drill 0.2)
		(layers "F.Cu" "B.Cu")
		(net 797)
	)
	(segment
		(start 163.7 186)
		(end 164.75 184.95)
		(width 0.182)
		(layer "B.Cu")
		(net 797)
	)
	(segment
		(start 164.75 184.185)
		(end 164.75 184.95)
		(width 0.256)
		(layer "B.Cu")
		(net 797)
	)
	(segment
		(start 163.45 186)
		(end 163.7 186)
		(width 0.182)
		(layer "B.Cu")
		(net 797)
	)
	(segment
		(start 165.8 184.185)
		(end 164.75 184.185)
		(width 0.256)
		(layer "B.Cu")
		(net 797)
	)
	(segment
		(start 236.19 177.81)
		(end 228 177.81)
		(width 0.1)
		(layer "B.Cu")
		(net 798)
	)
	(segment
		(start 255.75 175)
		(end 256.25 175)
		(width 0.1)
		(layer "B.Cu")
		(net 798)
	)
	(segment
		(start 256.25 172.75)
		(end 256.9 172.1)
		(width 0.1)
		(layer "B.Cu")
		(net 798)
	)
	(segment
		(start 256.9 172.1)
		(end 256.9 170)
		(width 0.1)
		(layer "B.Cu")
		(net 798)
	)
	(segment
		(start 254.8 171.385)
		(end 254.8 172.56262)
		(width 0.1)
		(layer "B.Cu")
		(net 798)
	)
	(segment
		(start 256.25 175)
		(end 256.5 174.75)
		(width 0.1)
		(layer "B.Cu")
		(net 798)
	)
	(segment
		(start 255.5 173)
		(end 255.5 174.75)
		(width 0.1)
		(layer "B.Cu")
		(net 798)
	)
	(segment
		(start 256.5 174.75)
		(end 256.5 174.25)
		(width 0.1)
		(layer "B.Cu")
		(net 798)
	)
	(segment
		(start 245 167)
		(end 240.5 171.5)
		(width 0.1)
		(layer "B.Cu")
		(net 798)
	)
	(segment
		(start 256.5 169.6)
		(end 254.1 169.6)
		(width 0.1)
		(layer "B.Cu")
		(net 798)
	)
	(segment
		(start 255.06262 172.56262)
		(end 255.5 173)
		(width 0.1)
		(layer "B.Cu")
		(net 798)
	)
	(segment
		(start 240.5 171.5)
		(end 240.5 173.5)
		(width 0.1)
		(layer "B.Cu")
		(net 798)
	)
	(segment
		(start 254.8 172.56262)
		(end 255.06262 172.56262)
		(width 0.1)
		(layer "B.Cu")
		(net 798)
	)
	(segment
		(start 256.25 174)
		(end 256.25 172.75)
		(width 0.1)
		(layer "B.Cu")
		(net 798)
	)
	(segment
		(start 255.5 174.75)
		(end 255.75 175)
		(width 0.1)
		(layer "B.Cu")
		(net 798)
	)
	(segment
		(start 240.5 173.5)
		(end 236.19 177.81)
		(width 0.1)
		(layer "B.Cu")
		(net 798)
	)
	(segment
		(start 251.5 167)
		(end 245 167)
		(width 0.1)
		(layer "B.Cu")
		(net 798)
	)
	(segment
		(start 256.9 170)
		(end 256.5 169.6)
		(width 0.1)
		(layer "B.Cu")
		(net 798)
	)
	(segment
		(start 256.5 174.25)
		(end 256.25 174)
		(width 0.1)
		(layer "B.Cu")
		(net 798)
	)
	(segment
		(start 254.1 169.6)
		(end 251.5 167)
		(width 0.1)
		(layer "B.Cu")
		(net 798)
	)
	(segment
		(start 238.8 128.285)
		(end 237.585 128.285)
		(width 0.1)
		(layer "F.Cu")
		(net 799)
	)
	(segment
		(start 175.77 185.76)
		(end 175.77 182.74)
		(width 0.1)
		(layer "F.Cu")
		(net 799)
	)
	(segment
		(start 235.6 126.3)
		(end 235.6 124.4)
		(width 0.1)
		(layer "F.Cu")
		(net 799)
	)
	(segment
		(start 235.075 123.875)
		(end 235.6 124.4)
		(width 0.1)
		(layer "F.Cu")
		(net 799)
	)
	(segment
		(start 235.075 123.875)
		(end 234.45 123.875)
		(width 0.1)
		(layer "F.Cu")
		(net 799)
	)
	(segment
		(start 235.6 126.3)
		(end 237.585 128.285)
		(width 0.1)
		(layer "F.Cu")
		(net 799)
	)
	(segment
		(start 239.05 128.535)
		(end 238.8 128.285)
		(width 0.1)
		(layer "F.Cu")
		(net 799)
	)
	(segment
		(start 239.05 129.3)
		(end 239.05 128.535)
		(width 0.1)
		(layer "F.Cu")
		(net 799)
	)
	(segment
		(start 183.000001 77.175001)
		(end 183.000001 76.130001)
		(width 0.1)
		(layer "F.Cu")
		(net 799)
	)
	(via
		(at 238.8 128.285)
		(size 0.45)
		(drill 0.2)
		(layers "F.Cu" "B.Cu")
		(net 799)
	)
	(via
		(at 234.45 123.875)
		(size 0.45)
		(drill 0.2)
		(layers "F.Cu" "B.Cu")
		(net 799)
	)
	(via
		(at 183.000001 77.175001)
		(size 0.45)
		(drill 0.2)
		(layers "F.Cu" "B.Cu")
		(net 799)
	)
	(via
		(at 175.77 185.76)
		(size 0.45)
		(drill 0.2)
		(layers "F.Cu" "B.Cu")
		(net 799)
	)
	(via
		(at 236.76 134.69)
		(size 0.45)
		(drill 0.2)
		(layers "F.Cu" "B.Cu")
		(net 799)
	)
	(via
		(at 238.92 151.13)
		(size 0.45)
		(drill 0.2)
		(layers "F.Cu" "B.Cu")
		(net 799)
	)
	(segment
		(start 235.9 134.56)
		(end 236.03 134.69)
		(width 0.1)
		(layer "In3.Cu")
		(net 799)
	)
	(segment
		(start 238.8 128.285)
		(end 235.9 131.185)
		(width 0.1)
		(layer "In3.Cu")
		(net 799)
	)
	(segment
		(start 235.9 131.185)
		(end 235.9 134.56)
		(width 0.1)
		(layer "In3.Cu")
		(net 799)
	)
	(segment
		(start 236.03 134.69)
		(end 236.76 134.69)
		(width 0.1)
		(layer "In3.Cu")
		(net 799)
	)
	(segment
		(start 216.194316 166.79)
		(end 198.225684 166.79)
		(width 0.1)
		(layer "In5.Cu")
		(net 799)
	)
	(segment
		(start 182.29 183.255686)
		(end 179.345684 186.2)
		(width 0.1)
		(layer "In5.Cu")
		(net 799)
	)
	(segment
		(start 198.225684 166.79)
		(end 196.015684 169)
		(width 0.1)
		(layer "In5.Cu")
		(net 799)
	)
	(segment
		(start 227.545684 162.5)
		(end 226.590684 163.455)
		(width 0.1)
		(layer "In5.Cu")
		(net 799)
	)
	(segment
		(start 179.345684 186.2)
		(end 176.21 186.2)
		(width 0.1)
		(layer "In5.Cu")
		(net 799)
	)
	(segment
		(start 238.19 150.4)
		(end 234.815683 150.4)
		(width 0.1)
		(layer "In5.Cu")
		(net 799)
	)
	(segment
		(start 234.815683 150.4)
		(end 231.62 153.595684)
		(width 0.1)
		(layer "In5.Cu")
		(net 799)
	)
	(segment
		(start 176.21 186.2)
		(end 175.77 185.76)
		(width 0.1)
		(layer "In5.Cu")
		(net 799)
	)
	(segment
		(start 231.62 153.595684)
		(end 231.62 161.118632)
		(width 0.1)
		(layer "In5.Cu")
		(net 799)
	)
	(segment
		(start 226.590684 163.455)
		(end 219.529315 163.455)
		(width 0.1)
		(layer "In5.Cu")
		(net 799)
	)
	(segment
		(start 230.238633 162.5)
		(end 227.545684 162.5)
		(width 0.1)
		(layer "In5.Cu")
		(net 799)
	)
	(segment
		(start 231.62 161.118632)
		(end 230.238633 162.5)
		(width 0.1)
		(layer "In5.Cu")
		(net 799)
	)
	(segment
		(start 238.92 151.13)
		(end 238.19 150.4)
		(width 0.1)
		(layer "In5.Cu")
		(net 799)
	)
	(segment
		(start 196.015684 169)
		(end 189.315684 169)
		(width 0.1)
		(layer "In5.Cu")
		(net 799)
	)
	(segment
		(start 182.29 176.025684)
		(end 182.29 183.255686)
		(width 0.1)
		(layer "In5.Cu")
		(net 799)
	)
	(segment
		(start 219.529315 163.455)
		(end 216.194316 166.79)
		(width 0.1)
		(layer "In5.Cu")
		(net 799)
	)
	(segment
		(start 189.315684 169)
		(end 182.29 176.025684)
		(width 0.1)
		(layer "In5.Cu")
		(net 799)
	)
	(segment
		(start 236.76 134.69)
		(end 235.78 135.67)
		(width 0.1)
		(layer "In7.Cu")
		(net 799)
	)
	(segment
		(start 235.78 135.67)
		(end 235.78 143.57)
		(width 0.1)
		(layer "In7.Cu")
		(net 799)
	)
	(segment
		(start 204.650001 86.200001)
		(end 208.7 90.25)
		(width 0.1)
		(layer "In7.Cu")
		(net 799)
	)
	(segment
		(start 183.000001 77.175001)
		(end 183.825 78)
		(width 0.1)
		(layer "In7.Cu")
		(net 799)
	)
	(segment
		(start 237.02 148.05)
		(end 237.02 149.23)
		(width 0.1)
		(layer "In7.Cu")
		(net 799)
	)
	(segment
		(start 208.7 90.25)
		(end 208.7 92.425)
		(width 0.1)
		(layer "In7.Cu")
		(net 799)
	)
	(segment
		(start 183.825 78)
		(end 196.475 78)
		(width 0.1)
		(layer "In7.Cu")
		(net 799)
	)
	(segment
		(start 235.325001 124.000001)
		(end 235.200001 123.875001)
		(width 0.1)
		(layer "In7.Cu")
		(net 799)
	)
	(segment
		(start 199.750001 84.650001)
		(end 201.300001 86.200001)
		(width 0.1)
		(layer "In7.Cu")
		(net 799)
	)
	(segment
		(start 235.200001 123.875001)
		(end 234.450001 123.875001)
		(width 0.1)
		(layer "In7.Cu")
		(net 799)
	)
	(segment
		(start 216.900001 108.475001)
		(end 233.100001 108.475001)
		(width 0.1)
		(layer "In7.Cu")
		(net 799)
	)
	(segment
		(start 199.750001 81.275001)
		(end 199.750001 84.650001)
		(width 0.1)
		(layer "In7.Cu")
		(net 799)
	)
	(segment
		(start 237.02 144.81)
		(end 237.02 148.05)
		(width 0.1)
		(layer "In7.Cu")
		(net 799)
	)
	(segment
		(start 201.300001 86.200001)
		(end 204.650001 86.200001)
		(width 0.1)
		(layer "In7.Cu")
		(net 799)
	)
	(segment
		(start 210.700001 102.275001)
		(end 216.900001 108.475001)
		(width 0.1)
		(layer "In7.Cu")
		(net 799)
	)
	(segment
		(start 237.02 149.23)
		(end 238.92 151.13)
		(width 0.1)
		(layer "In7.Cu")
		(net 799)
	)
	(segment
		(start 208.7 92.425)
		(end 210.700001 94.425001)
		(width 0.1)
		(layer "In7.Cu")
		(net 799)
	)
	(segment
		(start 233.100001 108.475001)
		(end 237.200001 112.575001)
		(width 0.1)
		(layer "In7.Cu")
		(net 799)
	)
	(segment
		(start 237.200001 112.575001)
		(end 237.200001 123.300001)
		(width 0.1)
		(layer "In7.Cu")
		(net 799)
	)
	(segment
		(start 196.475 78)
		(end 199.750001 81.275001)
		(width 0.1)
		(layer "In7.Cu")
		(net 799)
	)
	(segment
		(start 237.200001 123.300001)
		(end 236.500001 124.000001)
		(width 0.1)
		(layer "In7.Cu")
		(net 799)
	)
	(segment
		(start 210.700001 94.425001)
		(end 210.700001 102.275001)
		(width 0.1)
		(layer "In7.Cu")
		(net 799)
	)
	(segment
		(start 236.500001 124.000001)
		(end 235.325001 124.000001)
		(width 0.1)
		(layer "In7.Cu")
		(net 799)
	)
	(segment
		(start 235.78 143.57)
		(end 237.02 144.81)
		(width 0.1)
		(layer "In7.Cu")
		(net 799)
	)
	(segment
		(start 226.7 127.2)
		(end 226.7 127.7)
		(width 0.1)
		(layer "F.Cu")
		(net 801)
	)
	(segment
		(start 226.625 127.775)
		(end 226.05 127.775)
		(width 0.1)
		(layer "F.Cu")
		(net 801)
	)
	(segment
		(start 226.7 127.2)
		(end 227.825 126.075)
		(width 0.1)
		(layer "F.Cu")
		(net 801)
	)
	(segment
		(start 229.3 126.075)
		(end 227.825 126.075)
		(width 0.1)
		(layer "F.Cu")
		(net 801)
	)
	(segment
		(start 226.7 127.7)
		(end 226.625 127.775)
		(width 0.1)
		(layer "F.Cu")
		(net 801)
	)
	(segment
		(start 229.3 131.875)
		(end 229.3 126.075)
		(width 0.1)
		(layer "F.Cu")
		(net 801)
	)
	(via
		(at 226.05 127.775)
		(size 0.45)
		(drill 0.2)
		(layers "F.Cu" "B.Cu")
		(net 801)
	)
	(segment
		(start 224.55 124.8)
		(end 225.385 124.8)
		(width 0.1)
		(layer "B.Cu")
		(net 801)
	)
	(segment
		(start 224.55 125.475)
		(end 224.55 124.8)
		(width 0.1)
		(layer "B.Cu")
		(net 801)
	)
	(segment
		(start 226.05 127.775)
		(end 225.125 126.85)
		(width 0.1)
		(layer "B.Cu")
		(net 801)
	)
	(segment
		(start 225.385 124.8)
		(end 225.9 125.315)
		(width 0.1)
		(layer "B.Cu")
		(net 801)
	)
	(segment
		(start 225.125 126.05)
		(end 224.55 125.475)
		(width 0.1)
		(layer "B.Cu")
		(net 801)
	)
	(segment
		(start 225.125 126.85)
		(end 225.125 126.05)
		(width 0.1)
		(layer "B.Cu")
		(net 801)
	)
	(segment
		(start 221.0575 80.1495)
		(end 221.0575 78.7425)
		(width 0.182)
		(layer "B.Cu")
		(net 802)
	)
	(segment
		(start 221.0575 78.7425)
		(end 220.699999 78.384999)
		(width 0.182)
		(layer "B.Cu")
		(net 802)
	)
	(segment
		(start 221.0575 82.6895)
		(end 222.299999 81.447001)
		(width 0.182)
		(layer "B.Cu")
		(net 803)
	)
	(segment
		(start 222.299999 81.447001)
		(end 222.299999 78.684999)
		(width 0.182)
		(layer "B.Cu")
		(net 803)
	)
	(segment
		(start 222.299999 78.684999)
		(end 221.999999 78.384999)
		(width 0.182)
		(layer "B.Cu")
		(net 803)
	)
	(segment
		(start 218.5175 78.8025)
		(end 218.5175 80.1495)
		(width 0.182)
		(layer "B.Cu")
		(net 804)
	)
	(segment
		(start 218.099999 78.384999)
		(end 218.5175 78.8025)
		(width 0.182)
		(layer "B.Cu")
		(net 804)
	)
	(segment
		(start 219.799999 78.784999)
		(end 219.399999 78.384999)
		(width 0.182)
		(layer "B.Cu")
		(net 805)
	)
	(segment
		(start 218.5175 82.6895)
		(end 219.799999 81.407001)
		(width 0.182)
		(layer "B.Cu")
		(net 805)
	)
	(segment
		(start 219.799999 81.407001)
		(end 219.799999 78.784999)
		(width 0.182)
		(layer "B.Cu")
		(net 805)
	)
	(segment
		(start 215.9775 78.8625)
		(end 215.499999 78.384999)
		(width 0.182)
		(layer "B.Cu")
		(net 806)
	)
	(segment
		(start 215.9775 80.1495)
		(end 215.9775 78.8625)
		(width 0.182)
		(layer "B.Cu")
		(net 806)
	)
	(segment
		(start 217.299999 81.367001)
		(end 217.299999 78.884999)
		(width 0.182)
		(layer "B.Cu")
		(net 807)
	)
	(segment
		(start 215.9775 82.6895)
		(end 217.299999 81.367001)
		(width 0.182)
		(layer "B.Cu")
		(net 807)
	)
	(segment
		(start 217.299999 78.884999)
		(end 216.799999 78.384999)
		(width 0.182)
		(layer "B.Cu")
		(net 807)
	)
	(segment
		(start 213.4375 78.9225)
		(end 212.899999 78.384999)
		(width 0.182)
		(layer "B.Cu")
		(net 808)
	)
	(segment
		(start 213.4375 80.1495)
		(end 213.4375 78.9225)
		(width 0.182)
		(layer "B.Cu")
		(net 808)
	)
	(segment
		(start 214.699999 81.427001)
		(end 213.4375 82.6895)
		(width 0.182)
		(layer "B.Cu")
		(net 809)
	)
	(segment
		(start 214.199999 78.384999)
		(end 214.699999 78.884999)
		(width 0.182)
		(layer "B.Cu")
		(net 809)
	)
	(segment
		(start 214.699999 78.884999)
		(end 214.699999 81.427001)
		(width 0.182)
		(layer "B.Cu")
		(net 809)
	)
	(segment
		(start 245.099999 81.441999)
		(end 245.099999 84.014999)
		(width 0.182)
		(layer "B.Cu")
		(net 810)
	)
	(segment
		(start 245.099999 84.014999)
		(end 245.299999 84.214999)
		(width 0.182)
		(layer "B.Cu")
		(net 810)
	)
	(segment
		(start 243.8075 80.1495)
		(end 245.099999 81.441999)
		(width 0.182)
		(layer "B.Cu")
		(net 810)
	)
	(segment
		(start 244.099999 84.214999)
		(end 244.099999 82.981999)
		(width 0.182)
		(layer "B.Cu")
		(net 811)
	)
	(segment
		(start 244.099999 82.981999)
		(end 243.8075 82.6895)
		(width 0.182)
		(layer "B.Cu")
		(net 811)
	)
	(segment
		(start 241.2675 80.1495)
		(end 242.599999 81.481999)
		(width 0.182)
		(layer "B.Cu")
		(net 812)
	)
	(segment
		(start 242.599999 84.014999)
		(end 242.799999 84.214999)
		(width 0.182)
		(layer "B.Cu")
		(net 812)
	)
	(segment
		(start 242.599999 81.481999)
		(end 242.599999 84.014999)
		(width 0.182)
		(layer "B.Cu")
		(net 812)
	)
	(segment
		(start 241.499999 84.215)
		(end 241.499999 82.921999)
		(width 0.182)
		(layer "B.Cu")
		(net 813)
	)
	(segment
		(start 241.499999 82.921999)
		(end 241.2675 82.6895)
		(width 0.182)
		(layer "B.Cu")
		(net 813)
	)
	(segment
		(start 238.7275 80.1495)
		(end 239.999999 81.421999)
		(width 0.182)
		(layer "B.Cu")
		(net 814)
	)
	(segment
		(start 239.999999 84.014999)
		(end 240.199999 84.214999)
		(width 0.182)
		(layer "B.Cu")
		(net 814)
	)
	(segment
		(start 239.999999 81.421999)
		(end 239.999999 84.014999)
		(width 0.182)
		(layer "B.Cu")
		(net 814)
	)
	(segment
		(start 238.899999 82.861999)
		(end 238.7275 82.6895)
		(width 0.182)
		(layer "B.Cu")
		(net 815)
	)
	(segment
		(start 238.899999 84.214999)
		(end 238.899999 82.861999)
		(width 0.182)
		(layer "B.Cu")
		(net 815)
	)
	(segment
		(start 237.599999 84.214999)
		(end 237.599999 81.561999)
		(width 0.182)
		(layer "B.Cu")
		(net 816)
	)
	(segment
		(start 237.599999 81.561999)
		(end 236.1875 80.1495)
		(width 0.182)
		(layer "B.Cu")
		(net 816)
	)
	(segment
		(start 236.299999 82.801999)
		(end 236.1875 82.6895)
		(width 0.182)
		(layer "B.Cu")
		(net 817)
	)
	(segment
		(start 236.299999 84.214999)
		(end 236.299999 82.801999)
		(width 0.182)
		(layer "B.Cu")
		(net 817)
	)
	(via
		(at 185.500001 79.300001)
		(size 0.45)
		(drill 0.2)
		(layers "F.Cu" "B.Cu")
		(net 822)
	)
	(via
		(at 186.800001 85.300001)
		(size 0.45)
		(drill 0.2)
		(layers "F.Cu" "B.Cu")
		(net 823)
	)
	(via
		(at 186.800001 79.300001)
		(size 0.45)
		(drill 0.2)
		(layers "F.Cu" "B.Cu")
		(net 824)
	)
	(via
		(at 188.100001 85.300001)
		(size 0.45)
		(drill 0.2)
		(layers "F.Cu" "B.Cu")
		(net 825)
	)
	(via
		(at 189.3 85.3)
		(size 0.45)
		(drill 0.2)
		(layers "F.Cu" "B.Cu")
		(net 826)
	)
	(via
		(at 189.4 79.3)
		(size 0.45)
		(drill 0.2)
		(layers "F.Cu" "B.Cu")
		(net 827)
	)
	(via
		(at 190.6 85.3)
		(size 0.45)
		(drill 0.2)
		(layers "F.Cu" "B.Cu")
		(net 828)
	)
	(via
		(at 190.6 79.3)
		(size 0.45)
		(drill 0.2)
		(layers "F.Cu" "B.Cu")
		(net 829)
	)
	(via
		(at 191.9 85.3)
		(size 0.45)
		(drill 0.2)
		(layers "F.Cu" "B.Cu")
		(net 830)
	)
	(via
		(at 191.9 79.3)
		(size 0.45)
		(drill 0.2)
		(layers "F.Cu" "B.Cu")
		(net 831)
	)
	(via
		(at 193.1 85.3)
		(size 0.45)
		(drill 0.2)
		(layers "F.Cu" "B.Cu")
		(net 832)
	)
	(segment
		(start 200.6475 108.9875)
		(end 200.385 109.25)
		(width 0.198)
		(layer "F.Cu")
		(net 835)
	)
	(segment
		(start 217.498376 102.2375)
		(end 216.698376 103.0375)
		(width 0.198)
		(layer "F.Cu")
		(net 835)
	)
	(segment
		(start 261.9125 102.2375)
		(end 217.498376 102.2375)
		(width 0.198)
		(layer "F.Cu")
		(net 835)
	)
	(segment
		(start 260.485 102.25)
		(end 260.4975 102.2375)
		(width 0.198)
		(layer "F.Cu")
		(net 835)
	)
	(segment
		(start 210.698376 103.0375)
		(end 204.748376 108.9875)
		(width 0.198)
		(layer "F.Cu")
		(net 835)
	)
	(segment
		(start 216.698376 103.0375)
		(end 210.698376 103.0375)
		(width 0.198)
		(layer "F.Cu")
		(net 835)
	)
	(segment
		(start 262.375 102.7)
		(end 261.9125 102.2375)
		(width 0.198)
		(layer "F.Cu")
		(net 835)
	)
	(segment
		(start 204.748376 108.9875)
		(end 200.6475 108.9875)
		(width 0.198)
		(layer "F.Cu")
		(net 835)
	)
	(segment
		(start 260.485 101.75)
		(end 260.4975 101.7625)
		(width 0.198)
		(layer "F.Cu")
		(net 836)
	)
	(segment
		(start 261.9125 101.7625)
		(end 217.301624 101.7625)
		(width 0.198)
		(layer "F.Cu")
		(net 836)
	)
	(segment
		(start 204.551624 108.5125)
		(end 200.6475 108.5125)
		(width 0.198)
		(layer "F.Cu")
		(net 836)
	)
	(segment
		(start 217.301624 101.7625)
		(end 216.501624 102.5625)
		(width 0.198)
		(layer "F.Cu")
		(net 836)
	)
	(segment
		(start 262.375 101.3)
		(end 261.9125 101.7625)
		(width 0.198)
		(layer "F.Cu")
		(net 836)
	)
	(segment
		(start 200.6475 108.5125)
		(end 200.385 108.25)
		(width 0.198)
		(layer "F.Cu")
		(net 836)
	)
	(segment
		(start 210.501624 102.5625)
		(end 204.551624 108.5125)
		(width 0.198)
		(layer "F.Cu")
		(net 836)
	)
	(segment
		(start 216.501624 102.5625)
		(end 210.501624 102.5625)
		(width 0.198)
		(layer "F.Cu")
		(net 836)
	)
	(segment
		(start 231.21 164.18)
		(end 230.338 164.18)
		(width 0.1)
		(layer "F.Cu")
		(net 837)
	)
	(segment
		(start 262.085 147)
		(end 262.65 147)
		(width 0.1)
		(layer "F.Cu")
		(net 837)
	)
	(segment
		(start 262.65 147)
		(end 262.9 147.25)
		(width 0.1)
		(layer "F.Cu")
		(net 837)
	)
	(segment
		(start 231.405 164.375)
		(end 231.1 164.68)
		(width 0.1)
		(layer "F.Cu")
		(net 837)
	)
	(segment
		(start 260.8 147)
		(end 261.315 147)
		(width 0.1)
		(layer "F.Cu")
		(net 837)
	)
	(segment
		(start 261.315 147)
		(end 262.085 147)
		(width 0.1)
		(layer "F.Cu")
		(net 837)
	)
	(segment
		(start 231.405 164.375)
		(end 231.21 164.18)
		(width 0.1)
		(layer "F.Cu")
		(net 837)
	)
	(segment
		(start 231.1 164.68)
		(end 230.33 164.68)
		(width 0.1)
		(layer "F.Cu")
		(net 837)
	)
	(segment
		(start 262.9 147.25)
		(end 263.61 147.25)
		(width 0.1)
		(layer "F.Cu")
		(net 837)
	)
	(via
		(at 231.405 164.375)
		(size 0.45)
		(drill 0.2)
		(layers "F.Cu" "B.Cu")
		(net 837)
	)
	(via
		(at 260.8 147)
		(size 0.45)
		(drill 0.2)
		(layers "F.Cu" "B.Cu")
		(net 837)
	)
	(segment
		(start 249.1 151.55)
		(end 258.25 151.55)
		(width 0.1)
		(layer "In3.Cu")
		(net 837)
	)
	(segment
		(start 259.2 147.45)
		(end 259.65 147)
		(width 0.1)
		(layer "In3.Cu")
		(net 837)
	)
	(segment
		(start 235.489432 159.667726)
		(end 239.867158 155.29)
		(width 0.1)
		(layer "In3.Cu")
		(net 837)
	)
	(segment
		(start 259.2 150.6)
		(end 259.2 147.45)
		(width 0.1)
		(layer "In3.Cu")
		(net 837)
	)
	(segment
		(start 234.402274 159.667726)
		(end 235.489432 159.667726)
		(width 0.1)
		(layer "In3.Cu")
		(net 837)
	)
	(segment
		(start 258.25 151.55)
		(end 259.2 150.6)
		(width 0.1)
		(layer "In3.Cu")
		(net 837)
	)
	(segment
		(start 232.15 163.63)
		(end 232.15 161.92)
		(width 0.1)
		(layer "In3.Cu")
		(net 837)
	)
	(segment
		(start 245.36 155.29)
		(end 249.1 151.55)
		(width 0.1)
		(layer "In3.Cu")
		(net 837)
	)
	(segment
		(start 231.405 164.375)
		(end 232.15 163.63)
		(width 0.1)
		(layer "In3.Cu")
		(net 837)
	)
	(segment
		(start 259.65 147)
		(end 260.8 147)
		(width 0.1)
		(layer "In3.Cu")
		(net 837)
	)
	(segment
		(start 239.867158 155.29)
		(end 245.36 155.29)
		(width 0.1)
		(layer "In3.Cu")
		(net 837)
	)
	(segment
		(start 232.15 161.92)
		(end 234.402274 159.667726)
		(width 0.1)
		(layer "In3.Cu")
		(net 837)
	)
	(segment
		(start 262.775 146.5)
		(end 263.025 146.25)
		(width 0.198)
		(layer "F.Cu")
		(net 838)
	)
	(segment
		(start 254.55 135.525)
		(end 254.4125 135.6625)
		(width 0.198)
		(layer "F.Cu")
		(net 838)
	)
	(segment
		(start 262.085 146.5)
		(end 260.8385 146.5)
		(width 0.198)
		(layer "F.Cu")
		(net 838)
	)
	(segment
		(start 262.775 146.5)
		(end 262.775 146.525)
		(width 0.198)
		(layer "F.Cu")
		(net 838)
	)
	(segment
		(start 260.8385 146.5)
		(end 260.65 146.3115)
		(width 0.198)
		(layer "F.Cu")
		(net 838)
	)
	(segment
		(start 262.775 146.525)
		(end 262.7 146.6)
		(width 0.198)
		(layer "F.Cu")
		(net 838)
	)
	(segment
		(start 262.085 146.5)
		(end 262.775 146.5)
		(width 0.198)
		(layer "F.Cu")
		(net 838)
	)
	(segment
		(start 254.4125 135.6625)
		(end 252.35 135.6625)
		(width 0.198)
		(layer "F.Cu")
		(net 838)
	)
	(segment
		(start 252.35 135.6625)
		(end 252.3375 135.65)
		(width 0.198)
		(layer "F.Cu")
		(net 838)
	)
	(segment
		(start 262.85 145.075)
		(end 263.025 145.25)
		(width 0.198)
		(layer "F.Cu")
		(net 838)
	)
	(segment
		(start 262.7 145.075)
		(end 262.85 145.075)
		(width 0.198)
		(layer "F.Cu")
		(net 838)
	)
	(segment
		(start 263.025 146.25)
		(end 263.61 146.25)
		(width 0.198)
		(layer "F.Cu")
		(net 838)
	)
	(segment
		(start 263.025 145.25)
		(end 263.61 145.25)
		(width 0.198)
		(layer "F.Cu")
		(net 838)
	)
	(via
		(at 260.65 146.3115)
		(size 0.45)
		(drill 0.2)
		(layers "F.Cu" "B.Cu")
		(net 838)
	)
	(via
		(at 262.7 146.6)
		(size 0.45)
		(drill 0.2)
		(layers "F.Cu" "B.Cu")
		(net 838)
	)
	(via
		(at 262.7 145.075)
		(size 0.45)
		(drill 0.2)
		(layers "F.Cu" "B.Cu")
		(net 838)
	)
	(via
		(at 254.55 135.525)
		(size 0.45)
		(drill 0.2)
		(layers "F.Cu" "B.Cu")
		(net 838)
	)
	(segment
		(start 263.125 145.5)
		(end 262.7 145.075)
		(width 0.198)
		(layer "B.Cu")
		(net 838)
	)
	(segment
		(start 263.125 146.175)
		(end 263.125 145.5)
		(width 0.198)
		(layer "B.Cu")
		(net 838)
	)
	(segment
		(start 262.7 146.6)
		(end 263.125 146.175)
		(width 0.198)
		(layer "B.Cu")
		(net 838)
	)
	(segment
		(start 253.1515 136.07556)
		(end 253.1515 140.10444)
		(width 0.114)
		(layer "In5.Cu")
		(net 838)
	)
	(segment
		(start 259.19056 146.1435)
		(end 260.482 146.1435)
		(width 0.114)
		(layer "In5.Cu")
		(net 838)
	)
	(segment
		(start 253.1515 140.10444)
		(end 259.19056 146.1435)
		(width 0.114)
		(layer "In5.Cu")
		(net 838)
	)
	(segment
		(start 254.35075 135.72425)
		(end 253.50281 135.72425)
		(width 0.114)
		(layer "In5.Cu")
		(net 838)
	)
	(segment
		(start 254.55 135.525)
		(end 254.35075 135.72425)
		(width 0.114)
		(layer "In5.Cu")
		(net 838)
	)
	(segment
		(start 260.482 146.1435)
		(end 260.65 146.3115)
		(width 0.114)
		(layer "In5.Cu")
		(net 838)
	)
	(segment
		(start 253.50281 135.72425)
		(end 253.1515 136.07556)
		(width 0.114)
		(layer "In5.Cu")
		(net 838)
	)
	(segment
		(start 263 145.75)
		(end 263.61 145.75)
		(width 0.198)
		(layer "F.Cu")
		(net 839)
	)
	(segment
		(start 262.085 145.5)
		(end 262.75 145.5)
		(width 0.198)
		(layer "F.Cu")
		(net 839)
	)
	(segment
		(start 262.085 145.5)
		(end 260.8385 145.5)
		(width 0.198)
		(layer "F.Cu")
		(net 839)
	)
	(segment
		(start 252.35 136.1375)
		(end 252.3375 136.15)
		(width 0.198)
		(layer "F.Cu")
		(net 839)
	)
	(segment
		(start 263.61 146.75)
		(end 264.275 146.75)
		(width 0.198)
		(layer "F.Cu")
		(net 839)
	)
	(segment
		(start 262.75 145.5)
		(end 263 145.75)
		(width 0.198)
		(layer "F.Cu")
		(net 839)
	)
	(segment
		(start 254.4625 136.1375)
		(end 252.35 136.1375)
		(width 0.198)
		(layer "F.Cu")
		(net 839)
	)
	(segment
		(start 264.525 145.825)
		(end 264.45 145.75)
		(width 0.198)
		(layer "F.Cu")
		(net 839)
	)
	(segment
		(start 254.55 136.225)
		(end 254.4625 136.1375)
		(width 0.198)
		(layer "F.Cu")
		(net 839)
	)
	(segment
		(start 264.275 146.75)
		(end 264.525 146.5)
		(width 0.198)
		(layer "F.Cu")
		(net 839)
	)
	(segment
		(start 264.525 146.5)
		(end 264.525 145.825)
		(width 0.198)
		(layer "F.Cu")
		(net 839)
	)
	(segment
		(start 264.45 145.75)
		(end 263.61 145.75)
		(width 0.198)
		(layer "F.Cu")
		(net 839)
	)
	(segment
		(start 260.8385 145.5)
		(end 260.65 145.6885)
		(width 0.198)
		(layer "F.Cu")
		(net 839)
	)
	(via
		(at 260.65 145.6885)
		(size 0.45)
		(drill 0.2)
		(layers "F.Cu" "B.Cu")
		(net 839)
	)
	(via
		(at 254.55 136.225)
		(size 0.45)
		(drill 0.2)
		(layers "F.Cu" "B.Cu")
		(net 839)
	)
	(segment
		(start 253.878895 137.5385)
		(end 253.7385 137.5385)
		(width 0.114)
		(layer "In5.Cu")
		(net 839)
	)
	(segment
		(start 260.482 145.8565)
		(end 260.65 145.6885)
		(width 0.114)
		(layer "In5.Cu")
		(net 839)
	)
	(segment
		(start 253.4385 136.19444)
		(end 253.4385 136.6385)
		(width 0.114)
		(layer "In5.Cu")
		(net 839)
	)
	(segment
		(start 254.55 136.225)
		(end 254.33625 136.01125)
		(width 0.114)
		(layer "In5.Cu")
		(net 839)
	)
	(segment
		(start 253.4385 139.98556)
		(end 259.30944 145.8565)
		(width 0.114)
		(layer "In5.Cu")
		(net 839)
	)
	(segment
		(start 253.4385 137.8885)
		(end 253.4385 139.98556)
		(width 0.114)
		(layer "In5.Cu")
		(net 839)
	)
	(segment
		(start 253.7385 136.9385)
		(end 253.878895 136.9385)
		(width 0.114)
		(layer "In5.Cu")
		(net 839)
	)
	(segment
		(start 254.33625 136.01125)
		(end 253.62169 136.01125)
		(width 0.114)
		(layer "In5.Cu")
		(net 839)
	)
	(segment
		(start 259.30944 145.8565)
		(end 260.482 145.8565)
		(width 0.114)
		(layer "In5.Cu")
		(net 839)
	)
	(segment
		(start 253.62169 136.01125)
		(end 253.4385 136.19444)
		(width 0.114)
		(layer "In5.Cu")
		(net 839)
	)
	(segment
		(start 253.4385 137.8385)
		(end 253.4385 137.8885)
		(width 0.114)
		(layer "In5.Cu")
		(net 839)
	)
	(arc
		(start 253.878895 136.9385)
		(mid 254.091027 137.026368)
		(end 254.178895 137.2385)
		(width 0.114)
		(layer "In5.Cu")
		(net 839)
	)
	(arc
		(start 253.4385 136.6385)
		(mid 253.526368 136.850632)
		(end 253.7385 136.9385)
		(width 0.114)
		(layer "In5.Cu")
		(net 839)
	)
	(arc
		(start 253.7385 137.5385)
		(mid 253.526368 137.626368)
		(end 253.4385 137.8385)
		(width 0.114)
		(layer "In5.Cu")
		(net 839)
	)
	(arc
		(start 254.178895 137.2385)
		(mid 254.091027 137.450632)
		(end 253.878895 137.5385)
		(width 0.114)
		(layer "In5.Cu")
		(net 839)
	)
	(segment
		(start 231.267 162.682)
		(end 231.565 162.98)
		(width 0.1)
		(layer "F.Cu")
		(net 840)
	)
	(segment
		(start 262.2 145)
		(end 262.95 144.25)
		(width 0.1)
		(layer "F.Cu")
		(net 840)
	)
	(segment
		(start 262.085 145)
		(end 262.2 145)
		(width 0.1)
		(layer "F.Cu")
		(net 840)
	)
	(segment
		(start 261.315 145)
		(end 262.085 145)
		(width 0.1)
		(layer "F.Cu")
		(net 840)
	)
	(segment
		(start 260.8 145)
		(end 261.315 145)
		(width 0.1)
		(layer "F.Cu")
		(net 840)
	)
	(segment
		(start 262.95 144.25)
		(end 263.61 144.25)
		(width 0.1)
		(layer "F.Cu")
		(net 840)
	)
	(segment
		(start 230.338 163.182)
		(end 231.363 163.182)
		(width 0.1)
		(layer "F.Cu")
		(net 840)
	)
	(segment
		(start 230.338 162.682)
		(end 231.267 162.682)
		(width 0.1)
		(layer "F.Cu")
		(net 840)
	)
	(segment
		(start 231.363 163.182)
		(end 231.565 162.98)
		(width 0.1)
		(layer "F.Cu")
		(net 840)
	)
	(via
		(at 260.8 145)
		(size 0.45)
		(drill 0.2)
		(layers "F.Cu" "B.Cu")
		(net 840)
	)
	(via
		(at 231.565 162.98)
		(size 0.45)
		(drill 0.2)
		(layers "F.Cu" "B.Cu")
		(net 840)
	)
	(segment
		(start 239.784316 155.09)
		(end 245.277158 155.09)
		(width 0.1)
		(layer "In3.Cu")
		(net 840)
	)
	(segment
		(start 259.55 145)
		(end 260.8 145)
		(width 0.1)
		(layer "In3.Cu")
		(net 840)
	)
	(segment
		(start 249.067158 151.3)
		(end 258.2 151.3)
		(width 0.1)
		(layer "In3.Cu")
		(net 840)
	)
	(segment
		(start 258.2 151.3)
		(end 258.95 150.55)
		(width 0.1)
		(layer "In3.Cu")
		(net 840)
	)
	(segment
		(start 231.875 162.67)
		(end 231.875 161.835)
		(width 0.1)
		(layer "In3.Cu")
		(net 840)
	)
	(segment
		(start 231.565 162.98)
		(end 231.875 162.67)
		(width 0.1)
		(layer "In3.Cu")
		(net 840)
	)
	(segment
		(start 258.95 145.6)
		(end 259.55 145)
		(width 0.1)
		(layer "In3.Cu")
		(net 840)
	)
	(segment
		(start 258.95 150.55)
		(end 258.95 145.6)
		(width 0.1)
		(layer "In3.Cu")
		(net 840)
	)
	(segment
		(start 231.875 161.835)
		(end 234.242274 159.467726)
		(width 0.1)
		(layer "In3.Cu")
		(net 840)
	)
	(segment
		(start 245.277158 155.09)
		(end 249.067158 151.3)
		(width 0.1)
		(layer "In3.Cu")
		(net 840)
	)
	(segment
		(start 235.40659 159.467726)
		(end 239.784316 155.09)
		(width 0.1)
		(layer "In3.Cu")
		(net 840)
	)
	(segment
		(start 234.242274 159.467726)
		(end 235.40659 159.467726)
		(width 0.1)
		(layer "In3.Cu")
		(net 840)
	)
	(segment
		(start 263.61 128.25)
		(end 262.85 128.25)
		(width 0.182)
		(layer "F.Cu")
		(net 841)
	)
	(segment
		(start 262.6 128)
		(end 262.085 128)
		(width 0.182)
		(layer "F.Cu")
		(net 841)
	)
	(segment
		(start 261.315 128)
		(end 260.685 128)
		(width 0.182)
		(layer "F.Cu")
		(net 841)
	)
	(segment
		(start 262.085 128)
		(end 261.315 128)
		(width 0.182)
		(layer "F.Cu")
		(net 841)
	)
	(segment
		(start 262.85 128.25)
		(end 262.6 128)
		(width 0.182)
		(layer "F.Cu")
		(net 841)
	)
	(segment
		(start 260.685 128)
		(end 260.085 128.6)
		(width 0.182)
		(layer "F.Cu")
		(net 841)
	)
	(segment
		(start 264.4 126.25)
		(end 264.8 125.85)
		(width 0.198)
		(layer "F.Cu")
		(net 842)
	)
	(segment
		(start 262.8 126.25)
		(end 263.61 126.25)
		(width 0.198)
		(layer "F.Cu")
		(net 842)
	)
	(segment
		(start 261.315 127.5)
		(end 260.085 127.5)
		(width 0.198)
		(layer "F.Cu")
		(net 842)
	)
	(segment
		(start 262.75 126.3)
		(end 262.8 126.25)
		(width 0.198)
		(layer "F.Cu")
		(net 842)
	)
	(segment
		(start 263.61 127.25)
		(end 263.185 127.25)
		(width 0.198)
		(layer "F.Cu")
		(net 842)
	)
	(segment
		(start 264.8 125.85)
		(end 264.8 125.375)
		(width 0.198)
		(layer "F.Cu")
		(net 842)
	)
	(segment
		(start 263.185 127.25)
		(end 263.1725 127.2375)
		(width 0.198)
		(layer "F.Cu")
		(net 842)
	)
	(segment
		(start 263.1725 127.2375)
		(end 262.7875 127.2375)
		(width 0.198)
		(layer "F.Cu")
		(net 842)
	)
	(segment
		(start 263.61 126.25)
		(end 264.4 126.25)
		(width 0.198)
		(layer "F.Cu")
		(net 842)
	)
	(segment
		(start 262.7875 127.2375)
		(end 262.525 127.5)
		(width 0.198)
		(layer "F.Cu")
		(net 842)
	)
	(segment
		(start 262.525 127.5)
		(end 261.315 127.5)
		(width 0.198)
		(layer "F.Cu")
		(net 842)
	)
	(via
		(at 264.8 125.375)
		(size 0.45)
		(drill 0.2)
		(layers "F.Cu" "B.Cu")
		(net 842)
	)
	(via
		(at 262.7875 127.2375)
		(size 0.45)
		(drill 0.2)
		(layers "F.Cu" "B.Cu")
		(net 842)
	)
	(via
		(at 262.75 126.3)
		(size 0.45)
		(drill 0.2)
		(layers "F.Cu" "B.Cu")
		(net 842)
	)
	(segment
		(start 264.94 125.235)
		(end 264.8 125.375)
		(width 0.198)
		(layer "B.Cu")
		(net 842)
	)
	(segment
		(start 262.7875 127.2375)
		(end 262.7875 126.3375)
		(width 0.198)
		(layer "B.Cu")
		(net 842)
	)
	(segment
		(start 265.515 125.235)
		(end 264.94 125.235)
		(width 0.198)
		(layer "B.Cu")
		(net 842)
	)
	(segment
		(start 265.515 125.7)
		(end 265.515 125.235)
		(width 0.198)
		(layer "B.Cu")
		(net 842)
	)
	(segment
		(start 262.7875 126.3375)
		(end 262.75 126.3)
		(width 0.198)
		(layer "B.Cu")
		(net 842)
	)
	(segment
		(start 265.515 125.235)
		(end 265.515 124.7)
		(width 0.198)
		(layer "B.Cu")
		(net 842)
	)
	(segment
		(start 264.45 126.95)
		(end 264.25 126.75)
		(width 0.198)
		(layer "F.Cu")
		(net 843)
	)
	(segment
		(start 262.3 126.5)
		(end 262.55 126.75)
		(width 0.198)
		(layer "F.Cu")
		(net 843)
	)
	(segment
		(start 264.45 127.175)
		(end 264.9 127.175)
		(width 0.198)
		(layer "F.Cu")
		(net 843)
	)
	(segment
		(start 264.25 126.75)
		(end 263.61 126.75)
		(width 0.198)
		(layer "F.Cu")
		(net 843)
	)
	(segment
		(start 264.3 127.75)
		(end 264.45 127.6)
		(width 0.198)
		(layer "F.Cu")
		(net 843)
	)
	(segment
		(start 261.315 126.5)
		(end 262.085 126.5)
		(width 0.198)
		(layer "F.Cu")
		(net 843)
	)
	(segment
		(start 264.45 127.6)
		(end 264.45 127.175)
		(width 0.198)
		(layer "F.Cu")
		(net 843)
	)
	(segment
		(start 264.45 127.175)
		(end 264.45 126.95)
		(width 0.198)
		(layer "F.Cu")
		(net 843)
	)
	(segment
		(start 264.9 127.175)
		(end 264.925 127.2)
		(width 0.198)
		(layer "F.Cu")
		(net 843)
	)
	(segment
		(start 262.085 126.5)
		(end 262.3 126.5)
		(width 0.198)
		(layer "F.Cu")
		(net 843)
	)
	(segment
		(start 261.315 126.5)
		(end 260.085 126.5)
		(width 0.198)
		(layer "F.Cu")
		(net 843)
	)
	(segment
		(start 262.55 126.75)
		(end 263.61 126.75)
		(width 0.198)
		(layer "F.Cu")
		(net 843)
	)
	(segment
		(start 263.61 127.75)
		(end 264.3 127.75)
		(width 0.198)
		(layer "F.Cu")
		(net 843)
	)
	(via
		(at 264.925 127.2)
		(size 0.45)
		(drill 0.2)
		(layers "F.Cu" "B.Cu")
		(net 843)
	)
	(segment
		(start 265.515 126.7)
		(end 265.515 127.21)
		(width 0.198)
		(layer "B.Cu")
		(net 843)
	)
	(segment
		(start 264.925 127.2)
		(end 264.935 127.21)
		(width 0.198)
		(layer "B.Cu")
		(net 843)
	)
	(segment
		(start 265.515 127.21)
		(end 265.515 127.7)
		(width 0.198)
		(layer "B.Cu")
		(net 843)
	)
	(segment
		(start 264.935 127.21)
		(end 265.515 127.21)
		(width 0.198)
		(layer "B.Cu")
		(net 843)
	)
	(segment
		(start 260.4 125.5)
		(end 260.9 126)
		(width 0.182)
		(layer "F.Cu")
		(net 844)
	)
	(segment
		(start 260.085 125.5)
		(end 260.4 125.5)
		(width 0.182)
		(layer "F.Cu")
		(net 844)
	)
	(segment
		(start 262.085 126)
		(end 261.315 126)
		(width 0.182)
		(layer "F.Cu")
		(net 844)
	)
	(segment
		(start 262.085 126)
		(end 262.4 126)
		(width 0.182)
		(layer "F.Cu")
		(net 844)
	)
	(segment
		(start 262.835 125.25)
		(end 263.61 125.25)
		(width 0.182)
		(layer "F.Cu")
		(net 844)
	)
	(segment
		(start 262.6925 125.7075)
		(end 262.6925 125.3925)
		(width 0.182)
		(layer "F.Cu")
		(net 844)
	)
	(segment
		(start 262.6925 125.3925)
		(end 262.835 125.25)
		(width 0.182)
		(layer "F.Cu")
		(net 844)
	)
	(segment
		(start 260.9 126)
		(end 261.315 126)
		(width 0.182)
		(layer "F.Cu")
		(net 844)
	)
	(segment
		(start 262.4 126)
		(end 262.6925 125.7075)
		(width 0.182)
		(layer "F.Cu")
		(net 844)
	)
	(segment
		(start 264.3956 168.485)
		(end 263.1 169.7806)
		(width 0.182)
		(layer "B.Cu")
		(net 845)
	)
	(segment
		(start 263.1 169.7806)
		(end 263.1 170.3)
		(width 0.182)
		(layer "B.Cu")
		(net 845)
	)
	(segment
		(start 226.9 152.375)
		(end 226.9 151.4)
		(width 0.1)
		(layer "F.Cu")
		(net 846)
	)
	(segment
		(start 226.9 151.4)
		(end 226.55 151.05)
		(width 0.1)
		(layer "F.Cu")
		(net 846)
	)
	(segment
		(start 227.575 155.45)
		(end 227.575 153.05)
		(width 0.1)
		(layer "F.Cu")
		(net 846)
	)
	(segment
		(start 227.575 153.05)
		(end 226.9 152.375)
		(width 0.1)
		(layer "F.Cu")
		(net 846)
	)
	(segment
		(start 226.55 151.05)
		(end 224.3375 151.05)
		(width 0.1)
		(layer "F.Cu")
		(net 846)
	)
	(via
		(at 227.575 155.45)
		(size 0.45)
		(drill 0.2)
		(layers "F.Cu" "B.Cu")
		(net 846)
	)
	(segment
		(start 227.585 155.44)
		(end 227.575 155.45)
		(width 0.1)
		(layer "B.Cu")
		(net 846)
	)
	(segment
		(start 227.585 155.2)
		(end 227.585 155.44)
		(width 0.1)
		(layer "B.Cu")
		(net 846)
	)
	(segment
		(start 227.585 155.2)
		(end 227.585 154.2)
		(width 0.1)
		(layer "B.Cu")
		(net 846)
	)
	(segment
		(start 264.3956 158.6044)
		(end 261.8 161.2)
		(width 0.1)
		(layer "In3.Cu")
		(net 846)
	)
	(segment
		(start 217.85 164.2)
		(end 217.3 163.65)
		(width 0.1)
		(layer "In3.Cu")
		(net 846)
	)
	(segment
		(start 217.3 163.65)
		(end 217.3 158.72)
		(width 0.1)
		(layer "In3.Cu")
		(net 846)
	)
	(segment
		(start 220.825 157.45)
		(end 220.825 157.925)
		(width 0.1)
		(layer "In3.Cu")
		(net 846)
	)
	(segment
		(start 221.325 164.2)
		(end 217.85 164.2)
		(width 0.1)
		(layer "In3.Cu")
		(net 846)
	)
	(segment
		(start 227.575 157)
		(end 227.575 155.45)
		(width 0.1)
		(layer "In3.Cu")
		(net 846)
	)
	(segment
		(start 231.15 165.5)
		(end 230.625 164.975)
		(width 0.1)
		(layer "In3.Cu")
		(net 846)
	)
	(segment
		(start 231.817158 165.5)
		(end 231.15 165.5)
		(width 0.1)
		(layer "In3.Cu")
		(net 846)
	)
	(segment
		(start 219.145 156.875)
		(end 220.25 156.875)
		(width 0.1)
		(layer "In3.Cu")
		(net 846)
	)
	(segment
		(start 227.5 165.55)
		(end 222.675 165.55)
		(width 0.1)
		(layer "In3.Cu")
		(net 846)
	)
	(segment
		(start 264.3956 157.055)
		(end 264.3956 158.6044)
		(width 0.1)
		(layer "In3.Cu")
		(net 846)
	)
	(segment
		(start 222.675 165.55)
		(end 221.325 164.2)
		(width 0.1)
		(layer "In3.Cu")
		(net 846)
	)
	(segment
		(start 261.8 161.2)
		(end 236.117158 161.2)
		(width 0.1)
		(layer "In3.Cu")
		(net 846)
	)
	(segment
		(start 225.55 159.025)
		(end 227.575 157)
		(width 0.1)
		(layer "In3.Cu")
		(net 846)
	)
	(segment
		(start 236.117158 161.2)
		(end 231.817158 165.5)
		(width 0.1)
		(layer "In3.Cu")
		(net 846)
	)
	(segment
		(start 230.625 164.975)
		(end 228.075 164.975)
		(width 0.1)
		(layer "In3.Cu")
		(net 846)
	)
	(segment
		(start 220.25 156.875)
		(end 220.825 157.45)
		(width 0.1)
		(layer "In3.Cu")
		(net 846)
	)
	(segment
		(start 220.825 157.925)
		(end 221.925 159.025)
		(width 0.1)
		(layer "In3.Cu")
		(net 846)
	)
	(segment
		(start 221.925 159.025)
		(end 225.55 159.025)
		(width 0.1)
		(layer "In3.Cu")
		(net 846)
	)
	(segment
		(start 228.075 164.975)
		(end 227.5 165.55)
		(width 0.1)
		(layer "In3.Cu")
		(net 846)
	)
	(segment
		(start 217.3 158.72)
		(end 219.145 156.875)
		(width 0.1)
		(layer "In3.Cu")
		(net 846)
	)
	(segment
		(start 228.55 153.525)
		(end 228.55 154.025)
		(width 0.1)
		(layer "F.Cu")
		(net 847)
	)
	(segment
		(start 227.175 152.15)
		(end 228.55 153.525)
		(width 0.1)
		(layer "F.Cu")
		(net 847)
	)
	(segment
		(start 227.175 151.175)
		(end 227.175 152.15)
		(width 0.1)
		(layer "F.Cu")
		(net 847)
	)
	(segment
		(start 224.95 150.55)
		(end 225.075 150.675)
		(width 0.1)
		(layer "F.Cu")
		(net 847)
	)
	(segment
		(start 226.675 150.675)
		(end 227.175 151.175)
		(width 0.1)
		(layer "F.Cu")
		(net 847)
	)
	(segment
		(start 225.075 150.675)
		(end 226.675 150.675)
		(width 0.1)
		(layer "F.Cu")
		(net 847)
	)
	(segment
		(start 224.3375 150.55)
		(end 224.95 150.55)
		(width 0.1)
		(layer "F.Cu")
		(net 847)
	)
	(via
		(at 228.55 154.025)
		(size 0.45)
		(drill 0.2)
		(layers "F.Cu" "B.Cu")
		(net 847)
	)
	(segment
		(start 228.515 155.2)
		(end 228.515 154.2)
		(width 0.1)
		(layer "B.Cu")
		(net 847)
	)
	(segment
		(start 221.375 166.375)
		(end 219.55 164.55)
		(width 0.1)
		(layer "In3.Cu")
		(net 847)
	)
	(segment
		(start 263.125 161.5)
		(end 236.1 161.5)
		(width 0.1)
		(layer "In3.Cu")
		(net 847)
	)
	(segment
		(start 226 154.025)
		(end 228.55 154.025)
		(width 0.1)
		(layer "In3.Cu")
		(net 847)
	)
	(segment
		(start 219.55 164.55)
		(end 217.8 164.55)
		(width 0.1)
		(layer "In3.Cu")
		(net 847)
	)
	(segment
		(start 264.3956 165.945)
		(end 264.3956 162.7706)
		(width 0.1)
		(layer "In3.Cu")
		(net 847)
	)
	(segment
		(start 236.1 161.5)
		(end 231.725 165.875)
		(width 0.1)
		(layer "In3.Cu")
		(net 847)
	)
	(segment
		(start 264.3956 162.7706)
		(end 263.125 161.5)
		(width 0.1)
		(layer "In3.Cu")
		(net 847)
	)
	(segment
		(start 223.1 166.375)
		(end 221.375 166.375)
		(width 0.1)
		(layer "In3.Cu")
		(net 847)
	)
	(segment
		(start 223.6 165.875)
		(end 223.1 166.375)
		(width 0.1)
		(layer "In3.Cu")
		(net 847)
	)
	(segment
		(start 219.375 156.1)
		(end 223.925 156.1)
		(width 0.1)
		(layer "In3.Cu")
		(net 847)
	)
	(segment
		(start 223.925 156.1)
		(end 226 154.025)
		(width 0.1)
		(layer "In3.Cu")
		(net 847)
	)
	(segment
		(start 216.9 158.575)
		(end 219.375 156.1)
		(width 0.1)
		(layer "In3.Cu")
		(net 847)
	)
	(segment
		(start 216.9 163.65)
		(end 216.9 158.575)
		(width 0.1)
		(layer "In3.Cu")
		(net 847)
	)
	(segment
		(start 217.8 164.55)
		(end 216.9 163.65)
		(width 0.1)
		(layer "In3.Cu")
		(net 847)
	)
	(segment
		(start 231.725 165.875)
		(end 223.6 165.875)
		(width 0.1)
		(layer "In3.Cu")
		(net 847)
	)
	(via
		(at 264.075 151.75)
		(size 0.45)
		(drill 0.2)
		(layers "F.Cu" "B.Cu")
		(net 848)
	)
	(segment
		(start 263.1 152.5)
		(end 263.325 152.5)
		(width 0.1)
		(layer "B.Cu")
		(net 848)
	)
	(segment
		(start 263.325 152.5)
		(end 264.075 151.75)
		(width 0.1)
		(layer "B.Cu")
		(net 848)
	)
	(segment
		(start 264.3956 152.0706)
		(end 264.075 151.75)
		(width 0.1)
		(layer "In3.Cu")
		(net 848)
	)
	(segment
		(start 264.3956 154.515)
		(end 264.3956 152.0706)
		(width 0.1)
		(layer "In3.Cu")
		(net 848)
	)
	(segment
		(start 249.7 170.3)
		(end 249.7144 170.2856)
		(width 0.182)
		(layer "B.Cu")
		(net 849)
	)
	(segment
		(start 249.7144 170.2856)
		(end 249.7144 168.485)
		(width 0.182)
		(layer "B.Cu")
		(net 849)
	)
	(segment
		(start 203.2 89.6212)
		(end 203.1876 89.6088)
		(width 0.198)
		(layer "F.Cu")
		(net 850)
	)
	(segment
		(start 203.2 90.422851)
		(end 203.2 89.6212)
		(width 0.198)
		(layer "F.Cu")
		(net 850)
	)
	(via
		(at 203.1876 89.6088)
		(size 0.45)
		(drill 0.2)
		(layers "F.Cu" "B.Cu")
		(net 850)
	)
	(segment
		(start 233.4 116.125)
		(end 233.4 102.9)
		(width 0.198)
		(layer "B.Cu")
		(net 850)
	)
	(segment
		(start 236.975 119.7)
		(end 233.4 116.125)
		(width 0.198)
		(layer "B.Cu")
		(net 850)
	)
	(segment
		(start 203.1876 89.6088)
		(end 203.5176 89.6088)
		(width 0.198)
		(layer "B.Cu")
		(net 850)
	)
	(segment
		(start 203.2 91.285)
		(end 203.2 92.215)
		(width 0.198)
		(layer "B.Cu")
		(net 850)
	)
	(segment
		(start 236.975 123.6)
		(end 236.975 119.7)
		(width 0.198)
		(layer "B.Cu")
		(net 850)
	)
	(segment
		(start 223.325 101.225)
		(end 212.35 90.25)
		(width 0.198)
		(layer "B.Cu")
		(net 850)
	)
	(segment
		(start 212.35 90.25)
		(end 203.95 90.25)
		(width 0.198)
		(layer "B.Cu")
		(net 850)
	)
	(segment
		(start 241.875 151.25)
		(end 241.2 150.575)
		(width 0.198)
		(layer "B.Cu")
		(net 850)
	)
	(segment
		(start 203.8 90.3)
		(end 203.9 90.2)
		(width 0.198)
		(layer "B.Cu")
		(net 850)
	)
	(segment
		(start 253.5244 152.0244)
		(end 252.75 151.25)
		(width 0.198)
		(layer "B.Cu")
		(net 850)
	)
	(segment
		(start 252.75 151.25)
		(end 241.875 151.25)
		(width 0.198)
		(layer "B.Cu")
		(net 850)
	)
	(segment
		(start 235.55 143.55)
		(end 235.55 125.025)
		(width 0.198)
		(layer "B.Cu")
		(net 850)
	)
	(segment
		(start 203.9 90.2)
		(end 203.8 90.1)
		(width 0.198)
		(layer "B.Cu")
		(net 850)
	)
	(segment
		(start 203.8 90.1)
		(end 203.8 90.2)
		(width 0.198)
		(layer "B.Cu")
		(net 850)
	)
	(segment
		(start 235.55 125.025)
		(end 236.975 123.6)
		(width 0.198)
		(layer "B.Cu")
		(net 850)
	)
	(segment
		(start 233.4 102.9)
		(end 231.725 101.225)
		(width 0.198)
		(layer "B.Cu")
		(net 850)
	)
	(segment
		(start 241.2 150.575)
		(end 241.2 149.2)
		(width 0.198)
		(layer "B.Cu")
		(net 850)
	)
	(segment
		(start 231.725 101.225)
		(end 223.325 101.225)
		(width 0.198)
		(layer "B.Cu")
		(net 850)
	)
	(segment
		(start 203.8 90.2)
		(end 203.8 90.4)
		(width 0.198)
		(layer "B.Cu")
		(net 850)
	)
	(segment
		(start 203.8 90.685)
		(end 203.2 91.285)
		(width 0.198)
		(layer "B.Cu")
		(net 850)
	)
	(segment
		(start 253.5244 154.515)
		(end 253.5244 152.0244)
		(width 0.198)
		(layer "B.Cu")
		(net 850)
	)
	(segment
		(start 203.8 89.8912)
		(end 203.8 90.1)
		(width 0.198)
		(layer "B.Cu")
		(net 850)
	)
	(segment
		(start 241.2 149.2)
		(end 235.55 143.55)
		(width 0.198)
		(layer "B.Cu")
		(net 850)
	)
	(segment
		(start 203.8 90.4)
		(end 203.8 90.685)
		(width 0.198)
		(layer "B.Cu")
		(net 850)
	)
	(segment
		(start 203.8 90.4)
		(end 203.8 90.3)
		(width 0.198)
		(layer "B.Cu")
		(net 850)
	)
	(segment
		(start 203.95 90.25)
		(end 203.9 90.2)
		(width 0.198)
		(layer "B.Cu")
		(net 850)
	)
	(segment
		(start 203.5176 89.6088)
		(end 203.8 89.8912)
		(width 0.198)
		(layer "B.Cu")
		(net 850)
	)
	(segment
		(start 202.2 90.422851)
		(end 202.2 89.688)
		(width 0.198)
		(layer "F.Cu")
		(net 851)
	)
	(segment
		(start 202.2 89.688)
		(end 202.1716 89.6596)
		(width 0.198)
		(layer "F.Cu")
		(net 851)
	)
	(via
		(at 202.1716 89.6596)
		(size 0.45)
		(drill 0.2)
		(layers "F.Cu" "B.Cu")
		(net 851)
	)
	(segment
		(start 202.2 91.285)
		(end 202.2 92.215)
		(width 0.198)
		(layer "B.Cu")
		(net 851)
	)
	(segment
		(start 237.375 119.575)
		(end 233.75 115.95)
		(width 0.198)
		(layer "B.Cu")
		(net 851)
	)
	(segment
		(start 205.25 89.85)
		(end 203.7 88.3)
		(width 0.198)
		(layer "B.Cu")
		(net 851)
	)
	(segment
		(start 202.3 88.3)
		(end 202.1716 88.4284)
		(width 0.198)
		(layer "B.Cu")
		(net 851)
	)
	(segment
		(start 202.1716 89.6596)
		(end 201.8404 89.6596)
		(width 0.198)
		(layer "B.Cu")
		(net 851)
	)
	(segment
		(start 258.765 168.485)
		(end 259 168.25)
		(width 0.198)
		(layer "B.Cu")
		(net 851)
	)
	(segment
		(start 259 155.2)
		(end 256.8 153)
		(width 0.198)
		(layer "B.Cu")
		(net 851)
	)
	(segment
		(start 233.75 115.95)
		(end 233.75 102.725)
		(width 0.198)
		(layer "B.Cu")
		(net 851)
	)
	(segment
		(start 201.6 89.9)
		(end 201.6 90.685)
		(width 0.198)
		(layer "B.Cu")
		(net 851)
	)
	(segment
		(start 237.375 123.725)
		(end 237.375 119.575)
		(width 0.198)
		(layer "B.Cu")
		(net 851)
	)
	(segment
		(start 259 168.25)
		(end 259 155.2)
		(width 0.198)
		(layer "B.Cu")
		(net 851)
	)
	(segment
		(start 241.616 149.041)
		(end 235.925 143.35)
		(width 0.198)
		(layer "B.Cu")
		(net 851)
	)
	(segment
		(start 203.7 88.3)
		(end 202.3 88.3)
		(width 0.198)
		(layer "B.Cu")
		(net 851)
	)
	(segment
		(start 231.85 100.825)
		(end 223.518 100.825)
		(width 0.198)
		(layer "B.Cu")
		(net 851)
	)
	(segment
		(start 235.925 143.35)
		(end 235.925 125.175)
		(width 0.198)
		(layer "B.Cu")
		(net 851)
	)
	(segment
		(start 256.8 151.518)
		(end 256.132 150.85)
		(width 0.198)
		(layer "B.Cu")
		(net 851)
	)
	(segment
		(start 201.6 90.685)
		(end 202.2 91.285)
		(width 0.198)
		(layer "B.Cu")
		(net 851)
	)
	(segment
		(start 223.518 100.825)
		(end 212.543 89.85)
		(width 0.198)
		(layer "B.Cu")
		(net 851)
	)
	(segment
		(start 256.8 153)
		(end 256.8 151.518)
		(width 0.198)
		(layer "B.Cu")
		(net 851)
	)
	(segment
		(start 256.0644 168.485)
		(end 258.765 168.485)
		(width 0.198)
		(layer "B.Cu")
		(net 851)
	)
	(segment
		(start 233.75 102.725)
		(end 231.85 100.825)
		(width 0.198)
		(layer "B.Cu")
		(net 851)
	)
	(segment
		(start 201.8404 89.6596)
		(end 201.6 89.9)
		(width 0.198)
		(layer "B.Cu")
		(net 851)
	)
	(segment
		(start 256.132 150.85)
		(end 242.125 150.85)
		(width 0.198)
		(layer "B.Cu")
		(net 851)
	)
	(segment
		(start 202.1716 88.4284)
		(end 202.1716 89.6596)
		(width 0.198)
		(layer "B.Cu")
		(net 851)
	)
	(segment
		(start 241.616 150.341)
		(end 241.616 149.041)
		(width 0.198)
		(layer "B.Cu")
		(net 851)
	)
	(segment
		(start 242.125 150.85)
		(end 241.616 150.341)
		(width 0.198)
		(layer "B.Cu")
		(net 851)
	)
	(segment
		(start 212.543 89.85)
		(end 205.25 89.85)
		(width 0.198)
		(layer "B.Cu")
		(net 851)
	)
	(segment
		(start 235.925 125.175)
		(end 237.375 123.725)
		(width 0.198)
		(layer "B.Cu")
		(net 851)
	)
	(segment
		(start 256.0644 154.515)
		(end 256.0644 152.5356)
		(width 0.182)
		(layer "B.Cu")
		(net 852)
	)
	(segment
		(start 256.0644 152.5356)
		(end 256.1 152.5)
		(width 0.182)
		(layer "B.Cu")
		(net 852)
	)
	(segment
		(start 204.877149 91.6)
		(end 205.735665 91.6)
		(width 0.153)
		(layer "F.Cu")
		(net 853)
	)
	(segment
		(start 205.735665 91.6)
		(end 205.814665 91.521)
		(width 0.153)
		(layer "F.Cu")
		(net 853)
	)
	(via
		(at 205.814665 91.521)
		(size 0.45)
		(drill 0.2)
		(layers "F.Cu" "B.Cu")
		(net 853)
	)
	(segment
		(start 249.174766 154.4195)
		(end 246.824766 152.0695)
		(width 0.153)
		(layer "B.Cu")
		(net 853)
	)
	(segment
		(start 232.132647 135.332647)
		(end 231.952147 135.332647)
		(width 0.153)
		(layer "B.Cu")
		(net 853)
	)
	(segment
		(start 239.9305 148.675234)
		(end 232.6805 141.425234)
		(width 0.153)
		(layer "B.Cu")
		(net 853)
	)
	(segment
		(start 206.678559 91.6695)
		(end 206.457559 91.4485)
		(width 0.153)
		(layer "B.Cu")
		(net 853)
	)
	(segment
		(start 231.952147 133.436)
		(end 232.132647 133.436)
		(width 0.153)
		(layer "B.Cu")
		(net 853)
	)
	(segment
		(start 255.786266 158.198)
		(end 255.596573 158.008307)
		(width 0.153)
		(layer "B.Cu")
		(net 853)
	)
	(segment
		(start 206.457559 91.4485)
		(end 206.124945 91.4485)
		(width 0.153)
		(layer "B.Cu")
		(net 853)
	)
	(segment
		(start 254.974766 155.8195)
		(end 253.074766 155.8195)
		(width 0.153)
		(layer "B.Cu")
		(net 853)
	)
	(segment
		(start 223.174766 102.2195)
		(end 212.624766 91.6695)
		(width 0.153)
		(layer "B.Cu")
		(net 853)
	)
	(segment
		(start 253.074766 155.8195)
		(end 251.674766 154.4195)
		(width 0.153)
		(layer "B.Cu")
		(net 853)
	)
	(segment
		(start 231.765294 133.638147)
		(end 231.765294 133.622853)
		(width 0.153)
		(layer "B.Cu")
		(net 853)
	)
	(segment
		(start 233.047853 133.825)
		(end 232.6805 133.825)
		(width 0.153)
		(layer "B.Cu")
		(net 853)
	)
	(segment
		(start 232.6805 131.297547)
		(end 232.6805 102.925234)
		(width 0.153)
		(layer "B.Cu")
		(net 853)
	)
	(segment
		(start 232.6805 102.925234)
		(end 231.974766 102.2195)
		(width 0.153)
		(layer "B.Cu")
		(net 853)
	)
	(segment
		(start 256.801 158.198)
		(end 255.786266 158.198)
		(width 0.153)
		(layer "B.Cu")
		(net 853)
	)
	(segment
		(start 241.074766 152.0695)
		(end 239.9305 150.925234)
		(width 0.153)
		(layer "B.Cu")
		(net 853)
	)
	(segment
		(start 239.9305 150.925234)
		(end 239.9305 148.675234)
		(width 0.153)
		(layer "B.Cu")
		(net 853)
	)
	(segment
		(start 231.765294 135.145794)
		(end 231.765294 135.1305)
		(width 0.153)
		(layer "B.Cu")
		(net 853)
	)
	(segment
		(start 206.124945 91.4485)
		(end 205.933555 91.63989)
		(width 0.153)
		(layer "B.Cu")
		(net 853)
	)
	(segment
		(start 255.596573 156.441307)
		(end 254.974766 155.8195)
		(width 0.153)
		(layer "B.Cu")
		(net 853)
	)
	(segment
		(start 232.6805 141.425234)
		(end 232.6805 135.8805)
		(width 0.153)
		(layer "B.Cu")
		(net 853)
	)
	(segment
		(start 212.624766 91.6695)
		(end 206.678559 91.6695)
		(width 0.153)
		(layer "B.Cu")
		(net 853)
	)
	(segment
		(start 233.595706 134.388147)
		(end 233.595706 134.372853)
		(width 0.153)
		(layer "B.Cu")
		(net 853)
	)
	(segment
		(start 231.952147 134.943647)
		(end 232.132647 134.943647)
		(width 0.153)
		(layer "B.Cu")
		(net 853)
	)
	(segment
		(start 231.974766 102.2195)
		(end 223.174766 102.2195)
		(width 0.153)
		(layer "B.Cu")
		(net 853)
	)
	(segment
		(start 251.674766 154.4195)
		(end 249.174766 154.4195)
		(width 0.153)
		(layer "B.Cu")
		(net 853)
	)
	(segment
		(start 232.6805 132.888147)
		(end 232.6805 131.297547)
		(width 0.153)
		(layer "B.Cu")
		(net 853)
	)
	(segment
		(start 255.596573 158.008307)
		(end 255.596573 156.441307)
		(width 0.153)
		(layer "B.Cu")
		(net 853)
	)
	(segment
		(start 246.824766 152.0695)
		(end 241.074766 152.0695)
		(width 0.153)
		(layer "B.Cu")
		(net 853)
	)
	(segment
		(start 232.6805 133.825)
		(end 231.952147 133.825)
		(width 0.153)
		(layer "B.Cu")
		(net 853)
	)
	(segment
		(start 232.5 134.936)
		(end 233.047853 134.936)
		(width 0.153)
		(layer "B.Cu")
		(net 853)
	)
	(segment
		(start 232.5 134.943647)
		(end 232.5 134.936)
		(width 0.153)
		(layer "B.Cu")
		(net 853)
	)
	(segment
		(start 232.132647 134.943647)
		(end 232.5 134.943647)
		(width 0.153)
		(layer "B.Cu")
		(net 853)
	)
	(segment
		(start 205.933555 91.63989)
		(end 205.814665 91.521)
		(width 0.153)
		(layer "B.Cu")
		(net 853)
	)
	(arc
		(start 232.132647 133.436)
		(mid 232.520038 133.275538)
		(end 232.6805 132.888147)
		(width 0.153)
		(layer "B.Cu")
		(net 853)
	)
	(arc
		(start 233.595706 134.372853)
		(mid 233.435244 133.985462)
		(end 233.047853 133.825)
		(width 0.153)
		(layer "B.Cu")
		(net 853)
	)
	(arc
		(start 232.6805 135.8805)
		(mid 232.520038 135.493109)
		(end 232.132647 135.332647)
		(width 0.153)
		(layer "B.Cu")
		(net 853)
	)
	(arc
		(start 231.765294 135.1305)
		(mid 231.820022 134.998375)
		(end 231.952147 134.943647)
		(width 0.153)
		(layer "B.Cu")
		(net 853)
	)
	(arc
		(start 233.047853 134.936)
		(mid 233.435244 134.775538)
		(end 233.595706 134.388147)
		(width 0.153)
		(layer "B.Cu")
		(net 853)
	)
	(arc
		(start 231.952147 133.825)
		(mid 231.820022 133.770272)
		(end 231.765294 133.638147)
		(width 0.153)
		(layer "B.Cu")
		(net 853)
	)
	(arc
		(start 231.952147 135.332647)
		(mid 231.820022 135.277919)
		(end 231.765294 135.145794)
		(width 0.153)
		(layer "B.Cu")
		(net 853)
	)
	(arc
		(start 231.765294 133.622853)
		(mid 231.820022 133.490728)
		(end 231.952147 133.436)
		(width 0.153)
		(layer "B.Cu")
		(net 853)
	)
	(segment
		(start 204.877149 92.1)
		(end 205.735665 92.1)
		(width 0.153)
		(layer "F.Cu")
		(net 854)
	)
	(segment
		(start 205.735665 92.1)
		(end 205.814665 92.179)
		(width 0.153)
		(layer "F.Cu")
		(net 854)
	)
	(via
		(at 205.814665 92.179)
		(size 0.45)
		(drill 0.2)
		(layers "F.Cu" "B.Cu")
		(net 854)
	)
	(segment
		(start 232.3195 103.074766)
		(end 231.825234 102.5805)
		(width 0.153)
		(layer "B.Cu")
		(net 854)
	)
	(segment
		(start 255.235573 156.590839)
		(end 254.825234 156.1805)
		(width 0.153)
		(layer "B.Cu")
		(net 854)
	)
	(segment
		(start 208.2555 92.0305)
		(end 206.678559 92.0305)
		(width 0.153)
		(layer "B.Cu")
		(net 854)
	)
	(segment
		(start 254.825234 156.1805)
		(end 252.925234 156.1805)
		(width 0.153)
		(layer "B.Cu")
		(net 854)
	)
	(segment
		(start 232.3195 141.574766)
		(end 232.3195 135.8805)
		(width 0.153)
		(layer "B.Cu")
		(net 854)
	)
	(segment
		(start 232.132647 135.693647)
		(end 231.952147 135.693647)
		(width 0.153)
		(layer "B.Cu")
		(net 854)
	)
	(segment
		(start 252.925234 156.1805)
		(end 251.525234 154.7805)
		(width 0.153)
		(layer "B.Cu")
		(net 854)
	)
	(segment
		(start 212.475234 92.0305)
		(end 208.7615 92.0305)
		(width 0.153)
		(layer "B.Cu")
		(net 854)
	)
	(segment
		(start 255.531 159.468)
		(end 255.531 158.453266)
		(width 0.153)
		(layer "B.Cu")
		(net 854)
	)
	(segment
		(start 232.3195 132.888147)
		(end 232.3195 131.297547)
		(width 0.153)
		(layer "B.Cu")
		(net 854)
	)
	(segment
		(start 255.235573 158.157839)
		(end 255.235573 156.590839)
		(width 0.153)
		(layer "B.Cu")
		(net 854)
	)
	(segment
		(start 231.952147 133.075)
		(end 232.132647 133.075)
		(width 0.153)
		(layer "B.Cu")
		(net 854)
	)
	(segment
		(start 206.124945 92.2515)
		(end 205.933555 92.06011)
		(width 0.153)
		(layer "B.Cu")
		(net 854)
	)
	(segment
		(start 251.525234 154.7805)
		(end 249.025234 154.7805)
		(width 0.153)
		(layer "B.Cu")
		(net 854)
	)
	(segment
		(start 231.825234 102.5805)
		(end 223.025234 102.5805)
		(width 0.153)
		(layer "B.Cu")
		(net 854)
	)
	(segment
		(start 232.5 134.575)
		(end 233.047853 134.575)
		(width 0.153)
		(layer "B.Cu")
		(net 854)
	)
	(segment
		(start 232.3195 131.297547)
		(end 232.3195 103.074766)
		(width 0.153)
		(layer "B.Cu")
		(net 854)
	)
	(segment
		(start 255.531 158.453266)
		(end 255.235573 158.157839)
		(width 0.153)
		(layer "B.Cu")
		(net 854)
	)
	(segment
		(start 205.933555 92.06011)
		(end 205.814665 92.179)
		(width 0.153)
		(layer "B.Cu")
		(net 854)
	)
	(segment
		(start 233.234706 134.388147)
		(end 233.234706 134.372853)
		(width 0.153)
		(layer "B.Cu")
		(net 854)
	)
	(segment
		(start 206.678559 92.0305)
		(end 206.457559 92.2515)
		(width 0.153)
		(layer "B.Cu")
		(net 854)
	)
	(segment
		(start 232.132647 134.582647)
		(end 232.5 134.582647)
		(width 0.153)
		(layer "B.Cu")
		(net 854)
	)
	(segment
		(start 208.382 92.162122)
		(end 208.382 92.157)
		(width 0.153)
		(layer "B.Cu")
		(net 854)
	)
	(segment
		(start 231.952147 134.582647)
		(end 232.132647 134.582647)
		(width 0.153)
		(layer "B.Cu")
		(net 854)
	)
	(segment
		(start 223.025234 102.5805)
		(end 212.475234 92.0305)
		(width 0.153)
		(layer "B.Cu")
		(net 854)
	)
	(segment
		(start 249.025234 154.7805)
		(end 246.675234 152.4305)
		(width 0.153)
		(layer "B.Cu")
		(net 854)
	)
	(segment
		(start 231.404294 133.638147)
		(end 231.404294 133.622853)
		(width 0.153)
		(layer "B.Cu")
		(net 854)
	)
	(segment
		(start 208.635 92.157)
		(end 208.635 92.162122)
		(width 0.153)
		(layer "B.Cu")
		(net 854)
	)
	(segment
		(start 206.457559 92.2515)
		(end 206.124945 92.2515)
		(width 0.153)
		(layer "B.Cu")
		(net 854)
	)
	(segment
		(start 239.5695 151.074766)
		(end 239.5695 148.824766)
		(width 0.153)
		(layer "B.Cu")
		(net 854)
	)
	(segment
		(start 232.5 134.582647)
		(end 232.5 134.575)
		(width 0.153)
		(layer "B.Cu")
		(net 854)
	)
	(segment
		(start 246.675234 152.4305)
		(end 240.925234 152.4305)
		(width 0.153)
		(layer "B.Cu")
		(net 854)
	)
	(segment
		(start 232.6805 134.186)
		(end 231.952147 134.186)
		(width 0.153)
		(layer "B.Cu")
		(net 854)
	)
	(segment
		(start 231.404294 135.145794)
		(end 231.404294 135.1305)
		(width 0.153)
		(layer "B.Cu")
		(net 854)
	)
	(segment
		(start 239.5695 148.824766)
		(end 232.3195 141.574766)
		(width 0.153)
		(layer "B.Cu")
		(net 854)
	)
	(segment
		(start 240.925234 152.4305)
		(end 239.5695 151.074766)
		(width 0.153)
		(layer "B.Cu")
		(net 854)
	)
	(segment
		(start 233.047853 134.186)
		(end 232.6805 134.186)
		(width 0.153)
		(layer "B.Cu")
		(net 854)
	)
	(arc
		(start 208.7615 92.0305)
		(mid 208.672051 92.067551)
		(end 208.635 92.157)
		(width 0.153)
		(layer "B.Cu")
		(net 854)
	)
	(arc
		(start 208.382 92.157)
		(mid 208.344949 92.067551)
		(end 208.2555 92.0305)
		(width 0.153)
		(layer "B.Cu")
		(net 854)
	)
	(arc
		(start 231.404294 133.622853)
		(mid 231.564756 133.235462)
		(end 231.952147 133.075)
		(width 0.153)
		(layer "B.Cu")
		(net 854)
	)
	(arc
		(start 232.132647 133.075)
		(mid 232.264772 133.020272)
		(end 232.3195 132.888147)
		(width 0.153)
		(layer "B.Cu")
		(net 854)
	)
	(arc
		(start 208.5085 92.288622)
		(mid 208.419051 92.251571)
		(end 208.382 92.162122)
		(width 0.153)
		(layer "B.Cu")
		(net 854)
	)
	(arc
		(start 231.952147 134.186)
		(mid 231.564756 134.025538)
		(end 231.404294 133.638147)
		(width 0.153)
		(layer "B.Cu")
		(net 854)
	)
	(arc
		(start 233.047853 134.575)
		(mid 233.179978 134.520272)
		(end 233.234706 134.388147)
		(width 0.153)
		(layer "B.Cu")
		(net 854)
	)
	(arc
		(start 231.952147 135.693647)
		(mid 231.564756 135.533185)
		(end 231.404294 135.145794)
		(width 0.153)
		(layer "B.Cu")
		(net 854)
	)
	(arc
		(start 233.234706 134.372853)
		(mid 233.179978 134.240728)
		(end 233.047853 134.186)
		(width 0.153)
		(layer "B.Cu")
		(net 854)
	)
	(arc
		(start 208.635 92.162122)
		(mid 208.597949 92.251571)
		(end 208.5085 92.288622)
		(width 0.153)
		(layer "B.Cu")
		(net 854)
	)
	(arc
		(start 232.3195 135.8805)
		(mid 232.264772 135.748375)
		(end 232.132647 135.693647)
		(width 0.153)
		(layer "B.Cu")
		(net 854)
	)
	(arc
		(start 231.404294 135.1305)
		(mid 231.564756 134.743109)
		(end 231.952147 134.582647)
		(width 0.153)
		(layer "B.Cu")
		(net 854)
	)
	(segment
		(start 204.878149 93.101)
		(end 205.70693 93.101)
		(width 0.153)
		(layer "F.Cu")
		(net 855)
	)
	(segment
		(start 205.70693 93.101)
		(end 205.78693 93.021)
		(width 0.153)
		(layer "F.Cu")
		(net 855)
	)
	(via
		(at 205.78693 93.021)
		(size 0.45)
		(drill 0.2)
		(layers "F.Cu" "B.Cu")
		(net 855)
	)
	(segment
		(start 230.5805 124.799188)
		(end 230.5805 140.925234)
		(width 0.153)
		(layer "B.Cu")
		(net 855)
	)
	(segment
		(start 253.246266 158.198)
		(end 254.261 158.198)
		(width 0.153)
		(layer "B.Cu")
		(net 855)
	)
	(segment
		(start 248.774766 155.3195)
		(end 251.174766 155.3195)
		(width 0.153)
		(layer "B.Cu")
		(net 855)
	)
	(segment
		(start 222.174766 103.2195)
		(end 229.374766 103.2195)
		(width 0.153)
		(layer "B.Cu")
		(net 855)
	)
	(segment
		(start 231.092619 121.6)
		(end 230.8 121.6)
		(width 0.153)
		(layer "B.Cu")
		(net 855)
	)
	(segment
		(start 230.5805 140.925234)
		(end 238.1805 148.525234)
		(width 0.153)
		(layer "B.Cu")
		(net 855)
	)
	(segment
		(start 251.174766 155.3195)
		(end 253.0805 157.225234)
		(width 0.153)
		(layer "B.Cu")
		(net 855)
	)
	(segment
		(start 246.774766 153.3195)
		(end 248.774766 155.3195)
		(width 0.153)
		(layer "B.Cu")
		(net 855)
	)
	(segment
		(start 206.397046 92.943517)
		(end 206.623029 93.1695)
		(width 0.153)
		(layer "B.Cu")
		(net 855)
	)
	(segment
		(start 231.092619 120)
		(end 230.5805 120)
		(width 0.153)
		(layer "B.Cu")
		(net 855)
	)
	(segment
		(start 230.5805 104.425234)
		(end 230.5805 117.0195)
		(width 0.153)
		(layer "B.Cu")
		(net 855)
	)
	(segment
		(start 229.807381 120.439)
		(end 230.2195 120.439)
		(width 0.153)
		(layer "B.Cu")
		(net 855)
	)
	(segment
		(start 253.0805 158.032234)
		(end 253.246266 158.198)
		(width 0.153)
		(layer "B.Cu")
		(net 855)
	)
	(segment
		(start 231.092619 118.4)
		(end 230.8 118.4)
		(width 0.153)
		(layer "B.Cu")
		(net 855)
	)
	(segment
		(start 229.807381 118.839)
		(end 230.2195 118.839)
		(width 0.153)
		(layer "B.Cu")
		(net 855)
	)
	(segment
		(start 230.5805 120)
		(end 229.807381 120)
		(width 0.153)
		(layer "B.Cu")
		(net 855)
	)
	(segment
		(start 239.824766 153.3195)
		(end 246.774766 153.3195)
		(width 0.153)
		(layer "B.Cu")
		(net 855)
	)
	(segment
		(start 205.88694 93.12101)
		(end 206.064432 92.943517)
		(width 0.153)
		(layer "B.Cu")
		(net 855)
	)
	(segment
		(start 238.1805 151.675234)
		(end 239.824766 153.3195)
		(width 0.153)
		(layer "B.Cu")
		(net 855)
	)
	(segment
		(start 212.124766 93.1695)
		(end 222.174766 103.2195)
		(width 0.153)
		(layer "B.Cu")
		(net 855)
	)
	(segment
		(start 230.8 117.239)
		(end 231.092619 117.239)
		(width 0.153)
		(layer "B.Cu")
		(net 855)
	)
	(segment
		(start 238.1805 148.525234)
		(end 238.1805 151.675234)
		(width 0.153)
		(layer "B.Cu")
		(net 855)
	)
	(segment
		(start 230.2195 120.439)
		(end 231.092619 120.439)
		(width 0.153)
		(layer "B.Cu")
		(net 855)
	)
	(segment
		(start 230.2195 118.839)
		(end 231.092619 118.839)
		(width 0.153)
		(layer "B.Cu")
		(net 855)
	)
	(segment
		(start 230.8 118.4)
		(end 229.807381 118.4)
		(width 0.153)
		(layer "B.Cu")
		(net 855)
	)
	(segment
		(start 206.623029 93.1695)
		(end 212.124766 93.1695)
		(width 0.153)
		(layer "B.Cu")
		(net 855)
	)
	(segment
		(start 206.064432 92.943517)
		(end 206.397046 92.943517)
		(width 0.153)
		(layer "B.Cu")
		(net 855)
	)
	(segment
		(start 230.5805 121.8195)
		(end 230.5805 124.799188)
		(width 0.153)
		(layer "B.Cu")
		(net 855)
	)
	(segment
		(start 229.374766 103.2195)
		(end 230.5805 104.425234)
		(width 0.153)
		(layer "B.Cu")
		(net 855)
	)
	(segment
		(start 205.78693 93.021)
		(end 205.88694 93.12101)
		(width 0.153)
		(layer "B.Cu")
		(net 855)
	)
	(segment
		(start 253.0805 157.225234)
		(end 253.0805 158.032234)
		(width 0.153)
		(layer "B.Cu")
		(net 855)
	)
	(arc
		(start 231.092619 120.439)
		(mid 231.503094 120.609025)
		(end 231.673119 121.0195)
		(width 0.153)
		(layer "B.Cu")
		(net 855)
	)
	(arc
		(start 229.587881 120.2195)
		(mid 229.652171 120.37471)
		(end 229.807381 120.439)
		(width 0.153)
		(layer "B.Cu")
		(net 855)
	)
	(arc
		(start 229.807381 118.4)
		(mid 229.652171 118.46429)
		(end 229.587881 118.6195)
		(width 0.153)
		(layer "B.Cu")
		(net 855)
	)
	(arc
		(start 230.8 121.6)
		(mid 230.64479 121.66429)
		(end 230.5805 121.8195)
		(width 0.153)
		(layer "B.Cu")
		(net 855)
	)
	(arc
		(start 231.673119 119.4195)
		(mid 231.503094 119.829975)
		(end 231.092619 120)
		(width 0.153)
		(layer "B.Cu")
		(net 855)
	)
	(arc
		(start 231.092619 117.239)
		(mid 231.503094 117.409025)
		(end 231.673119 117.8195)
		(width 0.153)
		(layer "B.Cu")
		(net 855)
	)
	(arc
		(start 231.092619 118.839)
		(mid 231.503094 119.009025)
		(end 231.673119 119.4195)
		(width 0.153)
		(layer "B.Cu")
		(net 855)
	)
	(arc
		(start 231.673119 117.8195)
		(mid 231.503094 118.229975)
		(end 231.092619 118.4)
		(width 0.153)
		(layer "B.Cu")
		(net 855)
	)
	(arc
		(start 229.807381 120)
		(mid 229.652171 120.06429)
		(end 229.587881 120.2195)
		(width 0.153)
		(layer "B.Cu")
		(net 855)
	)
	(arc
		(start 229.587881 118.6195)
		(mid 229.652171 118.77471)
		(end 229.807381 118.839)
		(width 0.153)
		(layer "B.Cu")
		(net 855)
	)
	(arc
		(start 231.673119 121.0195)
		(mid 231.503094 121.429975)
		(end 231.092619 121.6)
		(width 0.153)
		(layer "B.Cu")
		(net 855)
	)
	(arc
		(start 230.5805 117.0195)
		(mid 230.64479 117.17471)
		(end 230.8 117.239)
		(width 0.153)
		(layer "B.Cu")
		(net 855)
	)
	(segment
		(start 204.878149 93.601)
		(end 205.70893 93.601)
		(width 0.153)
		(layer "F.Cu")
		(net 856)
	)
	(segment
		(start 205.70893 93.601)
		(end 205.78693 93.679)
		(width 0.153)
		(layer "F.Cu")
		(net 856)
	)
	(via
		(at 205.78693 93.679)
		(size 0.45)
		(drill 0.2)
		(layers "F.Cu" "B.Cu")
		(net 856)
	)
	(segment
		(start 229.225234 103.5805)
		(end 230.2195 104.574766)
		(width 0.153)
		(layer "B.Cu")
		(net 856)
	)
	(segment
		(start 230.2195 120.8)
		(end 231.092619 120.8)
		(width 0.153)
		(layer "B.Cu")
		(net 856)
	)
	(segment
		(start 230.8 117.6)
		(end 231.092619 117.6)
		(width 0.153)
		(layer "B.Cu")
		(net 856)
	)
	(segment
		(start 246.625234 153.6805)
		(end 248.625234 155.6805)
		(width 0.153)
		(layer "B.Cu")
		(net 856)
	)
	(segment
		(start 230.2195 124.799188)
		(end 230.2195 141.074766)
		(width 0.153)
		(layer "B.Cu")
		(net 856)
	)
	(segment
		(start 231.092619 121.239)
		(end 230.8 121.239)
		(width 0.153)
		(layer "B.Cu")
		(net 856)
	)
	(segment
		(start 252.7195 157.374766)
		(end 252.7195 158.181766)
		(width 0.153)
		(layer "B.Cu")
		(net 856)
	)
	(segment
		(start 211.975234 93.5305)
		(end 222.025234 103.5805)
		(width 0.153)
		(layer "B.Cu")
		(net 856)
	)
	(segment
		(start 230.2195 119.2)
		(end 231.092619 119.2)
		(width 0.153)
		(layer "B.Cu")
		(net 856)
	)
	(segment
		(start 206.397046 93.746517)
		(end 206.613063 93.5305)
		(width 0.153)
		(layer "B.Cu")
		(net 856)
	)
	(segment
		(start 231.092619 119.639)
		(end 230.5805 119.639)
		(width 0.153)
		(layer "B.Cu")
		(net 856)
	)
	(segment
		(start 205.78693 93.679)
		(end 205.891923 93.574007)
		(width 0.153)
		(layer "B.Cu")
		(net 856)
	)
	(segment
		(start 205.891923 93.574007)
		(end 206.064432 93.746517)
		(width 0.153)
		(layer "B.Cu")
		(net 856)
	)
	(segment
		(start 231.092619 118.039)
		(end 230.8 118.039)
		(width 0.153)
		(layer "B.Cu")
		(net 856)
	)
	(segment
		(start 230.8 118.039)
		(end 229.807381 118.039)
		(width 0.153)
		(layer "B.Cu")
		(net 856)
	)
	(segment
		(start 208.7005 93.5305)
		(end 209.124894 93.5305)
		(width 0.153)
		(layer "B.Cu")
		(net 856)
	)
	(segment
		(start 252.7195 158.181766)
		(end 252.991 158.453266)
		(width 0.153)
		(layer "B.Cu")
		(net 856)
	)
	(segment
		(start 230.2195 141.074766)
		(end 237.8195 148.674766)
		(width 0.153)
		(layer "B.Cu")
		(net 856)
	)
	(segment
		(start 248.625234 155.6805)
		(end 251.025234 155.6805)
		(width 0.153)
		(layer "B.Cu")
		(net 856)
	)
	(segment
		(start 229.807381 120.8)
		(end 230.2195 120.8)
		(width 0.153)
		(layer "B.Cu")
		(net 856)
	)
	(segment
		(start 206.613063 93.5305)
		(end 208.1945 93.5305)
		(width 0.153)
		(layer "B.Cu")
		(net 856)
	)
	(segment
		(start 237.8195 148.674766)
		(end 237.8195 151.824766)
		(width 0.153)
		(layer "B.Cu")
		(net 856)
	)
	(segment
		(start 222.025234 103.5805)
		(end 229.225234 103.5805)
		(width 0.153)
		(layer "B.Cu")
		(net 856)
	)
	(segment
		(start 251.025234 155.6805)
		(end 252.7195 157.374766)
		(width 0.153)
		(layer "B.Cu")
		(net 856)
	)
	(segment
		(start 230.2195 104.574766)
		(end 230.2195 117.0195)
		(width 0.153)
		(layer "B.Cu")
		(net 856)
	)
	(segment
		(start 206.064432 93.746517)
		(end 206.397046 93.746517)
		(width 0.153)
		(layer "B.Cu")
		(net 856)
	)
	(segment
		(start 209.124894 93.5305)
		(end 211.975234 93.5305)
		(width 0.153)
		(layer "B.Cu")
		(net 856)
	)
	(segment
		(start 230.2195 121.8195)
		(end 230.2195 124.799188)
		(width 0.153)
		(layer "B.Cu")
		(net 856)
	)
	(segment
		(start 208.321 93.657)
		(end 208.321 93.664186)
		(width 0.153)
		(layer "B.Cu")
		(net 856)
	)
	(segment
		(start 252.991 158.453266)
		(end 252.991 159.468)
		(width 0.153)
		(layer "B.Cu")
		(net 856)
	)
	(segment
		(start 239.675234 153.6805)
		(end 246.625234 153.6805)
		(width 0.153)
		(layer "B.Cu")
		(net 856)
	)
	(segment
		(start 237.8195 151.824766)
		(end 239.675234 153.6805)
		(width 0.153)
		(layer "B.Cu")
		(net 856)
	)
	(segment
		(start 208.574 93.664186)
		(end 208.574 93.657)
		(width 0.153)
		(layer "B.Cu")
		(net 856)
	)
	(segment
		(start 230.5805 119.639)
		(end 229.807381 119.639)
		(width 0.153)
		(layer "B.Cu")
		(net 856)
	)
	(segment
		(start 229.807381 119.2)
		(end 230.2195 119.2)
		(width 0.153)
		(layer "B.Cu")
		(net 856)
	)
	(arc
		(start 229.807381 119.639)
		(mid 229.396906 119.809025)
		(end 229.226881 120.2195)
		(width 0.153)
		(layer "B.Cu")
		(net 856)
	)
	(arc
		(start 208.321 93.664186)
		(mid 208.358051 93.753635)
		(end 208.4475 93.790686)
		(width 0.153)
		(layer "B.Cu")
		(net 856)
	)
	(arc
		(start 229.226881 120.2195)
		(mid 229.396906 120.629975)
		(end 229.807381 120.8)
		(width 0.153)
		(layer "B.Cu")
		(net 856)
	)
	(arc
		(start 231.092619 120.8)
		(mid 231.247829 120.86429)
		(end 231.312119 121.0195)
		(width 0.153)
		(layer "B.Cu")
		(net 856)
	)
	(arc
		(start 231.092619 119.2)
		(mid 231.247829 119.26429)
		(end 231.312119 119.4195)
		(width 0.153)
		(layer "B.Cu")
		(net 856)
	)
	(arc
		(start 231.092619 117.6)
		(mid 231.247829 117.66429)
		(end 231.312119 117.8195)
		(width 0.153)
		(layer "B.Cu")
		(net 856)
	)
	(arc
		(start 229.226881 118.6195)
		(mid 229.396906 119.029975)
		(end 229.807381 119.2)
		(width 0.153)
		(layer "B.Cu")
		(net 856)
	)
	(arc
		(start 231.312119 119.4195)
		(mid 231.247829 119.57471)
		(end 231.092619 119.639)
		(width 0.153)
		(layer "B.Cu")
		(net 856)
	)
	(arc
		(start 231.312119 117.8195)
		(mid 231.247829 117.97471)
		(end 231.092619 118.039)
		(width 0.153)
		(layer "B.Cu")
		(net 856)
	)
	(arc
		(start 230.2195 117.0195)
		(mid 230.389525 117.429975)
		(end 230.8 117.6)
		(width 0.153)
		(layer "B.Cu")
		(net 856)
	)
	(arc
		(start 231.312119 121.0195)
		(mid 231.247829 121.17471)
		(end 231.092619 121.239)
		(width 0.153)
		(layer "B.Cu")
		(net 856)
	)
	(arc
		(start 229.807381 118.039)
		(mid 229.396906 118.209025)
		(end 229.226881 118.6195)
		(width 0.153)
		(layer "B.Cu")
		(net 856)
	)
	(arc
		(start 208.1945 93.5305)
		(mid 208.283949 93.567551)
		(end 208.321 93.657)
		(width 0.153)
		(layer "B.Cu")
		(net 856)
	)
	(arc
		(start 230.8 121.239)
		(mid 230.389525 121.409025)
		(end 230.2195 121.8195)
		(width 0.153)
		(layer "B.Cu")
		(net 856)
	)
	(arc
		(start 208.4475 93.790686)
		(mid 208.536949 93.753635)
		(end 208.574 93.664186)
		(width 0.153)
		(layer "B.Cu")
		(net 856)
	)
	(arc
		(start 208.574 93.657)
		(mid 208.611051 93.567551)
		(end 208.7005 93.5305)
		(width 0.153)
		(layer "B.Cu")
		(net 856)
	)
	(segment
		(start 204.878149 94.099)
		(end 206.757741 94.099)
		(width 0.153)
		(layer "F.Cu")
		(net 857)
	)
	(segment
		(start 206.757741 94.099)
		(end 206.835741 94.021)
		(width 0.153)
		(layer "F.Cu")
		(net 857)
	)
	(via
		(at 206.835741 94.021)
		(size 0.45)
		(drill 0.2)
		(layers "F.Cu" "B.Cu")
		(net 857)
	)
	(segment
		(start 227.994811 111.589)
		(end 228.5195 111.589)
		(width 0.153)
		(layer "B.Cu")
		(net 857)
	)
	(segment
		(start 220.774766 104.9195)
		(end 225.974766 104.9195)
		(width 0.153)
		(layer "B.Cu")
		(net 857)
	)
	(segment
		(start 229.1 109.989)
		(end 229.305189 109.989)
		(width 0.153)
		(layer "B.Cu")
		(net 857)
	)
	(segment
		(start 228.8805 114.35)
		(end 227.994811 114.35)
		(width 0.153)
		(layer "B.Cu")
		(net 857)
	)
	(segment
		(start 228.8805 107.825234)
		(end 228.8805 109.7695)
		(width 0.153)
		(layer "B.Cu")
		(net 857)
	)
	(segment
		(start 210.024766 94.1695)
		(end 220.774766 104.9195)
		(width 0.153)
		(layer "B.Cu")
		(net 857)
	)
	(segment
		(start 229.305189 112.75)
		(end 228.8805 112.75)
		(width 0.153)
		(layer "B.Cu")
		(net 857)
	)
	(segment
		(start 229.305189 114.35)
		(end 228.8805 114.35)
		(width 0.153)
		(layer "B.Cu")
		(net 857)
	)
	(segment
		(start 231.0805 151.425234)
		(end 234.674766 155.0195)
		(width 0.153)
		(layer "B.Cu")
		(net 857)
	)
	(segment
		(start 207.113693 93.954101)
		(end 207.446307 93.954101)
		(width 0.153)
		(layer "B.Cu")
		(net 857)
	)
	(segment
		(start 227.994811 114.789)
		(end 228.3 114.789)
		(width 0.153)
		(layer "B.Cu")
		(net 857)
	)
	(segment
		(start 250.706266 158.198)
		(end 251.721 158.198)
		(width 0.153)
		(layer "B.Cu")
		(net 857)
	)
	(segment
		(start 207.661706 94.1695)
		(end 210.024766 94.1695)
		(width 0.153)
		(layer "B.Cu")
		(net 857)
	)
	(segment
		(start 234.674766 155.0195)
		(end 247.174766 155.0195)
		(width 0.153)
		(layer "B.Cu")
		(net 857)
	)
	(segment
		(start 231.0805 148.125234)
		(end 231.0805 151.425234)
		(width 0.153)
		(layer "B.Cu")
		(net 857)
	)
	(segment
		(start 228.8805 116.199999)
		(end 228.8805 145.925234)
		(width 0.153)
		(layer "B.Cu")
		(net 857)
	)
	(segment
		(start 229.305189 111.15)
		(end 229.1 111.15)
		(width 0.153)
		(layer "B.Cu")
		(net 857)
	)
	(segment
		(start 228.8805 145.925234)
		(end 231.0805 148.125234)
		(width 0.153)
		(layer "B.Cu")
		(net 857)
	)
	(segment
		(start 206.835741 94.021)
		(end 206.941268 94.126527)
		(width 0.153)
		(layer "B.Cu")
		(net 857)
	)
	(segment
		(start 250.5805 158.072234)
		(end 250.706266 158.198)
		(width 0.153)
		(layer "B.Cu")
		(net 857)
	)
	(segment
		(start 225.974766 104.9195)
		(end 228.8805 107.825234)
		(width 0.153)
		(layer "B.Cu")
		(net 857)
	)
	(segment
		(start 206.941268 94.126527)
		(end 207.113693 93.954101)
		(width 0.153)
		(layer "B.Cu")
		(net 857)
	)
	(segment
		(start 247.174766 155.0195)
		(end 248.374766 156.2195)
		(width 0.153)
		(layer "B.Cu")
		(net 857)
	)
	(segment
		(start 228.5195 111.589)
		(end 229.305189 111.589)
		(width 0.153)
		(layer "B.Cu")
		(net 857)
	)
	(segment
		(start 248.374766 156.2195)
		(end 249.774766 156.2195)
		(width 0.153)
		(layer "B.Cu")
		(net 857)
	)
	(segment
		(start 228.5195 113.189)
		(end 229.305189 113.189)
		(width 0.153)
		(layer "B.Cu")
		(net 857)
	)
	(segment
		(start 250.5805 157.025234)
		(end 250.5805 158.072234)
		(width 0.153)
		(layer "B.Cu")
		(net 857)
	)
	(segment
		(start 228.8805 115.3695)
		(end 228.8805 116.199999)
		(width 0.153)
		(layer "B.Cu")
		(net 857)
	)
	(segment
		(start 249.774766 156.2195)
		(end 250.5805 157.025234)
		(width 0.153)
		(layer "B.Cu")
		(net 857)
	)
	(segment
		(start 228.8805 112.75)
		(end 227.994811 112.75)
		(width 0.153)
		(layer "B.Cu")
		(net 857)
	)
	(segment
		(start 207.446307 93.954101)
		(end 207.661706 94.1695)
		(width 0.153)
		(layer "B.Cu")
		(net 857)
	)
	(segment
		(start 227.994811 113.189)
		(end 228.5195 113.189)
		(width 0.153)
		(layer "B.Cu")
		(net 857)
	)
	(segment
		(start 229.1 111.15)
		(end 227.994811 111.15)
		(width 0.153)
		(layer "B.Cu")
		(net 857)
	)
	(arc
		(start 227.775311 111.3695)
		(mid 227.839601 111.52471)
		(end 227.994811 111.589)
		(width 0.153)
		(layer "B.Cu")
		(net 857)
	)
	(arc
		(start 229.305189 113.189)
		(mid 229.715664 113.359025)
		(end 229.885689 113.7695)
		(width 0.153)
		(layer "B.Cu")
		(net 857)
	)
	(arc
		(start 227.994811 111.15)
		(mid 227.839601 111.21429)
		(end 227.775311 111.3695)
		(width 0.153)
		(layer "B.Cu")
		(net 857)
	)
	(arc
		(start 227.775311 114.5695)
		(mid 227.839601 114.72471)
		(end 227.994811 114.789)
		(width 0.153)
		(layer "B.Cu")
		(net 857)
	)
	(arc
		(start 229.305189 109.989)
		(mid 229.715664 110.159025)
		(end 229.885689 110.5695)
		(width 0.153)
		(layer "B.Cu")
		(net 857)
	)
	(arc
		(start 229.885689 112.1695)
		(mid 229.715664 112.579975)
		(end 229.305189 112.75)
		(width 0.153)
		(layer "B.Cu")
		(net 857)
	)
	(arc
		(start 227.994811 114.35)
		(mid 227.839601 114.41429)
		(end 227.775311 114.5695)
		(width 0.153)
		(layer "B.Cu")
		(net 857)
	)
	(arc
		(start 227.775311 112.9695)
		(mid 227.839601 113.12471)
		(end 227.994811 113.189)
		(width 0.153)
		(layer "B.Cu")
		(net 857)
	)
	(arc
		(start 229.305189 111.589)
		(mid 229.715664 111.759025)
		(end 229.885689 112.1695)
		(width 0.153)
		(layer "B.Cu")
		(net 857)
	)
	(arc
		(start 228.8805 109.7695)
		(mid 228.94479 109.92471)
		(end 229.1 109.989)
		(width 0.153)
		(layer "B.Cu")
		(net 857)
	)
	(arc
		(start 227.994811 112.75)
		(mid 227.839601 112.81429)
		(end 227.775311 112.9695)
		(width 0.153)
		(layer "B.Cu")
		(net 857)
	)
	(arc
		(start 229.885689 110.5695)
		(mid 229.715664 110.979975)
		(end 229.305189 111.15)
		(width 0.153)
		(layer "B.Cu")
		(net 857)
	)
	(arc
		(start 228.3 114.789)
		(mid 228.710475 114.959025)
		(end 228.8805 115.3695)
		(width 0.153)
		(layer "B.Cu")
		(net 857)
	)
	(arc
		(start 229.885689 113.7695)
		(mid 229.715664 114.179975)
		(end 229.305189 114.35)
		(width 0.153)
		(layer "B.Cu")
		(net 857)
	)
	(segment
		(start 206.755741 94.599)
		(end 206.835741 94.679)
		(width 0.153)
		(layer "F.Cu")
		(net 858)
	)
	(segment
		(start 204.878149 94.599)
		(end 206.755741 94.599)
		(width 0.153)
		(layer "F.Cu")
		(net 858)
	)
	(via
		(at 206.835741 94.679)
		(size 0.45)
		(drill 0.2)
		(layers "F.Cu" "B.Cu")
		(net 858)
	)
	(segment
		(start 227.994811 115.15)
		(end 228.3 115.15)
		(width 0.153)
		(layer "B.Cu")
		(net 858)
	)
	(segment
		(start 228.5195 116.199999)
		(end 228.5195 146.074766)
		(width 0.153)
		(layer "B.Cu")
		(net 858)
	)
	(segment
		(start 234.525234 155.3805)
		(end 247.025234 155.3805)
		(width 0.153)
		(layer "B.Cu")
		(net 858)
	)
	(segment
		(start 248.225234 156.5805)
		(end 249.625234 156.5805)
		(width 0.153)
		(layer "B.Cu")
		(net 858)
	)
	(segment
		(start 207.672908 94.5305)
		(end 208.1805 94.5305)
		(width 0.153)
		(layer "B.Cu")
		(net 858)
	)
	(segment
		(start 250.451 158.453266)
		(end 250.451 159.468)
		(width 0.153)
		(layer "B.Cu")
		(net 858)
	)
	(segment
		(start 230.7195 151.574766)
		(end 234.525234 155.3805)
		(width 0.153)
		(layer "B.Cu")
		(net 858)
	)
	(segment
		(start 207.446307 94.757101)
		(end 207.672908 94.5305)
		(width 0.153)
		(layer "B.Cu")
		(net 858)
	)
	(segment
		(start 228.5195 107.974766)
		(end 228.5195 109.7695)
		(width 0.153)
		(layer "B.Cu")
		(net 858)
	)
	(segment
		(start 230.7195 148.274766)
		(end 230.7195 151.574766)
		(width 0.153)
		(layer "B.Cu")
		(net 858)
	)
	(segment
		(start 220.625234 105.2805)
		(end 225.825234 105.2805)
		(width 0.153)
		(layer "B.Cu")
		(net 858)
	)
	(segment
		(start 229.1 110.35)
		(end 229.305189 110.35)
		(width 0.153)
		(layer "B.Cu")
		(net 858)
	)
	(segment
		(start 228.5195 113.55)
		(end 229.305189 113.55)
		(width 0.153)
		(layer "B.Cu")
		(net 858)
	)
	(segment
		(start 227.994811 111.95)
		(end 228.5195 111.95)
		(width 0.153)
		(layer "B.Cu")
		(net 858)
	)
	(segment
		(start 228.8805 113.989)
		(end 227.994811 113.989)
		(width 0.153)
		(layer "B.Cu")
		(net 858)
	)
	(segment
		(start 227.994811 113.55)
		(end 228.5195 113.55)
		(width 0.153)
		(layer "B.Cu")
		(net 858)
	)
	(segment
		(start 208.307 94.657)
		(end 208.307 94.659801)
		(width 0.153)
		(layer "B.Cu")
		(net 858)
	)
	(segment
		(start 228.5195 146.074766)
		(end 230.7195 148.274766)
		(width 0.153)
		(layer "B.Cu")
		(net 858)
	)
	(segment
		(start 209.875234 94.5305)
		(end 220.625234 105.2805)
		(width 0.153)
		(layer "B.Cu")
		(net 858)
	)
	(segment
		(start 250.2195 157.174766)
		(end 250.2195 158.221766)
		(width 0.153)
		(layer "B.Cu")
		(net 858)
	)
	(segment
		(start 229.1 110.789)
		(end 227.994811 110.789)
		(width 0.153)
		(layer "B.Cu")
		(net 858)
	)
	(segment
		(start 228.8805 112.389)
		(end 227.994811 112.389)
		(width 0.153)
		(layer "B.Cu")
		(net 858)
	)
	(segment
		(start 208.6865 94.5305)
		(end 209.56296 94.5305)
		(width 0.153)
		(layer "B.Cu")
		(net 858)
	)
	(segment
		(start 206.935667 94.579074)
		(end 207.113693 94.757101)
		(width 0.153)
		(layer "B.Cu")
		(net 858)
	)
	(segment
		(start 229.305189 113.989)
		(end 228.8805 113.989)
		(width 0.153)
		(layer "B.Cu")
		(net 858)
	)
	(segment
		(start 209.56296 94.5305)
		(end 209.875234 94.5305)
		(width 0.153)
		(layer "B.Cu")
		(net 858)
	)
	(segment
		(start 229.305189 110.789)
		(end 229.1 110.789)
		(width 0.153)
		(layer "B.Cu")
		(net 858)
	)
	(segment
		(start 247.025234 155.3805)
		(end 248.225234 156.5805)
		(width 0.153)
		(layer "B.Cu")
		(net 858)
	)
	(segment
		(start 249.625234 156.5805)
		(end 250.2195 157.174766)
		(width 0.153)
		(layer "B.Cu")
		(net 858)
	)
	(segment
		(start 206.835741 94.679)
		(end 206.935667 94.579074)
		(width 0.153)
		(layer "B.Cu")
		(net 858)
	)
	(segment
		(start 208.56 94.659801)
		(end 208.56 94.657)
		(width 0.153)
		(layer "B.Cu")
		(net 858)
	)
	(segment
		(start 228.5195 111.95)
		(end 229.305189 111.95)
		(width 0.153)
		(layer "B.Cu")
		(net 858)
	)
	(segment
		(start 250.2195 158.221766)
		(end 250.451 158.453266)
		(width 0.153)
		(layer "B.Cu")
		(net 858)
	)
	(segment
		(start 207.113693 94.757101)
		(end 207.446307 94.757101)
		(width 0.153)
		(layer "B.Cu")
		(net 858)
	)
	(segment
		(start 225.825234 105.2805)
		(end 228.5195 107.974766)
		(width 0.153)
		(layer "B.Cu")
		(net 858)
	)
	(segment
		(start 228.5195 115.3695)
		(end 228.5195 116.199999)
		(width 0.153)
		(layer "B.Cu")
		(net 858)
	)
	(segment
		(start 229.305189 112.389)
		(end 228.8805 112.389)
		(width 0.153)
		(layer "B.Cu")
		(net 858)
	)
	(arc
		(start 208.1805 94.5305)
		(mid 208.269949 94.567551)
		(end 208.307 94.657)
		(width 0.153)
		(layer "B.Cu")
		(net 858)
	)
	(arc
		(start 227.994811 113.989)
		(mid 227.584336 114.159025)
		(end 227.414311 114.5695)
		(width 0.153)
		(layer "B.Cu")
		(net 858)
	)
	(arc
		(start 229.305189 110.35)
		(mid 229.460399 110.41429)
		(end 229.524689 110.5695)
		(width 0.153)
		(layer "B.Cu")
		(net 858)
	)
	(arc
		(start 227.414311 114.5695)
		(mid 227.584336 114.979975)
		(end 227.994811 115.15)
		(width 0.153)
		(layer "B.Cu")
		(net 858)
	)
	(arc
		(start 208.56 94.657)
		(mid 208.597051 94.567551)
		(end 208.6865 94.5305)
		(width 0.153)
		(layer "B.Cu")
		(net 858)
	)
	(arc
		(start 227.994811 110.789)
		(mid 227.584336 110.959025)
		(end 227.414311 111.3695)
		(width 0.153)
		(layer "B.Cu")
		(net 858)
	)
	(arc
		(start 228.5195 109.7695)
		(mid 228.689525 110.179975)
		(end 229.1 110.35)
		(width 0.153)
		(layer "B.Cu")
		(net 858)
	)
	(arc
		(start 208.307 94.659801)
		(mid 208.344051 94.74925)
		(end 208.4335 94.786301)
		(width 0.153)
		(layer "B.Cu")
		(net 858)
	)
	(arc
		(start 227.414311 112.9695)
		(mid 227.584336 113.379975)
		(end 227.994811 113.55)
		(width 0.153)
		(layer "B.Cu")
		(net 858)
	)
	(arc
		(start 229.524689 113.7695)
		(mid 229.460399 113.92471)
		(end 229.305189 113.989)
		(width 0.153)
		(layer "B.Cu")
		(net 858)
	)
	(arc
		(start 208.4335 94.786301)
		(mid 208.522949 94.74925)
		(end 208.56 94.659801)
		(width 0.153)
		(layer "B.Cu")
		(net 858)
	)
	(arc
		(start 229.524689 112.1695)
		(mid 229.460399 112.32471)
		(end 229.305189 112.389)
		(width 0.153)
		(layer "B.Cu")
		(net 858)
	)
	(arc
		(start 228.3 115.15)
		(mid 228.45521 115.21429)
		(end 228.5195 115.3695)
		(width 0.153)
		(layer "B.Cu")
		(net 858)
	)
	(arc
		(start 227.414311 111.3695)
		(mid 227.584336 111.779975)
		(end 227.994811 111.95)
		(width 0.153)
		(layer "B.Cu")
		(net 858)
	)
	(arc
		(start 229.305189 113.55)
		(mid 229.460399 113.61429)
		(end 229.524689 113.7695)
		(width 0.153)
		(layer "B.Cu")
		(net 858)
	)
	(arc
		(start 227.994811 112.389)
		(mid 227.584336 112.559025)
		(end 227.414311 112.9695)
		(width 0.153)
		(layer "B.Cu")
		(net 858)
	)
	(arc
		(start 229.305189 111.95)
		(mid 229.460399 112.01429)
		(end 229.524689 112.1695)
		(width 0.153)
		(layer "B.Cu")
		(net 858)
	)
	(arc
		(start 229.524689 110.5695)
		(mid 229.460399 110.72471)
		(end 229.305189 110.789)
		(width 0.153)
		(layer "B.Cu")
		(net 858)
	)
	(segment
		(start 205.686123 95.599)
		(end 205.764123 95.521)
		(width 0.153)
		(layer "F.Cu")
		(net 859)
	)
	(segment
		(start 204.878149 95.599)
		(end 205.686123 95.599)
		(width 0.153)
		(layer "F.Cu")
		(net 859)
	)
	(via
		(at 205.764123 95.521)
		(size 0.45)
		(drill 0.2)
		(layers "F.Cu" "B.Cu")
		(net 859)
	)
	(segment
		(start 226.9805 108.725234)
		(end 226.9805 144.825234)
		(width 0.153)
		(layer "B.Cu")
		(net 859)
	)
	(segment
		(start 215.172338 102.004789)
		(end 215.172338 102.00479)
		(width 0.153)
		(layer "B.Cu")
		(net 859)
	)
	(segment
		(start 218.367044 105.199495)
		(end 218.367044 105.199496)
		(width 0.153)
		(layer "B.Cu")
		(net 859)
	)
	(segment
		(start 206.594666 95.6695)
		(end 209.624766 95.6695)
		(width 0.153)
		(layer "B.Cu")
		(net 859)
	)
	(segment
		(start 206.03927 95.446718)
		(end 206.371884 95.446718)
		(width 0.153)
		(layer "B.Cu")
		(net 859)
	)
	(segment
		(start 211.948629 99.393457)
		(end 212.254816 99.087269)
		(width 0.153)
		(layer "B.Cu")
		(net 859)
	)
	(segment
		(start 220.496847 106.541583)
		(end 221.174766 107.2195)
		(width 0.153)
		(layer "B.Cu")
		(net 859)
	)
	(segment
		(start 211.977632 98.810083)
		(end 211.977632 98.810084)
		(width 0.153)
		(layer "B.Cu")
		(net 859)
	)
	(segment
		(start 205.864556 95.621433)
		(end 206.03927 95.446718)
		(width 0.153)
		(layer "B.Cu")
		(net 859)
	)
	(segment
		(start 205.764123 95.521)
		(end 205.864556 95.621433)
		(width 0.153)
		(layer "B.Cu")
		(net 859)
	)
	(segment
		(start 213.042534 99.874986)
		(end 212.736346 100.181173)
		(width 0.153)
		(layer "B.Cu")
		(net 859)
	)
	(segment
		(start 247.9805 157.225234)
		(end 247.9805 158.012234)
		(width 0.153)
		(layer "B.Cu")
		(net 859)
	)
	(segment
		(start 214.078433 101.523261)
		(end 214.38462 101.217073)
		(width 0.153)
		(layer "B.Cu")
		(net 859)
	)
	(segment
		(start 246.987724 156.232458)
		(end 247.9805 157.225234)
		(width 0.153)
		(layer "B.Cu")
		(net 859)
	)
	(segment
		(start 219.431946 106.264398)
		(end 219.125758 106.570585)
		(width 0.153)
		(layer "B.Cu")
		(net 859)
	)
	(segment
		(start 218.338041 105.782868)
		(end 218.338041 105.782869)
		(width 0.153)
		(layer "B.Cu")
		(net 859)
	)
	(segment
		(start 215.172338 102.00479)
		(end 214.86615 102.310977)
		(width 0.153)
		(layer "B.Cu")
		(net 859)
	)
	(segment
		(start 214.107436 100.939888)
		(end 213.801248 101.246075)
		(width 0.153)
		(layer "B.Cu")
		(net 859)
	)
	(segment
		(start 220.496847 106.541582)
		(end 220.496847 106.541583)
		(width 0.153)
		(layer "B.Cu")
		(net 859)
	)
	(segment
		(start 247.9805 158.012234)
		(end 248.166266 158.198)
		(width 0.153)
		(layer "B.Cu")
		(net 859)
	)
	(segment
		(start 217.273139 104.717966)
		(end 217.273139 104.717967)
		(width 0.153)
		(layer "B.Cu")
		(net 859)
	)
	(segment
		(start 214.107436 100.939887)
		(end 214.107436 100.939888)
		(width 0.153)
		(layer "B.Cu")
		(net 859)
	)
	(segment
		(start 206.371884 95.446718)
		(end 206.594666 95.6695)
		(width 0.153)
		(layer "B.Cu")
		(net 859)
	)
	(segment
		(start 219.431946 106.264397)
		(end 219.431946 106.264398)
		(width 0.153)
		(layer "B.Cu")
		(net 859)
	)
	(segment
		(start 213.013531 100.458358)
		(end 213.013531 100.458359)
		(width 0.153)
		(layer "B.Cu")
		(net 859)
	)
	(segment
		(start 211.977632 98.810084)
		(end 211.671444 99.116271)
		(width 0.153)
		(layer "B.Cu")
		(net 859)
	)
	(segment
		(start 213.042534 99.874985)
		(end 213.042534 99.874986)
		(width 0.153)
		(layer "B.Cu")
		(net 859)
	)
	(segment
		(start 219.402943 106.847771)
		(end 219.70913 106.541583)
		(width 0.153)
		(layer "B.Cu")
		(net 859)
	)
	(segment
		(start 216.23724 103.069691)
		(end 216.23724 103.069692)
		(width 0.153)
		(layer "B.Cu")
		(net 859)
	)
	(segment
		(start 221.174766 107.2195)
		(end 225.474766 107.2195)
		(width 0.153)
		(layer "B.Cu")
		(net 859)
	)
	(segment
		(start 211.948629 99.393456)
		(end 211.948629 99.393457)
		(width 0.153)
		(layer "B.Cu")
		(net 859)
	)
	(segment
		(start 226.9805 144.825234)
		(end 227.6805 145.525234)
		(width 0.153)
		(layer "B.Cu")
		(net 859)
	)
	(segment
		(start 218.367044 105.199496)
		(end 218.060856 105.505683)
		(width 0.153)
		(layer "B.Cu")
		(net 859)
	)
	(segment
		(start 227.6805 145.525234)
		(end 227.6805 150.425234)
		(width 0.153)
		(layer "B.Cu")
		(net 859)
	)
	(segment
		(start 217.273139 104.717967)
		(end 217.579326 104.411779)
		(width 0.153)
		(layer "B.Cu")
		(net 859)
	)
	(segment
		(start 215.143335 102.588162)
		(end 215.143335 102.588163)
		(width 0.153)
		(layer "B.Cu")
		(net 859)
	)
	(segment
		(start 217.302142 104.134594)
		(end 216.995954 104.440781)
		(width 0.153)
		(layer "B.Cu")
		(net 859)
	)
	(segment
		(start 225.474766 107.2195)
		(end 226.9805 108.725234)
		(width 0.153)
		(layer "B.Cu")
		(net 859)
	)
	(segment
		(start 227.6805 150.425234)
		(end 233.487724 156.232458)
		(width 0.153)
		(layer "B.Cu")
		(net 859)
	)
	(segment
		(start 209.624766 95.6695)
		(end 211.977632 98.022367)
		(width 0.153)
		(layer "B.Cu")
		(net 859)
	)
	(segment
		(start 213.013531 100.458359)
		(end 213.319718 100.152171)
		(width 0.153)
		(layer "B.Cu")
		(net 859)
	)
	(segment
		(start 216.208237 103.653065)
		(end 216.514424 103.346877)
		(width 0.153)
		(layer "B.Cu")
		(net 859)
	)
	(segment
		(start 219.402943 106.84777)
		(end 219.402943 106.847771)
		(width 0.153)
		(layer "B.Cu")
		(net 859)
	)
	(segment
		(start 216.208237 103.653064)
		(end 216.208237 103.653065)
		(width 0.153)
		(layer "B.Cu")
		(net 859)
	)
	(segment
		(start 217.302142 104.134593)
		(end 217.302142 104.134594)
		(width 0.153)
		(layer "B.Cu")
		(net 859)
	)
	(segment
		(start 215.143335 102.588163)
		(end 215.449522 102.281975)
		(width 0.153)
		(layer "B.Cu")
		(net 859)
	)
	(segment
		(start 233.487724 156.232458)
		(end 246.987724 156.232458)
		(width 0.153)
		(layer "B.Cu")
		(net 859)
	)
	(segment
		(start 218.338041 105.782869)
		(end 218.644228 105.476681)
		(width 0.153)
		(layer "B.Cu")
		(net 859)
	)
	(segment
		(start 248.166266 158.198)
		(end 249.181 158.198)
		(width 0.153)
		(layer "B.Cu")
		(net 859)
	)
	(segment
		(start 216.23724 103.069692)
		(end 215.931052 103.375879)
		(width 0.153)
		(layer "B.Cu")
		(net 859)
	)
	(segment
		(start 214.078433 101.52326)
		(end 214.078433 101.523261)
		(width 0.153)
		(layer "B.Cu")
		(net 859)
	)
	(arc
		(start 215.172338 101.217073)
		(mid 215.335479 101.610931)
		(end 215.172338 102.004789)
		(width 0.153)
		(layer "B.Cu")
		(net 859)
	)
	(arc
		(start 213.801248 101.246075)
		(mid 213.743841 101.384668)
		(end 213.801248 101.523261)
		(width 0.153)
		(layer "B.Cu")
		(net 859)
	)
	(arc
		(start 215.931052 103.653065)
		(mid 216.069645 103.710471)
		(end 216.208237 103.653064)
		(width 0.153)
		(layer "B.Cu")
		(net 859)
	)
	(arc
		(start 216.514424 103.346877)
		(mid 216.908282 103.183735)
		(end 217.302141 103.346876)
		(width 0.153)
		(layer "B.Cu")
		(net 859)
	)
	(arc
		(start 214.86615 102.588163)
		(mid 215.004743 102.645569)
		(end 215.143335 102.588162)
		(width 0.153)
		(layer "B.Cu")
		(net 859)
	)
	(arc
		(start 218.060856 105.782869)
		(mid 218.199449 105.840275)
		(end 218.338041 105.782868)
		(width 0.153)
		(layer "B.Cu")
		(net 859)
	)
	(arc
		(start 211.977632 98.022367)
		(mid 212.140773 98.416225)
		(end 211.977632 98.810083)
		(width 0.153)
		(layer "B.Cu")
		(net 859)
	)
	(arc
		(start 218.367044 104.411779)
		(mid 218.530185 104.805637)
		(end 218.367044 105.199495)
		(width 0.153)
		(layer "B.Cu")
		(net 859)
	)
	(arc
		(start 216.23724 102.281975)
		(mid 216.400381 102.675833)
		(end 216.23724 103.069691)
		(width 0.153)
		(layer "B.Cu")
		(net 859)
	)
	(arc
		(start 215.931052 103.375879)
		(mid 215.873645 103.514472)
		(end 215.931052 103.653065)
		(width 0.153)
		(layer "B.Cu")
		(net 859)
	)
	(arc
		(start 219.431946 105.476681)
		(mid 219.595087 105.870539)
		(end 219.431946 106.264397)
		(width 0.153)
		(layer "B.Cu")
		(net 859)
	)
	(arc
		(start 212.736346 100.181173)
		(mid 212.678939 100.319766)
		(end 212.736346 100.458359)
		(width 0.153)
		(layer "B.Cu")
		(net 859)
	)
	(arc
		(start 216.995954 104.717967)
		(mid 217.134547 104.775373)
		(end 217.273139 104.717966)
		(width 0.153)
		(layer "B.Cu")
		(net 859)
	)
	(arc
		(start 213.042534 99.087269)
		(mid 213.205675 99.481127)
		(end 213.042534 99.874985)
		(width 0.153)
		(layer "B.Cu")
		(net 859)
	)
	(arc
		(start 214.86615 102.310977)
		(mid 214.808743 102.44957)
		(end 214.86615 102.588163)
		(width 0.153)
		(layer "B.Cu")
		(net 859)
	)
	(arc
		(start 217.579326 104.411779)
		(mid 217.973184 104.248637)
		(end 218.367043 104.411778)
		(width 0.153)
		(layer "B.Cu")
		(net 859)
	)
	(arc
		(start 212.736346 100.458359)
		(mid 212.874939 100.515765)
		(end 213.013531 100.458358)
		(width 0.153)
		(layer "B.Cu")
		(net 859)
	)
	(arc
		(start 219.70913 106.541583)
		(mid 220.102988 106.378441)
		(end 220.496847 106.541582)
		(width 0.153)
		(layer "B.Cu")
		(net 859)
	)
	(arc
		(start 218.644228 105.476681)
		(mid 219.038086 105.313539)
		(end 219.431945 105.47668)
		(width 0.153)
		(layer "B.Cu")
		(net 859)
	)
	(arc
		(start 213.801248 101.523261)
		(mid 213.939841 101.580667)
		(end 214.078433 101.52326)
		(width 0.153)
		(layer "B.Cu")
		(net 859)
	)
	(arc
		(start 218.060856 105.505683)
		(mid 218.003449 105.644276)
		(end 218.060856 105.782869)
		(width 0.153)
		(layer "B.Cu")
		(net 859)
	)
	(arc
		(start 216.995954 104.440781)
		(mid 216.938547 104.579374)
		(end 216.995954 104.717967)
		(width 0.153)
		(layer "B.Cu")
		(net 859)
	)
	(arc
		(start 214.107436 100.152171)
		(mid 214.270577 100.546029)
		(end 214.107436 100.939887)
		(width 0.153)
		(layer "B.Cu")
		(net 859)
	)
	(arc
		(start 213.319718 100.152171)
		(mid 213.713576 99.989029)
		(end 214.107435 100.15217)
		(width 0.153)
		(layer "B.Cu")
		(net 859)
	)
	(arc
		(start 212.254816 99.087269)
		(mid 212.648674 98.924127)
		(end 213.042533 99.087268)
		(width 0.153)
		(layer "B.Cu")
		(net 859)
	)
	(arc
		(start 215.449522 102.281975)
		(mid 215.84338 102.118833)
		(end 216.237239 102.281974)
		(width 0.153)
		(layer "B.Cu")
		(net 859)
	)
	(arc
		(start 211.671444 99.393457)
		(mid 211.810037 99.450863)
		(end 211.948629 99.393456)
		(width 0.153)
		(layer "B.Cu")
		(net 859)
	)
	(arc
		(start 217.302142 103.346877)
		(mid 217.465283 103.740735)
		(end 217.302142 104.134593)
		(width 0.153)
		(layer "B.Cu")
		(net 859)
	)
	(arc
		(start 211.671444 99.116271)
		(mid 211.614037 99.254864)
		(end 211.671444 99.393457)
		(width 0.153)
		(layer "B.Cu")
		(net 859)
	)
	(arc
		(start 219.125758 106.847771)
		(mid 219.264351 106.905177)
		(end 219.402943 106.84777)
		(width 0.153)
		(layer "B.Cu")
		(net 859)
	)
	(arc
		(start 214.38462 101.217073)
		(mid 214.778478 101.053931)
		(end 215.172337 101.217072)
		(width 0.153)
		(layer "B.Cu")
		(net 859)
	)
	(arc
		(start 219.125758 106.570585)
		(mid 219.068351 106.709178)
		(end 219.125758 106.847771)
		(width 0.153)
		(layer "B.Cu")
		(net 859)
	)
	(segment
		(start 204.878149 96.099)
		(end 205.684123 96.099)
		(width 0.153)
		(layer "F.Cu")
		(net 860)
	)
	(segment
		(start 205.684123 96.099)
		(end 205.764123 96.179)
		(width 0.153)
		(layer "F.Cu")
		(net 860)
	)
	(via
		(at 205.764123 96.179)
		(size 0.45)
		(drill 0.2)
		(layers "F.Cu" "B.Cu")
		(net 860)
	)
	(segment
		(start 205.764123 96.179)
		(end 205.866338 96.076785)
		(width 0.153)
		(layer "B.Cu")
		(net 860)
	)
	(segment
		(start 213.268797 100.713624)
		(end 213.574984 100.407436)
		(width 0.153)
		(layer "B.Cu")
		(net 860)
	)
	(segment
		(start 206.03927 96.249718)
		(end 206.371884 96.249718)
		(width 0.153)
		(layer "B.Cu")
		(net 860)
	)
	(segment
		(start 214.917074 101.472339)
		(end 214.917073 101.472338)
		(width 0.153)
		(layer "B.Cu")
		(net 860)
	)
	(segment
		(start 216.463504 103.908329)
		(end 216.463503 103.90833)
		(width 0.153)
		(layer "B.Cu")
		(net 860)
	)
	(segment
		(start 218.11178 104.667045)
		(end 218.111779 104.667044)
		(width 0.153)
		(layer "B.Cu")
		(net 860)
	)
	(segment
		(start 219.176681 106.009132)
		(end 218.870493 106.315319)
		(width 0.153)
		(layer "B.Cu")
		(net 860)
	)
	(segment
		(start 213.852172 100.407437)
		(end 213.852171 100.407436)
		(width 0.153)
		(layer "B.Cu")
		(net 860)
	)
	(segment
		(start 227.3195 150.574766)
		(end 233.338192 156.593458)
		(width 0.153)
		(layer "B.Cu")
		(net 860)
	)
	(segment
		(start 217.80559 106.038134)
		(end 217.805591 106.038134)
		(width 0.153)
		(layer "B.Cu")
		(net 860)
	)
	(segment
		(start 212.48108 100.713624)
		(end 212.481081 100.713624)
		(width 0.153)
		(layer "B.Cu")
		(net 860)
	)
	(segment
		(start 213.545982 101.778526)
		(end 213.545983 101.778526)
		(width 0.153)
		(layer "B.Cu")
		(net 860)
	)
	(segment
		(start 216.463503 103.90833)
		(end 216.76969 103.602142)
		(width 0.153)
		(layer "B.Cu")
		(net 860)
	)
	(segment
		(start 212.78727 99.342535)
		(end 212.787269 99.342534)
		(width 0.153)
		(layer "B.Cu")
		(net 860)
	)
	(segment
		(start 219.17668 105.731946)
		(end 219.176682 105.731947)
		(width 0.153)
		(layer "B.Cu")
		(net 860)
	)
	(segment
		(start 214.333699 101.778526)
		(end 214.639886 101.472338)
		(width 0.153)
		(layer "B.Cu")
		(net 860)
	)
	(segment
		(start 214.917073 101.749524)
		(end 214.610885 102.055711)
		(width 0.153)
		(layer "B.Cu")
		(net 860)
	)
	(segment
		(start 217.528405 104.973232)
		(end 217.834592 104.667044)
		(width 0.153)
		(layer "B.Cu")
		(net 860)
	)
	(segment
		(start 218.111778 104.667044)
		(end 218.11178 104.667045)
		(width 0.153)
		(layer "B.Cu")
		(net 860)
	)
	(segment
		(start 216.740688 104.973232)
		(end 216.740689 104.973232)
		(width 0.153)
		(layer "B.Cu")
		(net 860)
	)
	(segment
		(start 212.203895 99.648722)
		(end 212.510082 99.342534)
		(width 0.153)
		(layer "B.Cu")
		(net 860)
	)
	(segment
		(start 215.981975 102.814426)
		(end 215.675787 103.120613)
		(width 0.153)
		(layer "B.Cu")
		(net 860)
	)
	(segment
		(start 247.6195 157.374766)
		(end 247.6195 158.161766)
		(width 0.153)
		(layer "B.Cu")
		(net 860)
	)
	(segment
		(start 217.528406 104.973231)
		(end 217.528405 104.973232)
		(width 0.153)
		(layer "B.Cu")
		(net 860)
	)
	(segment
		(start 213.268798 100.713623)
		(end 213.268797 100.713624)
		(width 0.153)
		(layer "B.Cu")
		(net 860)
	)
	(segment
		(start 218.111779 104.94423)
		(end 217.805591 105.250417)
		(width 0.153)
		(layer "B.Cu")
		(net 860)
	)
	(segment
		(start 213.852171 100.684622)
		(end 213.545983 100.990809)
		(width 0.153)
		(layer "B.Cu")
		(net 860)
	)
	(segment
		(start 247.911 158.453266)
		(end 247.911 159.468)
		(width 0.153)
		(layer "B.Cu")
		(net 860)
	)
	(segment
		(start 215.981974 102.53724)
		(end 215.981976 102.537241)
		(width 0.153)
		(layer "B.Cu")
		(net 860)
	)
	(segment
		(start 206.371884 96.249718)
		(end 206.591102 96.0305)
		(width 0.153)
		(layer "B.Cu")
		(net 860)
	)
	(segment
		(start 247.6195 158.161766)
		(end 247.911 158.453266)
		(width 0.153)
		(layer "B.Cu")
		(net 860)
	)
	(segment
		(start 215.981976 102.537241)
		(end 215.981975 102.53724)
		(width 0.153)
		(layer "B.Cu")
		(net 860)
	)
	(segment
		(start 220.241582 106.796848)
		(end 220.241584 106.796849)
		(width 0.153)
		(layer "B.Cu")
		(net 860)
	)
	(segment
		(start 208.257 96.157)
		(end 208.257 96.162859)
		(width 0.153)
		(layer "B.Cu")
		(net 860)
	)
	(segment
		(start 214.917072 101.472338)
		(end 214.917074 101.472339)
		(width 0.153)
		(layer "B.Cu")
		(net 860)
	)
	(segment
		(start 217.046878 103.602143)
		(end 217.046877 103.602142)
		(width 0.153)
		(layer "B.Cu")
		(net 860)
	)
	(segment
		(start 213.85217 100.407436)
		(end 213.852172 100.407437)
		(width 0.153)
		(layer "B.Cu")
		(net 860)
	)
	(segment
		(start 212.787269 99.61972)
		(end 212.481081 99.925907)
		(width 0.153)
		(layer "B.Cu")
		(net 860)
	)
	(segment
		(start 218.593307 106.038134)
		(end 218.899494 105.731946)
		(width 0.153)
		(layer "B.Cu")
		(net 860)
	)
	(segment
		(start 208.6365 96.0305)
		(end 209.475234 96.0305)
		(width 0.153)
		(layer "B.Cu")
		(net 860)
	)
	(segment
		(start 205.866338 96.076785)
		(end 206.03927 96.249718)
		(width 0.153)
		(layer "B.Cu")
		(net 860)
	)
	(segment
		(start 221.025234 107.5805)
		(end 225.325234 107.5805)
		(width 0.153)
		(layer "B.Cu")
		(net 860)
	)
	(segment
		(start 215.398601 102.843428)
		(end 215.704788 102.53724)
		(width 0.153)
		(layer "B.Cu")
		(net 860)
	)
	(segment
		(start 215.675786 103.90833)
		(end 215.675787 103.90833)
		(width 0.153)
		(layer "B.Cu")
		(net 860)
	)
	(segment
		(start 227.3195 145.674766)
		(end 227.3195 150.574766)
		(width 0.153)
		(layer "B.Cu")
		(net 860)
	)
	(segment
		(start 233.338192 156.593458)
		(end 246.838192 156.593458)
		(width 0.153)
		(layer "B.Cu")
		(net 860)
	)
	(segment
		(start 211.722367 98.554818)
		(end 211.416179 98.861005)
		(width 0.153)
		(layer "B.Cu")
		(net 860)
	)
	(segment
		(start 212.203896 99.648721)
		(end 212.203895 99.648722)
		(width 0.153)
		(layer "B.Cu")
		(net 860)
	)
	(segment
		(start 218.593308 106.038133)
		(end 218.593307 106.038134)
		(width 0.153)
		(layer "B.Cu")
		(net 860)
	)
	(segment
		(start 226.6195 144.974766)
		(end 227.3195 145.674766)
		(width 0.153)
		(layer "B.Cu")
		(net 860)
	)
	(segment
		(start 215.398602 102.843427)
		(end 215.398601 102.843428)
		(width 0.153)
		(layer "B.Cu")
		(net 860)
	)
	(segment
		(start 206.591102 96.0305)
		(end 208.1305 96.0305)
		(width 0.153)
		(layer "B.Cu")
		(net 860)
	)
	(segment
		(start 219.658209 107.103036)
		(end 219.964396 106.796848)
		(width 0.153)
		(layer "B.Cu")
		(net 860)
	)
	(segment
		(start 212.787268 99.342534)
		(end 212.78727 99.342535)
		(width 0.153)
		(layer "B.Cu")
		(net 860)
	)
	(segment
		(start 214.610884 102.843428)
		(end 214.610885 102.843428)
		(width 0.153)
		(layer "B.Cu")
		(net 860)
	)
	(segment
		(start 225.325234 107.5805)
		(end 226.6195 108.874766)
		(width 0.153)
		(layer "B.Cu")
		(net 860)
	)
	(segment
		(start 219.176682 105.731947)
		(end 219.176681 105.731946)
		(width 0.153)
		(layer "B.Cu")
		(net 860)
	)
	(segment
		(start 218.870492 107.103036)
		(end 218.870493 107.103036)
		(width 0.153)
		(layer "B.Cu")
		(net 860)
	)
	(segment
		(start 211.416178 99.648722)
		(end 211.416179 99.648722)
		(width 0.153)
		(layer "B.Cu")
		(net 860)
	)
	(segment
		(start 217.046877 103.879328)
		(end 216.740689 104.185515)
		(width 0.153)
		(layer "B.Cu")
		(net 860)
	)
	(segment
		(start 246.838192 156.593458)
		(end 247.6195 157.374766)
		(width 0.153)
		(layer "B.Cu")
		(net 860)
	)
	(segment
		(start 219.65821 107.103035)
		(end 219.658209 107.103036)
		(width 0.153)
		(layer "B.Cu")
		(net 860)
	)
	(segment
		(start 220.241584 106.796849)
		(end 221.025234 107.5805)
		(width 0.153)
		(layer "B.Cu")
		(net 860)
	)
	(segment
		(start 226.6195 108.874766)
		(end 226.6195 144.974766)
		(width 0.153)
		(layer "B.Cu")
		(net 860)
	)
	(segment
		(start 214.3337 101.778525)
		(end 214.333699 101.778526)
		(width 0.153)
		(layer "B.Cu")
		(net 860)
	)
	(segment
		(start 209.475234 96.0305)
		(end 211.722367 98.277632)
		(width 0.153)
		(layer "B.Cu")
		(net 860)
	)
	(segment
		(start 217.046876 103.602142)
		(end 217.046878 103.602143)
		(width 0.153)
		(layer "B.Cu")
		(net 860)
	)
	(segment
		(start 208.51 96.162859)
		(end 208.51 96.157)
		(width 0.153)
		(layer "B.Cu")
		(net 860)
	)
	(arc
		(start 217.046877 103.602142)
		(mid 217.104284 103.740735)
		(end 217.046877 103.879328)
		(width 0.153)
		(layer "B.Cu")
		(net 860)
	)
	(arc
		(start 216.740689 104.973232)
		(mid 217.134548 105.136373)
		(end 217.528406 104.973231)
		(width 0.153)
		(layer "B.Cu")
		(net 860)
	)
	(arc
		(start 214.917073 101.472338)
		(mid 214.97448 101.610931)
		(end 214.917073 101.749524)
		(width 0.153)
		(layer "B.Cu")
		(net 860)
	)
	(arc
		(start 212.787269 99.342534)
		(mid 212.844676 99.481127)
		(end 212.787269 99.61972)
		(width 0.153)
		(layer "B.Cu")
		(net 860)
	)
	(arc
		(start 212.510082 99.342534)
		(mid 212.648675 99.285127)
		(end 212.787268 99.342534)
		(width 0.153)
		(layer "B.Cu")
		(net 860)
	)
	(arc
		(start 215.704788 102.53724)
		(mid 215.843381 102.479833)
		(end 215.981974 102.53724)
		(width 0.153)
		(layer "B.Cu")
		(net 860)
	)
	(arc
		(start 208.51 96.157)
		(mid 208.547051 96.067551)
		(end 208.6365 96.0305)
		(width 0.153)
		(layer "B.Cu")
		(net 860)
	)
	(arc
		(start 217.805591 105.250417)
		(mid 217.642449 105.644275)
		(end 217.80559 106.038134)
		(width 0.153)
		(layer "B.Cu")
		(net 860)
	)
	(arc
		(start 218.870493 106.315319)
		(mid 218.707351 106.709177)
		(end 218.870492 107.103036)
		(width 0.153)
		(layer "B.Cu")
		(net 860)
	)
	(arc
		(start 213.545983 101.778526)
		(mid 213.939842 101.941667)
		(end 214.3337 101.778525)
		(width 0.153)
		(layer "B.Cu")
		(net 860)
	)
	(arc
		(start 211.416179 99.648722)
		(mid 211.810038 99.811863)
		(end 212.203896 99.648721)
		(width 0.153)
		(layer "B.Cu")
		(net 860)
	)
	(arc
		(start 211.416179 98.861005)
		(mid 211.253037 99.254863)
		(end 211.416178 99.648722)
		(width 0.153)
		(layer "B.Cu")
		(net 860)
	)
	(arc
		(start 217.834592 104.667044)
		(mid 217.973185 104.609637)
		(end 218.111778 104.667044)
		(width 0.153)
		(layer "B.Cu")
		(net 860)
	)
	(arc
		(start 215.675787 103.120613)
		(mid 215.512645 103.514471)
		(end 215.675786 103.90833)
		(width 0.153)
		(layer "B.Cu")
		(net 860)
	)
	(arc
		(start 213.852171 100.407436)
		(mid 213.909578 100.546029)
		(end 213.852171 100.684622)
		(width 0.153)
		(layer "B.Cu")
		(net 860)
	)
	(arc
		(start 208.3835 96.289359)
		(mid 208.472949 96.252308)
		(end 208.51 96.162859)
		(width 0.153)
		(layer "B.Cu")
		(net 860)
	)
	(arc
		(start 214.610885 102.055711)
		(mid 214.447743 102.449569)
		(end 214.610884 102.843428)
		(width 0.153)
		(layer "B.Cu")
		(net 860)
	)
	(arc
		(start 219.176681 105.731946)
		(mid 219.234088 105.870539)
		(end 219.176681 106.009132)
		(width 0.153)
		(layer "B.Cu")
		(net 860)
	)
	(arc
		(start 214.639886 101.472338)
		(mid 214.778479 101.414931)
		(end 214.917072 101.472338)
		(width 0.153)
		(layer "B.Cu")
		(net 860)
	)
	(arc
		(start 214.610885 102.843428)
		(mid 215.004744 103.006569)
		(end 215.398602 102.843427)
		(width 0.153)
		(layer "B.Cu")
		(net 860)
	)
	(arc
		(start 212.481081 99.925907)
		(mid 212.317939 100.319765)
		(end 212.48108 100.713624)
		(width 0.153)
		(layer "B.Cu")
		(net 860)
	)
	(arc
		(start 213.545983 100.990809)
		(mid 213.382841 101.384667)
		(end 213.545982 101.778526)
		(width 0.153)
		(layer "B.Cu")
		(net 860)
	)
	(arc
		(start 213.574984 100.407436)
		(mid 213.713577 100.350029)
		(end 213.85217 100.407436)
		(width 0.153)
		(layer "B.Cu")
		(net 860)
	)
	(arc
		(start 215.675787 103.90833)
		(mid 216.069646 104.071471)
		(end 216.463504 103.908329)
		(width 0.153)
		(layer "B.Cu")
		(net 860)
	)
	(arc
		(start 208.257 96.162859)
		(mid 208.294051 96.252308)
		(end 208.3835 96.289359)
		(width 0.153)
		(layer "B.Cu")
		(net 860)
	)
	(arc
		(start 212.481081 100.713624)
		(mid 212.87494 100.876765)
		(end 213.268798 100.713623)
		(width 0.153)
		(layer "B.Cu")
		(net 860)
	)
	(arc
		(start 215.981975 102.53724)
		(mid 216.039382 102.675833)
		(end 215.981975 102.814426)
		(width 0.153)
		(layer "B.Cu")
		(net 860)
	)
	(arc
		(start 211.722367 98.277632)
		(mid 211.779774 98.416225)
		(end 211.722367 98.554818)
		(width 0.153)
		(layer "B.Cu")
		(net 860)
	)
	(arc
		(start 217.805591 106.038134)
		(mid 218.19945 106.201275)
		(end 218.593308 106.038133)
		(width 0.153)
		(layer "B.Cu")
		(net 860)
	)
	(arc
		(start 216.76969 103.602142)
		(mid 216.908283 103.544735)
		(end 217.046876 103.602142)
		(width 0.153)
		(layer "B.Cu")
		(net 860)
	)
	(arc
		(start 208.1305 96.0305)
		(mid 208.219949 96.067551)
		(end 208.257 96.157)
		(width 0.153)
		(layer "B.Cu")
		(net 860)
	)
	(arc
		(start 218.111779 104.667044)
		(mid 218.169186 104.805637)
		(end 218.111779 104.94423)
		(width 0.153)
		(layer "B.Cu")
		(net 860)
	)
	(arc
		(start 219.964396 106.796848)
		(mid 220.102989 106.739441)
		(end 220.241582 106.796848)
		(width 0.153)
		(layer "B.Cu")
		(net 860)
	)
	(arc
		(start 216.740689 104.185515)
		(mid 216.577547 104.579373)
		(end 216.740688 104.973232)
		(width 0.153)
		(layer "B.Cu")
		(net 860)
	)
	(arc
		(start 218.899494 105.731946)
		(mid 219.038087 105.674539)
		(end 219.17668 105.731946)
		(width 0.153)
		(layer "B.Cu")
		(net 860)
	)
	(arc
		(start 218.870493 107.103036)
		(mid 219.264352 107.266177)
		(end 219.65821 107.103035)
		(width 0.153)
		(layer "B.Cu")
		(net 860)
	)
	(segment
		(start 247.014 109.425)
		(end 247.014 110.347994)
		(width 0.153)
		(layer "F.Cu")
		(net 861)
	)
	(segment
		(start 248.225 110.347994)
		(end 248.225 109.425)
		(width 0.153)
		(layer "F.Cu")
		(net 861)
	)
	(segment
		(start 253.429196 108.732639)
		(end 253.639208 108.732639)
		(width 0.153)
		(layer "F.Cu")
		(net 861)
	)
	(segment
		(start 242.635 109.5)
		(end 242.9545 109.1805)
		(width 0.153)
		(layer "F.Cu")
		(net 861)
	)
	(segment
		(start 244.825 110.347994)
		(end 244.825 109.425)
		(width 0.153)
		(layer "F.Cu")
		(net 861)
	)
	(segment
		(start 249.938831 109.1805)
		(end 252.981335 109.1805)
		(width 0.153)
		(layer "F.Cu")
		(net 861)
	)
	(segment
		(start 252.981335 109.1805)
		(end 253.429196 108.732639)
		(width 0.153)
		(layer "F.Cu")
		(net 861)
	)
	(segment
		(start 242.9545 109.1805)
		(end 243.3695 109.1805)
		(width 0.153)
		(layer "F.Cu")
		(net 861)
	)
	(segment
		(start 248.4695 109.1805)
		(end 249.938831 109.1805)
		(width 0.153)
		(layer "F.Cu")
		(net 861)
	)
	(segment
		(start 246.525 110.347994)
		(end 246.525 109.425)
		(width 0.153)
		(layer "F.Cu")
		(net 861)
	)
	(segment
		(start 245.314 109.425)
		(end 245.314 110.347994)
		(width 0.153)
		(layer "F.Cu")
		(net 861)
	)
	(segment
		(start 243.614 109.425)
		(end 243.614 110.347994)
		(width 0.153)
		(layer "F.Cu")
		(net 861)
	)
	(via
		(at 253.639208 108.732639)
		(size 0.45)
		(drill 0.2)
		(layers "F.Cu" "B.Cu")
		(net 861)
	)
	(arc
		(start 246.525 109.425)
		(mid 246.596612 109.252112)
		(end 246.7695 109.1805)
		(width 0.153)
		(layer "F.Cu")
		(net 861)
	)
	(arc
		(start 247.014 110.347994)
		(mid 247.191347 110.776147)
		(end 247.6195 110.953494)
		(width 0.153)
		(layer "F.Cu")
		(net 861)
	)
	(arc
		(start 245.0695 109.1805)
		(mid 245.242388 109.252112)
		(end 245.314 109.425)
		(width 0.153)
		(layer "F.Cu")
		(net 861)
	)
	(arc
		(start 247.6195 110.953494)
		(mid 248.047653 110.776147)
		(end 248.225 110.347994)
		(width 0.153)
		(layer "F.Cu")
		(net 861)
	)
	(arc
		(start 244.825 109.425)
		(mid 244.896612 109.252112)
		(end 245.0695 109.1805)
		(width 0.153)
		(layer "F.Cu")
		(net 861)
	)
	(arc
		(start 246.7695 109.1805)
		(mid 246.942388 109.252112)
		(end 247.014 109.425)
		(width 0.153)
		(layer "F.Cu")
		(net 861)
	)
	(arc
		(start 243.3695 109.1805)
		(mid 243.542388 109.252112)
		(end 243.614 109.425)
		(width 0.153)
		(layer "F.Cu")
		(net 861)
	)
	(arc
		(start 245.314 110.347994)
		(mid 245.491347 110.776147)
		(end 245.9195 110.953494)
		(width 0.153)
		(layer "F.Cu")
		(net 861)
	)
	(arc
		(start 248.225 109.425)
		(mid 248.296612 109.252112)
		(end 248.4695 109.1805)
		(width 0.153)
		(layer "F.Cu")
		(net 861)
	)
	(arc
		(start 245.9195 110.953494)
		(mid 246.347653 110.776147)
		(end 246.525 110.347994)
		(width 0.153)
		(layer "F.Cu")
		(net 861)
	)
	(arc
		(start 244.2195 110.953494)
		(mid 244.647653 110.776147)
		(end 244.825 110.347994)
		(width 0.153)
		(layer "F.Cu")
		(net 861)
	)
	(arc
		(start 243.614 110.347994)
		(mid 243.791347 110.776147)
		(end 244.2195 110.953494)
		(width 0.153)
		(layer "F.Cu")
		(net 861)
	)
	(segment
		(start 256.5515 113.738795)
		(end 256.5525 113.739795)
		(width 0.153)
		(layer "B.Cu")
		(net 861)
	)
	(segment
		(start 256.5515 113.738795)
		(end 256.5515 113.261205)
		(width 0.153)
		(layer "B.Cu")
		(net 861)
	)
	(segment
		(start 256.5525 113.739795)
		(end 256.5525 114.5)
		(width 0.153)
		(layer "B.Cu")
		(net 861)
	)
	(segment
		(start 255.849766 112.0945)
		(end 253.849766 112.0945)
		(width 0.153)
		(layer "B.Cu")
		(net 861)
	)
	(segment
		(start 256.1555 112.400234)
		(end 255.849766 112.0945)
		(width 0.153)
		(layer "B.Cu")
		(net 861)
	)
	(segment
		(start 253.849766 112.0945)
		(end 253.187069 111.431803)
		(width 0.153)
		(layer "B.Cu")
		(net 861)
	)
	(segment
		(start 256.5515 113.261205)
		(end 256.1555 112.865205)
		(width 0.153)
		(layer "B.Cu")
		(net 861)
	)
	(segment
		(start 253.187069 111.431803)
		(end 253.187069 108.974766)
		(width 0.153)
		(layer "B.Cu")
		(net 861)
	)
	(segment
		(start 253.187069 108.974766)
		(end 253.429196 108.732639)
		(width 0.153)
		(layer "B.Cu")
		(net 861)
	)
	(segment
		(start 256.1555 112.865205)
		(end 256.1555 112.400234)
		(width 0.153)
		(layer "B.Cu")
		(net 861)
	)
	(segment
		(start 253.429196 108.732639)
		(end 253.639208 108.732639)
		(width 0.153)
		(layer "B.Cu")
		(net 861)
	)
	(segment
		(start 250.889 106.9)
		(end 250.889 107.975277)
		(width 0.153)
		(layer "F.Cu")
		(net 862)
	)
	(segment
		(start 248.85 107.4805)
		(end 248.85 106.624723)
		(width 0.153)
		(layer "F.Cu")
		(net 862)
	)
	(segment
		(start 254.567361 106.877373)
		(end 254.325234 107.1195)
		(width 0.153)
		(layer "F.Cu")
		(net 862)
	)
	(segment
		(start 244.9545 107.1195)
		(end 244.635 106.8)
		(width 0.153)
		(layer "F.Cu")
		(net 862)
	)
	(segment
		(start 250.45 107.4805)
		(end 250.45 106.624723)
		(width 0.153)
		(layer "F.Cu")
		(net 862)
	)
	(segment
		(start 246.827937 107.1195)
		(end 244.9545 107.1195)
		(width 0.153)
		(layer "F.Cu")
		(net 862)
	)
	(segment
		(start 254.325234 107.1195)
		(end 252.2695 107.1195)
		(width 0.153)
		(layer "F.Cu")
		(net 862)
	)
	(segment
		(start 250.45 107.975277)
		(end 250.45 107.4805)
		(width 0.153)
		(layer "F.Cu")
		(net 862)
	)
	(segment
		(start 249.289 107.1195)
		(end 249.289 107.975277)
		(width 0.153)
		(layer "F.Cu")
		(net 862)
	)
	(segment
		(start 250.889 106.624723)
		(end 250.889 106.9)
		(width 0.153)
		(layer "F.Cu")
		(net 862)
	)
	(segment
		(start 247.4695 107.1195)
		(end 246.827937 107.1195)
		(width 0.153)
		(layer "F.Cu")
		(net 862)
	)
	(segment
		(start 252.05 106.9)
		(end 252.05 106.624723)
		(width 0.153)
		(layer "F.Cu")
		(net 862)
	)
	(segment
		(start 254.567361 106.667361)
		(end 254.567361 106.877373)
		(width 0.153)
		(layer "F.Cu")
		(net 862)
	)
	(segment
		(start 249.289 106.624723)
		(end 249.289 107.1195)
		(width 0.153)
		(layer "F.Cu")
		(net 862)
	)
	(segment
		(start 247.689 106.624723)
		(end 247.689 106.9)
		(width 0.153)
		(layer "F.Cu")
		(net 862)
	)
	(segment
		(start 248.85 107.975277)
		(end 248.85 107.4805)
		(width 0.153)
		(layer "F.Cu")
		(net 862)
	)
	(via
		(at 254.567361 106.667361)
		(size 0.45)
		(drill 0.2)
		(layers "F.Cu" "B.Cu")
		(net 862)
	)
	(arc
		(start 250.45 106.624723)
		(mid 250.279975 106.214248)
		(end 249.8695 106.044223)
		(width 0.153)
		(layer "F.Cu")
		(net 862)
	)
	(arc
		(start 252.05 106.624723)
		(mid 251.879975 106.214248)
		(end 251.4695 106.044223)
		(width 0.153)
		(layer "F.Cu")
		(net 862)
	)
	(arc
		(start 251.4695 106.044223)
		(mid 251.059025 106.214248)
		(end 250.889 106.624723)
		(width 0.153)
		(layer "F.Cu")
		(net 862)
	)
	(arc
		(start 250.889 107.975277)
		(mid 250.82471 108.130487)
		(end 250.6695 108.194777)
		(width 0.153)
		(layer "F.Cu")
		(net 862)
	)
	(arc
		(start 252.2695 107.1195)
		(mid 252.11429 107.05521)
		(end 252.05 106.9)
		(width 0.153)
		(layer "F.Cu")
		(net 862)
	)
	(arc
		(start 249.289 107.975277)
		(mid 249.22471 108.130487)
		(end 249.0695 108.194777)
		(width 0.153)
		(layer "F.Cu")
		(net 862)
	)
	(arc
		(start 249.0695 108.194777)
		(mid 248.91429 108.130487)
		(end 248.85 107.975277)
		(width 0.153)
		(layer "F.Cu")
		(net 862)
	)
	(arc
		(start 250.6695 108.194777)
		(mid 250.51429 108.130487)
		(end 250.45 107.975277)
		(width 0.153)
		(layer "F.Cu")
		(net 862)
	)
	(arc
		(start 249.8695 106.044223)
		(mid 249.459025 106.214248)
		(end 249.289 106.624723)
		(width 0.153)
		(layer "F.Cu")
		(net 862)
	)
	(arc
		(start 248.85 106.624723)
		(mid 248.679975 106.214248)
		(end 248.2695 106.044223)
		(width 0.153)
		(layer "F.Cu")
		(net 862)
	)
	(arc
		(start 247.689 106.9)
		(mid 247.62471 107.05521)
		(end 247.4695 107.1195)
		(width 0.153)
		(layer "F.Cu")
		(net 862)
	)
	(arc
		(start 248.2695 106.044223)
		(mid 247.859025 106.214248)
		(end 247.689 106.624723)
		(width 0.153)
		(layer "F.Cu")
		(net 862)
	)
	(segment
		(start 254.567361 106.877373)
		(end 254.567361 106.667361)
		(width 0.153)
		(layer "B.Cu")
		(net 862)
	)
	(segment
		(start 257.13 113.5)
		(end 257.527 113.103)
		(width 0.153)
		(layer "B.Cu")
		(net 862)
	)
	(segment
		(start 253.9945 107.450234)
		(end 254.567361 106.877373)
		(width 0.153)
		(layer "B.Cu")
		(net 862)
	)
	(segment
		(start 254.650234 111.6805)
		(end 254.329514 111.35978)
		(width 0.153)
		(layer "B.Cu")
		(net 862)
	)
	(segment
		(start 256.350234 111.6805)
		(end 254.650234 111.6805)
		(width 0.153)
		(layer "B.Cu")
		(net 862)
	)
	(segment
		(start 254.329514 108.43478)
		(end 253.9945 108.099766)
		(width 0.153)
		(layer "B.Cu")
		(net 862)
	)
	(segment
		(start 257.527 113.103)
		(end 257.527 112.857266)
		(width 0.153)
		(layer "B.Cu")
		(net 862)
	)
	(segment
		(start 253.9945 108.099766)
		(end 253.9945 107.450234)
		(width 0.153)
		(layer "B.Cu")
		(net 862)
	)
	(segment
		(start 257.527 112.857266)
		(end 256.350234 111.6805)
		(width 0.153)
		(layer "B.Cu")
		(net 862)
	)
	(segment
		(start 254.329514 111.35978)
		(end 254.329514 108.43478)
		(width 0.153)
		(layer "B.Cu")
		(net 862)
	)
	(segment
		(start 250.089 107.4805)
		(end 250.089 106.624723)
		(width 0.153)
		(layer "F.Cu")
		(net 863)
	)
	(segment
		(start 247.4695 107.4805)
		(end 246.827937 107.4805)
		(width 0.153)
		(layer "F.Cu")
		(net 863)
	)
	(segment
		(start 244.9545 107.4805)
		(end 244.635 107.8)
		(width 0.153)
		(layer "F.Cu")
		(net 863)
	)
	(segment
		(start 251.25 106.624723)
		(end 251.25 106.9)
		(width 0.153)
		(layer "F.Cu")
		(net 863)
	)
	(segment
		(start 249.65 106.624723)
		(end 249.65 107.1195)
		(width 0.153)
		(layer "F.Cu")
		(net 863)
	)
	(segment
		(start 250.089 107.975277)
		(end 250.089 107.4805)
		(width 0.153)
		(layer "F.Cu")
		(net 863)
	)
	(segment
		(start 254.822627 107.132639)
		(end 254.474766 107.4805)
		(width 0.153)
		(layer "F.Cu")
		(net 863)
	)
	(segment
		(start 248.05 106.624723)
		(end 248.05 106.9)
		(width 0.153)
		(layer "F.Cu")
		(net 863)
	)
	(segment
		(start 251.689 106.9)
		(end 251.689 106.624723)
		(width 0.153)
		(layer "F.Cu")
		(net 863)
	)
	(segment
		(start 251.25 106.9)
		(end 251.25 107.975277)
		(width 0.153)
		(layer "F.Cu")
		(net 863)
	)
	(segment
		(start 254.474766 107.4805)
		(end 252.2695 107.4805)
		(width 0.153)
		(layer "F.Cu")
		(net 863)
	)
	(segment
		(start 249.65 107.1195)
		(end 249.65 107.975277)
		(width 0.153)
		(layer "F.Cu")
		(net 863)
	)
	(segment
		(start 246.827937 107.4805)
		(end 244.9545 107.4805)
		(width 0.153)
		(layer "F.Cu")
		(net 863)
	)
	(segment
		(start 248.489 107.975277)
		(end 248.489 107.4805)
		(width 0.153)
		(layer "F.Cu")
		(net 863)
	)
	(segment
		(start 255.032639 107.132639)
		(end 254.822627 107.132639)
		(width 0.153)
		(layer "F.Cu")
		(net 863)
	)
	(segment
		(start 248.489 107.4805)
		(end 248.489 106.624723)
		(width 0.153)
		(layer "F.Cu")
		(net 863)
	)
	(via
		(at 255.032639 107.132639)
		(size 0.45)
		(drill 0.2)
		(layers "F.Cu" "B.Cu")
		(net 863)
	)
	(arc
		(start 248.489 106.624723)
		(mid 248.42471 106.469513)
		(end 248.2695 106.405223)
		(width 0.153)
		(layer "F.Cu")
		(net 863)
	)
	(arc
		(start 250.089 106.624723)
		(mid 250.02471 106.469513)
		(end 249.8695 106.405223)
		(width 0.153)
		(layer "F.Cu")
		(net 863)
	)
	(arc
		(start 251.689 106.624723)
		(mid 251.62471 106.469513)
		(end 251.4695 106.405223)
		(width 0.153)
		(layer "F.Cu")
		(net 863)
	)
	(arc
		(start 249.8695 106.405223)
		(mid 249.71429 106.469513)
		(end 249.65 106.624723)
		(width 0.153)
		(layer "F.Cu")
		(net 863)
	)
	(arc
		(start 252.2695 107.4805)
		(mid 251.859025 107.310475)
		(end 251.689 106.9)
		(width 0.153)
		(layer "F.Cu")
		(net 863)
	)
	(arc
		(start 248.2695 106.405223)
		(mid 248.11429 106.469513)
		(end 248.05 106.624723)
		(width 0.153)
		(layer "F.Cu")
		(net 863)
	)
	(arc
		(start 250.6695 108.555777)
		(mid 250.259025 108.385752)
		(end 250.089 107.975277)
		(width 0.153)
		(layer "F.Cu")
		(net 863)
	)
	(arc
		(start 248.05 106.9)
		(mid 247.879975 107.310475)
		(end 247.4695 107.4805)
		(width 0.153)
		(layer "F.Cu")
		(net 863)
	)
	(arc
		(start 251.4695 106.405223)
		(mid 251.31429 106.469513)
		(end 251.25 106.624723)
		(width 0.153)
		(layer "F.Cu")
		(net 863)
	)
	(arc
		(start 251.25 107.975277)
		(mid 251.079975 108.385752)
		(end 250.6695 108.555777)
		(width 0.153)
		(layer "F.Cu")
		(net 863)
	)
	(arc
		(start 249.0695 108.555777)
		(mid 248.659025 108.385752)
		(end 248.489 107.975277)
		(width 0.153)
		(layer "F.Cu")
		(net 863)
	)
	(arc
		(start 249.65 107.975277)
		(mid 249.479975 108.385752)
		(end 249.0695 108.555777)
		(width 0.153)
		(layer "F.Cu")
		(net 863)
	)
	(segment
		(start 254.690514 111.210248)
		(end 254.690514 108.285248)
		(width 0.153)
		(layer "B.Cu")
		(net 863)
	)
	(segment
		(start 254.822627 107.132639)
		(end 255.032639 107.132639)
		(width 0.153)
		(layer "B.Cu")
		(net 863)
	)
	(segment
		(start 257.888 113.103)
		(end 257.888 112.707734)
		(width 0.153)
		(layer "B.Cu")
		(net 863)
	)
	(segment
		(start 254.3555 107.950234)
		(end 254.3555 107.599766)
		(width 0.153)
		(layer "B.Cu")
		(net 863)
	)
	(segment
		(start 256.499766 111.3195)
		(end 254.799766 111.3195)
		(width 0.153)
		(layer "B.Cu")
		(net 863)
	)
	(segment
		(start 254.799766 111.3195)
		(end 254.690514 111.210248)
		(width 0.153)
		(layer "B.Cu")
		(net 863)
	)
	(segment
		(start 257.888 112.707734)
		(end 256.499766 111.3195)
		(width 0.153)
		(layer "B.Cu")
		(net 863)
	)
	(segment
		(start 258.285 113.5)
		(end 257.888 113.103)
		(width 0.153)
		(layer "B.Cu")
		(net 863)
	)
	(segment
		(start 254.3555 107.599766)
		(end 254.822627 107.132639)
		(width 0.153)
		(layer "B.Cu")
		(net 863)
	)
	(segment
		(start 254.690514 108.285248)
		(end 254.3555 107.950234)
		(width 0.153)
		(layer "B.Cu")
		(net 863)
	)
	(segment
		(start 256.625234 105.4195)
		(end 255.8805 105.4195)
		(width 0.153)
		(layer "F.Cu")
		(net 864)
	)
	(segment
		(start 256.767361 105.067361)
		(end 256.767361 105.277373)
		(width 0.153)
		(layer "F.Cu")
		(net 864)
	)
	(segment
		(start 255.586 105.125)
		(end 255.586 104.933718)
		(width 0.153)
		(layer "F.Cu")
		(net 864)
	)
	(segment
		(start 242.9545 105.4195)
		(end 242.635 105.1)
		(width 0.153)
		(layer "F.Cu")
		(net 864)
	)
	(segment
		(start 252.375 104.933718)
		(end 252.375 105.125)
		(width 0.153)
		(layer "F.Cu")
		(net 864)
	)
	(segment
		(start 252.0805 105.4195)
		(end 251.407961 105.4195)
		(width 0.153)
		(layer "F.Cu")
		(net 864)
	)
	(segment
		(start 251.407961 105.4195)
		(end 242.9545 105.4195)
		(width 0.153)
		(layer "F.Cu")
		(net 864)
	)
	(segment
		(start 253.686 105.125)
		(end 253.686 104.933718)
		(width 0.153)
		(layer "F.Cu")
		(net 864)
	)
	(segment
		(start 254.275 104.933718)
		(end 254.275 105.125)
		(width 0.153)
		(layer "F.Cu")
		(net 864)
	)
	(segment
		(start 256.767361 105.277373)
		(end 256.625234 105.4195)
		(width 0.153)
		(layer "F.Cu")
		(net 864)
	)
	(via
		(at 256.767361 105.067361)
		(size 0.45)
		(drill 0.2)
		(layers "F.Cu" "B.Cu")
		(net 864)
	)
	(arc
		(start 254.9305 104.278218)
		(mid 254.466992 104.47021)
		(end 254.275 104.933718)
		(width 0.153)
		(layer "F.Cu")
		(net 864)
	)
	(arc
		(start 253.686 104.933718)
		(mid 253.494008 104.47021)
		(end 253.0305 104.278218)
		(width 0.153)
		(layer "F.Cu")
		(net 864)
	)
	(arc
		(start 253.0305 104.278218)
		(mid 252.566992 104.47021)
		(end 252.375 104.933718)
		(width 0.153)
		(layer "F.Cu")
		(net 864)
	)
	(arc
		(start 252.375 105.125)
		(mid 252.288743 105.333243)
		(end 252.0805 105.4195)
		(width 0.153)
		(layer "F.Cu")
		(net 864)
	)
	(arc
		(start 255.586 104.933718)
		(mid 255.394008 104.47021)
		(end 254.9305 104.278218)
		(width 0.153)
		(layer "F.Cu")
		(net 864)
	)
	(arc
		(start 255.8805 105.4195)
		(mid 255.672257 105.333243)
		(end 255.586 105.125)
		(width 0.153)
		(layer "F.Cu")
		(net 864)
	)
	(arc
		(start 254.275 105.125)
		(mid 254.188743 105.333243)
		(end 253.9805 105.4195)
		(width 0.153)
		(layer "F.Cu")
		(net 864)
	)
	(arc
		(start 253.9805 105.4195)
		(mid 253.772257 105.333243)
		(end 253.686 105.125)
		(width 0.153)
		(layer "F.Cu")
		(net 864)
	)
	(segment
		(start 258.325234 112.2805)
		(end 256.3195 110.274766)
		(width 0.153)
		(layer "B.Cu")
		(net 864)
	)
	(segment
		(start 258.825234 112.2805)
		(end 258.325234 112.2805)
		(width 0.153)
		(layer "B.Cu")
		(net 864)
	)
	(segment
		(start 256.767361 105.277373)
		(end 256.767361 105.067361)
		(width 0.153)
		(layer "B.Cu")
		(net 864)
	)
	(segment
		(start 258.8625 114.5)
		(end 258.8625 113.2375)
		(width 0.153)
		(layer "B.Cu")
		(net 864)
	)
	(segment
		(start 259.2595 112.8405)
		(end 259.2595 112.714766)
		(width 0.153)
		(layer "B.Cu")
		(net 864)
	)
	(segment
		(start 256.3195 105.725234)
		(end 256.767361 105.277373)
		(width 0.153)
		(layer "B.Cu")
		(net 864)
	)
	(segment
		(start 258.8625 113.2375)
		(end 259.2595 112.8405)
		(width 0.153)
		(layer "B.Cu")
		(net 864)
	)
	(segment
		(start 256.3195 110.274766)
		(end 256.3195 105.725234)
		(width 0.153)
		(layer "B.Cu")
		(net 864)
	)
	(segment
		(start 259.2595 112.714766)
		(end 258.825234 112.2805)
		(width 0.153)
		(layer "B.Cu")
		(net 864)
	)
	(segment
		(start 252.0805 105.7805)
		(end 251.407961 105.7805)
		(width 0.153)
		(layer "F.Cu")
		(net 865)
	)
	(segment
		(start 252.736 104.933718)
		(end 252.736 105.125)
		(width 0.153)
		(layer "F.Cu")
		(net 865)
	)
	(segment
		(start 242.9545 105.7805)
		(end 242.635 106.1)
		(width 0.153)
		(layer "F.Cu")
		(net 865)
	)
	(segment
		(start 257.232639 105.532639)
		(end 257.022627 105.532639)
		(width 0.153)
		(layer "F.Cu")
		(net 865)
	)
	(segment
		(start 257.022627 105.532639)
		(end 256.774766 105.7805)
		(width 0.153)
		(layer "F.Cu")
		(net 865)
	)
	(segment
		(start 251.407961 105.7805)
		(end 242.9545 105.7805)
		(width 0.153)
		(layer "F.Cu")
		(net 865)
	)
	(segment
		(start 253.325 105.125)
		(end 253.325 104.933718)
		(width 0.153)
		(layer "F.Cu")
		(net 865)
	)
	(segment
		(start 254.636 104.933718)
		(end 254.636 105.125)
		(width 0.153)
		(layer "F.Cu")
		(net 865)
	)
	(segment
		(start 255.225 105.125)
		(end 255.225 104.933718)
		(width 0.153)
		(layer "F.Cu")
		(net 865)
	)
	(segment
		(start 256.774766 105.7805)
		(end 255.8805 105.7805)
		(width 0.153)
		(layer "F.Cu")
		(net 865)
	)
	(via
		(at 257.232639 105.532639)
		(size 0.45)
		(drill 0.2)
		(layers "F.Cu" "B.Cu")
		(net 865)
	)
	(arc
		(start 253.325 104.933718)
		(mid 253.238743 104.725475)
		(end 253.0305 104.639218)
		(width 0.153)
		(layer "F.Cu")
		(net 865)
	)
	(arc
		(start 254.636 105.125)
		(mid 254.444008 105.588508)
		(end 253.9805 105.7805)
		(width 0.153)
		(layer "F.Cu")
		(net 865)
	)
	(arc
		(start 253.0305 104.639218)
		(mid 252.822257 104.725475)
		(end 252.736 104.933718)
		(width 0.153)
		(layer "F.Cu")
		(net 865)
	)
	(arc
		(start 254.9305 104.639218)
		(mid 254.722257 104.725475)
		(end 254.636 104.933718)
		(width 0.153)
		(layer "F.Cu")
		(net 865)
	)
	(arc
		(start 252.736 105.125)
		(mid 252.544008 105.588508)
		(end 252.0805 105.7805)
		(width 0.153)
		(layer "F.Cu")
		(net 865)
	)
	(arc
		(start 253.9805 105.7805)
		(mid 253.516992 105.588508)
		(end 253.325 105.125)
		(width 0.153)
		(layer "F.Cu")
		(net 865)
	)
	(arc
		(start 255.225 104.933718)
		(mid 255.138743 104.725475)
		(end 254.9305 104.639218)
		(width 0.153)
		(layer "F.Cu")
		(net 865)
	)
	(arc
		(start 255.8805 105.7805)
		(mid 255.416992 105.588508)
		(end 255.225 105.125)
		(width 0.153)
		(layer "F.Cu")
		(net 865)
	)
	(segment
		(start 260.0175 113.739795)
		(end 260.0165 113.738795)
		(width 0.153)
		(layer "B.Cu")
		(net 865)
	)
	(segment
		(start 256.6805 105.874766)
		(end 257.022627 105.532639)
		(width 0.153)
		(layer "B.Cu")
		(net 865)
	)
	(segment
		(start 259.6205 112.865204)
		(end 259.6205 112.565234)
		(width 0.153)
		(layer "B.Cu")
		(net 865)
	)
	(segment
		(start 259.6205 112.565234)
		(end 258.974766 111.9195)
		(width 0.153)
		(layer "B.Cu")
		(net 865)
	)
	(segment
		(start 258.474766 111.9195)
		(end 256.6805 110.125234)
		(width 0.153)
		(layer "B.Cu")
		(net 865)
	)
	(segment
		(start 258.974766 111.9195)
		(end 258.474766 111.9195)
		(width 0.153)
		(layer "B.Cu")
		(net 865)
	)
	(segment
		(start 257.022627 105.532639)
		(end 257.232639 105.532639)
		(width 0.153)
		(layer "B.Cu")
		(net 865)
	)
	(segment
		(start 260.0165 113.261204)
		(end 259.6205 112.865204)
		(width 0.153)
		(layer "B.Cu")
		(net 865)
	)
	(segment
		(start 256.6805 110.125234)
		(end 256.6805 105.874766)
		(width 0.153)
		(layer "B.Cu")
		(net 865)
	)
	(segment
		(start 260.0165 113.738795)
		(end 260.0165 113.261204)
		(width 0.153)
		(layer "B.Cu")
		(net 865)
	)
	(segment
		(start 260.0175 114.5)
		(end 260.0175 113.739795)
		(width 0.153)
		(layer "B.Cu")
		(net 865)
	)
	(segment
		(start 244.9545 103.6195)
		(end 244.635 103.3)
		(width 0.153)
		(layer "F.Cu")
		(net 866)
	)
	(segment
		(start 257.839728 103.234722)
		(end 257.839728 103.444734)
		(width 0.153)
		(layer "F.Cu")
		(net 866)
	)
	(segment
		(start 257.664962 103.6195)
		(end 244.9545 103.6195)
		(width 0.153)
		(layer "F.Cu")
		(net 866)
	)
	(segment
		(start 257.839728 103.444734)
		(end 257.664962 103.6195)
		(width 0.153)
		(layer "F.Cu")
		(net 866)
	)
	(via
		(at 257.839728 103.234722)
		(size 0.45)
		(drill 0.2)
		(layers "F.Cu" "B.Cu")
		(net 866)
	)
	(segment
		(start 262.0195 111.525234)
		(end 262.0195 109.899766)
		(width 0.153)
		(layer "B.Cu")
		(net 866)
	)
	(segment
		(start 260.595 113.5)
		(end 260.992 113.103)
		(width 0.153)
		(layer "B.Cu")
		(net 866)
	)
	(segment
		(start 257.8195 109.14083)
		(end 257.8195 105.424766)
		(width 0.153)
		(layer "B.Cu")
		(net 866)
	)
	(segment
		(start 257.211838 104.817104)
		(end 257.211838 104.072624)
		(width 0.153)
		(layer "B.Cu")
		(net 866)
	)
	(segment
		(start 261.650234 109.5305)
		(end 258.20917 109.5305)
		(width 0.153)
		(layer "B.Cu")
		(net 866)
	)
	(segment
		(start 258.20917 109.5305)
		(end 257.8195 109.14083)
		(width 0.153)
		(layer "B.Cu")
		(net 866)
	)
	(segment
		(start 257.839728 103.444734)
		(end 257.839728 103.234722)
		(width 0.153)
		(layer "B.Cu")
		(net 866)
	)
	(segment
		(start 260.992 112.552734)
		(end 262.0195 111.525234)
		(width 0.153)
		(layer "B.Cu")
		(net 866)
	)
	(segment
		(start 262.0195 109.899766)
		(end 261.650234 109.5305)
		(width 0.153)
		(layer "B.Cu")
		(net 866)
	)
	(segment
		(start 257.211838 104.072624)
		(end 257.839728 103.444734)
		(width 0.153)
		(layer "B.Cu")
		(net 866)
	)
	(segment
		(start 260.992 113.103)
		(end 260.992 112.552734)
		(width 0.153)
		(layer "B.Cu")
		(net 866)
	)
	(segment
		(start 257.8195 105.424766)
		(end 257.211838 104.817104)
		(width 0.153)
		(layer "B.Cu")
		(net 866)
	)
	(segment
		(start 258.094994 103.7)
		(end 257.814494 103.9805)
		(width 0.153)
		(layer "F.Cu")
		(net 867)
	)
	(segment
		(start 258.305006 103.7)
		(end 258.094994 103.7)
		(width 0.153)
		(layer "F.Cu")
		(net 867)
	)
	(segment
		(start 257.814494 103.9805)
		(end 244.9545 103.9805)
		(width 0.153)
		(layer "F.Cu")
		(net 867)
	)
	(segment
		(start 244.9545 103.9805)
		(end 244.635 104.3)
		(width 0.153)
		(layer "F.Cu")
		(net 867)
	)
	(via
		(at 258.305006 103.7)
		(size 0.45)
		(drill 0.2)
		(layers "F.Cu" "B.Cu")
		(net 867)
	)
	(segment
		(start 258.094994 103.7)
		(end 258.305006 103.7)
		(width 0.153)
		(layer "B.Cu")
		(net 867)
	)
	(segment
		(start 261.75 113.5)
		(end 261.353 113.103)
		(width 0.153)
		(layer "B.Cu")
		(net 867)
	)
	(segment
		(start 261.353 113.103)
		(end 261.353 112.702266)
		(width 0.153)
		(layer "B.Cu")
		(net 867)
	)
	(segment
		(start 257.572838 104.667572)
		(end 257.572838 104.222156)
		(width 0.153)
		(layer "B.Cu")
		(net 867)
	)
	(segment
		(start 258.1805 105.275234)
		(end 257.572838 104.667572)
		(width 0.153)
		(layer "B.Cu")
		(net 867)
	)
	(segment
		(start 262.3805 109.750234)
		(end 261.799766 109.1695)
		(width 0.153)
		(layer "B.Cu")
		(net 867)
	)
	(segment
		(start 258.358702 109.1695)
		(end 258.1805 108.991298)
		(width 0.153)
		(layer "B.Cu")
		(net 867)
	)
	(segment
		(start 261.353 112.702266)
		(end 262.3805 111.674766)
		(width 0.153)
		(layer "B.Cu")
		(net 867)
	)
	(segment
		(start 258.1805 108.991298)
		(end 258.1805 105.275234)
		(width 0.153)
		(layer "B.Cu")
		(net 867)
	)
	(segment
		(start 257.572838 104.222156)
		(end 258.094994 103.7)
		(width 0.153)
		(layer "B.Cu")
		(net 867)
	)
	(segment
		(start 261.799766 109.1695)
		(end 258.358702 109.1695)
		(width 0.153)
		(layer "B.Cu")
		(net 867)
	)
	(segment
		(start 262.3805 111.674766)
		(end 262.3805 109.750234)
		(width 0.153)
		(layer "B.Cu")
		(net 867)
	)
	(segment
		(start 252.831803 108.8195)
		(end 253.17393 108.477373)
		(width 0.153)
		(layer "F.Cu")
		(net 868)
	)
	(segment
		(start 242.9545 108.8195)
		(end 243.3695 108.8195)
		(width 0.153)
		(layer "F.Cu")
		(net 868)
	)
	(segment
		(start 243.975 109.425)
		(end 243.975 110.347994)
		(width 0.153)
		(layer "F.Cu")
		(net 868)
	)
	(segment
		(start 246.164 110.347994)
		(end 246.164 109.425)
		(width 0.153)
		(layer "F.Cu")
		(net 868)
	)
	(segment
		(start 248.4695 108.8195)
		(end 249.938831 108.8195)
		(width 0.153)
		(layer "F.Cu")
		(net 868)
	)
	(segment
		(start 249.938831 108.8195)
		(end 252.831803 108.8195)
		(width 0.153)
		(layer "F.Cu")
		(net 868)
	)
	(segment
		(start 253.17393 108.477373)
		(end 253.17393 108.267361)
		(width 0.153)
		(layer "F.Cu")
		(net 868)
	)
	(segment
		(start 247.864 110.347994)
		(end 247.864 109.425)
		(width 0.153)
		(layer "F.Cu")
		(net 868)
	)
	(segment
		(start 245.675 109.425)
		(end 245.675 110.347994)
		(width 0.153)
		(layer "F.Cu")
		(net 868)
	)
	(segment
		(start 244.464 110.347994)
		(end 244.464 109.425)
		(width 0.153)
		(layer "F.Cu")
		(net 868)
	)
	(segment
		(start 242.635 108.5)
		(end 242.9545 108.8195)
		(width 0.153)
		(layer "F.Cu")
		(net 868)
	)
	(segment
		(start 247.375 109.425)
		(end 247.375 110.347994)
		(width 0.153)
		(layer "F.Cu")
		(net 868)
	)
	(via
		(at 253.17393 108.267361)
		(size 0.45)
		(drill 0.2)
		(layers "F.Cu" "B.Cu")
		(net 868)
	)
	(arc
		(start 245.9195 110.592494)
		(mid 246.092388 110.520882)
		(end 246.164 110.347994)
		(width 0.153)
		(layer "F.Cu")
		(net 868)
	)
	(arc
		(start 243.975 110.347994)
		(mid 244.046612 110.520882)
		(end 244.2195 110.592494)
		(width 0.153)
		(layer "F.Cu")
		(net 868)
	)
	(arc
		(start 243.3695 108.8195)
		(mid 243.797653 108.996847)
		(end 243.975 109.425)
		(width 0.153)
		(layer "F.Cu")
		(net 868)
	)
	(arc
		(start 247.864 109.425)
		(mid 248.041347 108.996847)
		(end 248.4695 108.8195)
		(width 0.153)
		(layer "F.Cu")
		(net 868)
	)
	(arc
		(start 245.675 110.347994)
		(mid 245.746612 110.520882)
		(end 245.9195 110.592494)
		(width 0.153)
		(layer "F.Cu")
		(net 868)
	)
	(arc
		(start 246.164 109.425)
		(mid 246.341347 108.996847)
		(end 246.7695 108.8195)
		(width 0.153)
		(layer "F.Cu")
		(net 868)
	)
	(arc
		(start 244.464 109.425)
		(mid 244.641347 108.996847)
		(end 245.0695 108.8195)
		(width 0.153)
		(layer "F.Cu")
		(net 868)
	)
	(arc
		(start 247.6195 110.592494)
		(mid 247.792388 110.520882)
		(end 247.864 110.347994)
		(width 0.153)
		(layer "F.Cu")
		(net 868)
	)
	(arc
		(start 244.2195 110.592494)
		(mid 244.392388 110.520882)
		(end 244.464 110.347994)
		(width 0.153)
		(layer "F.Cu")
		(net 868)
	)
	(arc
		(start 247.375 110.347994)
		(mid 247.446612 110.520882)
		(end 247.6195 110.592494)
		(width 0.153)
		(layer "F.Cu")
		(net 868)
	)
	(arc
		(start 245.0695 108.8195)
		(mid 245.497653 108.996847)
		(end 245.675 109.425)
		(width 0.153)
		(layer "F.Cu")
		(net 868)
	)
	(arc
		(start 246.7695 108.8195)
		(mid 247.197653 108.996847)
		(end 247.375 109.425)
		(width 0.153)
		(layer "F.Cu")
		(net 868)
	)
	(segment
		(start 255.700234 112.4555)
		(end 253.700234 112.4555)
		(width 0.153)
		(layer "B.Cu")
		(net 868)
	)
	(segment
		(start 255.7945 112.8055)
		(end 255.7945 112.549766)
		(width 0.153)
		(layer "B.Cu")
		(net 868)
	)
	(segment
		(start 255.3975 114.5)
		(end 255.3975 113.2025)
		(width 0.153)
		(layer "B.Cu")
		(net 868)
	)
	(segment
		(start 252.826069 108.825234)
		(end 253.17393 108.477373)
		(width 0.153)
		(layer "B.Cu")
		(net 868)
	)
	(segment
		(start 255.7945 112.549766)
		(end 255.700234 112.4555)
		(width 0.153)
		(layer "B.Cu")
		(net 868)
	)
	(segment
		(start 253.17393 108.477373)
		(end 253.17393 108.267361)
		(width 0.153)
		(layer "B.Cu")
		(net 868)
	)
	(segment
		(start 253.700234 112.4555)
		(end 252.826069 111.581335)
		(width 0.153)
		(layer "B.Cu")
		(net 868)
	)
	(segment
		(start 252.826069 111.581335)
		(end 252.826069 108.825234)
		(width 0.153)
		(layer "B.Cu")
		(net 868)
	)
	(segment
		(start 255.3975 113.2025)
		(end 255.7945 112.8055)
		(width 0.153)
		(layer "B.Cu")
		(net 868)
	)
	(segment
		(start 160.4 145.85)
		(end 160.55 145.7)
		(width 0.1)
		(layer "F.Cu")
		(net 869)
	)
	(segment
		(start 160.55 145.7)
		(end 160.646 145.7)
		(width 0.1)
		(layer "F.Cu")
		(net 869)
	)
	(segment
		(start 160.185 147.9)
		(end 160.4 147.685)
		(width 0.1)
		(layer "F.Cu")
		(net 869)
	)
	(segment
		(start 160.4 147.685)
		(end 160.4 145.85)
		(width 0.1)
		(layer "F.Cu")
		(net 869)
	)
	(segment
		(start 161.508578 145.4)
		(end 161.8 145.108578)
		(width 0.1)
		(layer "F.Cu")
		(net 870)
	)
	(segment
		(start 161.8 145.108578)
		(end 161.8 142.591422)
		(width 0.1)
		(layer "F.Cu")
		(net 870)
	)
	(segment
		(start 161 145.4)
		(end 161.508578 145.4)
		(width 0.1)
		(layer "F.Cu")
		(net 870)
	)
	(segment
		(start 161.8 142.591422)
		(end 161.083578 141.875)
		(width 0.1)
		(layer "F.Cu")
		(net 870)
	)
	(segment
		(start 160.9 145.3)
		(end 161 145.4)
		(width 0.1)
		(layer "F.Cu")
		(net 870)
	)
	(segment
		(start 160.425 141.875)
		(end 160.25 142.05)
		(width 0.1)
		(layer "F.Cu")
		(net 870)
	)
	(segment
		(start 161.083578 141.875)
		(end 160.425 141.875)
		(width 0.1)
		(layer "F.Cu")
		(net 870)
	)
	(via
		(at 198 131)
		(size 0.45)
		(drill 0.2)
		(layers "F.Cu" "B.Cu")
		(free yes)
		(net 870)
	)
	(via
		(at 160.25 142.05)
		(size 0.45)
		(drill 0.2)
		(layers "F.Cu" "B.Cu")
		(net 870)
	)
	(segment
		(start 198.229 131.229)
		(end 198 131)
		(width 0.4)
		(layer "B.Cu")
		(net 870)
	)
	(segment
		(start 198.229 131.442)
		(end 198.229 131.229)
		(width 0.4)
		(layer "B.Cu")
		(net 870)
	)
	(segment
		(start 156.075 135.108578)
		(end 159.308578 131.875)
		(width 0.1)
		(layer "In5.Cu")
		(net 870)
	)
	(segment
		(start 164.341422 133.125)
		(end 172.391422 133.125)
		(width 0.1)
		(layer "In5.Cu")
		(net 870)
	)
	(segment
		(start 192.125 133.233578)
		(end 192.125 134.933578)
		(width 0.1)
		(layer "In5.Cu")
		(net 870)
	)
	(segment
		(start 198.4 131.125)
		(end 198.4 131.283578)
		(width 0.1)
		(layer "In5.Cu")
		(net 870)
	)
	(segment
		(start 182.233578 133.75)
		(end 183.083578 132.9)
		(width 0.1)
		(layer "In5.Cu")
		(net 870)
	)
	(segment
		(start 159.308578 131.875)
		(end 163.091422 131.875)
		(width 0.1)
		(layer "In5.Cu")
		(net 870)
	)
	(segment
		(start 197.783578 131.4)
		(end 198.283578 131.4)
		(width 0.1)
		(layer "In5.Cu")
		(net 870)
	)
	(segment
		(start 192.883578 135.1)
		(end 193.4 134.583578)
		(width 0.1)
		(layer "In5.Cu")
		(net 870)
	)
	(segment
		(start 197.208578 132.425)
		(end 197.4 132.233578)
		(width 0.1)
		(layer "In5.Cu")
		(net 870)
	)
	(segment
		(start 160.25 142.05)
		(end 160.075 141.875)
		(width 0.1)
		(layer "In5.Cu")
		(net 870)
	)
	(segment
		(start 198.275 131)
		(end 198.4 131.125)
		(width 0.1)
		(layer "In5.Cu")
		(net 870)
	)
	(segment
		(start 193.4 132.708578)
		(end 193.683578 132.425)
		(width 0.1)
		(layer "In5.Cu")
		(net 870)
	)
	(segment
		(start 183.083578 132.9)
		(end 191.791422 132.9)
		(width 0.1)
		(layer "In5.Cu")
		(net 870)
	)
	(segment
		(start 156.075 139.591422)
		(end 156.075 135.108578)
		(width 0.1)
		(layer "In5.Cu")
		(net 870)
	)
	(segment
		(start 163.091422 131.875)
		(end 164.341422 133.125)
		(width 0.1)
		(layer "In5.Cu")
		(net 870)
	)
	(segment
		(start 198 131)
		(end 198.275 131)
		(width 0.1)
		(layer "In5.Cu")
		(net 870)
	)
	(segment
		(start 198.283578 131.4)
		(end 198.4 131.283578)
		(width 0.1)
		(layer "In5.Cu")
		(net 870)
	)
	(segment
		(start 193.4 134.583578)
		(end 193.4 132.708578)
		(width 0.1)
		(layer "In5.Cu")
		(net 870)
	)
	(segment
		(start 191.791422 132.9)
		(end 192.125 133.233578)
		(width 0.1)
		(layer "In5.Cu")
		(net 870)
	)
	(segment
		(start 158.358578 141.875)
		(end 156.075 139.591422)
		(width 0.1)
		(layer "In5.Cu")
		(net 870)
	)
	(segment
		(start 192.291422 135.1)
		(end 192.883578 135.1)
		(width 0.1)
		(layer "In5.Cu")
		(net 870)
	)
	(segment
		(start 173.016422 133.75)
		(end 182.233578 133.75)
		(width 0.1)
		(layer "In5.Cu")
		(net 870)
	)
	(segment
		(start 197.4 131.783578)
		(end 197.783578 131.4)
		(width 0.1)
		(layer "In5.Cu")
		(net 870)
	)
	(segment
		(start 172.391422 133.125)
		(end 173.016422 133.75)
		(width 0.1)
		(layer "In5.Cu")
		(net 870)
	)
	(segment
		(start 193.683578 132.425)
		(end 197.208578 132.425)
		(width 0.1)
		(layer "In5.Cu")
		(net 870)
	)
	(segment
		(start 192.125 134.933578)
		(end 192.291422 135.1)
		(width 0.1)
		(layer "In5.Cu")
		(net 870)
	)
	(segment
		(start 160.075 141.875)
		(end 158.358578 141.875)
		(width 0.1)
		(layer "In5.Cu")
		(net 870)
	)
	(segment
		(start 197.4 132.233578)
		(end 197.4 131.783578)
		(width 0.1)
		(layer "In5.Cu")
		(net 870)
	)
	(segment
		(start 227.225 156.2)
		(end 227.235 156.21)
		(width 0.1)
		(layer "F.Cu")
		(net 872)
	)
	(segment
		(start 228.5 158.502121)
		(end 228.517121 158.485)
		(width 0.1)
		(layer "F.Cu")
		(net 872)
	)
	(segment
		(start 224.315 163.32)
		(end 225.285 162.35)
		(width 0.1)
		(layer "F.Cu")
		(net 872)
	)
	(segment
		(start 228.812121 158.19)
		(end 228.517121 158.485)
		(width 0.1)
		(layer "F.Cu")
		(net 872)
	)
	(segment
		(start 225.285 162.35)
		(end 225.3 162.35)
		(width 0.1)
		(layer "F.Cu")
		(net 872)
	)
	(segment
		(start 229.8 158.19)
		(end 228.812121 158.19)
		(width 0.1)
		(layer "F.Cu")
		(net 872)
	)
	(segment
		(start 225.3 162.35)
		(end 225.95 161.7)
		(width 0.1)
		(layer "F.Cu")
		(net 872)
	)
	(segment
		(start 226.65 156.2)
		(end 227.225 156.2)
		(width 0.1)
		(layer "F.Cu")
		(net 872)
	)
	(segment
		(start 224.315 163.4)
		(end 224.315 163.32)
		(width 0.1)
		(layer "F.Cu")
		(net 872)
	)
	(segment
		(start 228.5 158.8)
		(end 228.5 158.502121)
		(width 0.1)
		(layer "F.Cu")
		(net 872)
	)
	(via
		(at 226.65 156.2)
		(size 0.45)
		(drill 0.2)
		(layers "F.Cu" "B.Cu")
		(net 872)
	)
	(via
		(at 228.5 158.8)
		(size 0.45)
		(drill 0.2)
		(layers "F.Cu" "B.Cu")
		(net 872)
	)
	(via
		(at 225.95 161.7)
		(size 0.45)
		(drill 0.2)
		(layers "F.Cu" "B.Cu")
		(net 872)
	)
	(segment
		(start 225.95 161.35)
		(end 228.5 158.8)
		(width 0.1)
		(layer "B.Cu")
		(net 872)
	)
	(segment
		(start 225.95 161.7)
		(end 225.95 161.35)
		(width 0.1)
		(layer "B.Cu")
		(net 872)
	)
	(segment
		(start 228.5 158.8)
		(end 228.5 158.05)
		(width 0.1)
		(layer "B.Cu")
		(net 872)
	)
	(segment
		(start 228.5 158.05)
		(end 226.65 156.2)
		(width 0.1)
		(layer "B.Cu")
		(net 872)
	)
	(segment
		(start 222.45 125.75)
		(end 221.135 125.75)
		(width 0.1)
		(layer "B.Cu")
		(net 876)
	)
	(segment
		(start 221.135 125.75)
		(end 221.085 125.8)
		(width 0.1)
		(layer "B.Cu")
		(net 876)
	)
	(segment
		(start 221.085 123.8)
		(end 221.085 125.8)
		(width 0.1)
		(layer "B.Cu")
		(net 876)
	)
	(segment
		(start 241.001473 141.215)
		(end 238.65 141.215)
		(width 0.1)
		(layer "F.Cu")
		(net 878)
	)
	(segment
		(start 241.39 140.826473)
		(end 241.001473 141.215)
		(width 0.1)
		(layer "F.Cu")
		(net 878)
	)
	(via
		(at 241.39 140.826473)
		(size 0.45)
		(drill 0.2)
		(layers "F.Cu" "B.Cu")
		(net 878)
	)
	(segment
		(start 242.195 141.53)
		(end 242.3 141.635)
		(width 0.1)
		(layer "B.Cu")
		(net 878)
	)
	(segment
		(start 240.95 141)
		(end 240.551 141)
		(width 0.1)
		(layer "B.Cu")
		(net 878)
	)
	(segment
		(start 241.39 141.12)
		(end 241.8 141.53)
		(width 0.1)
		(layer "B.Cu")
		(net 878)
	)
	(segment
		(start 241.39 140.826473)
		(end 241.39 141.12)
		(width 0.1)
		(layer "B.Cu")
		(net 878)
	)
	(segment
		(start 241.8 141.53)
		(end 242.195 141.53)
		(width 0.1)
		(layer "B.Cu")
		(net 878)
	)
	(segment
		(start 241.39 140.826473)
		(end 241.123527 140.826473)
		(width 0.1)
		(layer "B.Cu")
		(net 878)
	)
	(segment
		(start 241.123527 140.826473)
		(end 240.95 141)
		(width 0.1)
		(layer "B.Cu")
		(net 878)
	)
	(segment
		(start 225.68 164.66)
		(end 225.7 164.68)
		(width 0.1)
		(layer "F.Cu")
		(net 880)
	)
	(segment
		(start 233.0655 162.22)
		(end 232.705 162.22)
		(width 0.1)
		(layer "F.Cu")
		(net 880)
	)
	(segment
		(start 232.705 162.22)
		(end 232.7 162.215)
		(width 0.1)
		(layer "F.Cu")
		(net 880)
	)
	(segment
		(start 225.7 164.68)
		(end 226.47 164.68)
		(width 0.1)
		(layer "F.Cu")
		(net 880)
	)
	(via
		(at 225.68 164.66)
		(size 0.45)
		(drill 0.2)
		(layers "F.Cu" "B.Cu")
		(net 880)
	)
	(via
		(at 233.0655 162.22)
		(size 0.45)
		(drill 0.2)
		(layers "F.Cu" "B.Cu")
		(net 880)
	)
	(segment
		(start 225.605 162.524669)
		(end 225.909669 162.22)
		(width 0.1)
		(layer "B.Cu")
		(net 880)
	)
	(segment
		(start 225.605 164.585)
		(end 225.605 162.524669)
		(width 0.1)
		(layer "B.Cu")
		(net 880)
	)
	(segment
		(start 225.68 164.66)
		(end 225.605 164.585)
		(width 0.1)
		(layer "B.Cu")
		(net 880)
	)
	(segment
		(start 225.909669 162.22)
		(end 233.0655 162.22)
		(width 0.1)
		(layer "B.Cu")
		(net 880)
	)
	(segment
		(start 252.6 177.225)
		(end 252.6 177.9)
		(width 0.256)
		(layer "F.Cu")
		(net 881)
	)
	(via
		(at 252.6 177.9)
		(size 0.45)
		(drill 0.2)
		(layers "F.Cu" "B.Cu")
		(net 881)
	)
	(segment
		(start 252.6 177.9)
		(end 252.6 177.47)
		(width 0.4)
		(layer "B.Cu")
		(net 881)
	)
	(segment
		(start 252.92 177.15)
		(end 254.91 177.15)
		(width 0.4)
		(layer "B.Cu")
		(net 881)
	)
	(segment
		(start 254.91 177.15)
		(end 255.23 176.83)
		(width 0.4)
		(layer "B.Cu")
		(net 881)
	)
	(segment
		(start 252.6 177.47)
		(end 252.92 177.15)
		(width 0.4)
		(layer "B.Cu")
		(net 881)
	)
	(segment
		(start 251.95 177.225)
		(end 251.95 177.9)
		(width 0.256)
		(layer "F.Cu")
		(net 882)
	)
	(via
		(at 251.95 177.9)
		(size 0.45)
		(drill 0.2)
		(layers "F.Cu" "B.Cu")
		(net 882)
	)
	(segment
		(start 251.95 178.365)
		(end 252.1 178.515)
		(width 0.256)
		(layer "B.Cu")
		(net 882)
	)
	(segment
		(start 251.95 177.9)
		(end 251.95 178.365)
		(width 0.256)
		(layer "B.Cu")
		(net 882)
	)
	(segment
		(start 253.25 177.225)
		(end 253.25 177.9)
		(width 0.256)
		(layer "F.Cu")
		(net 883)
	)
	(via
		(at 253.25 177.9)
		(size 0.45)
		(drill 0.2)
		(layers "F.Cu" "B.Cu")
		(net 883)
	)
	(segment
		(start 253.25 178.425)
		(end 253.1 178.575)
		(width 0.256)
		(layer "B.Cu")
		(net 883)
	)
	(segment
		(start 253.25 177.9)
		(end 253.25 178.425)
		(width 0.256)
		(layer "B.Cu")
		(net 883)
	)
	(segment
		(start 250.275 174.9)
		(end 249.6 174.9)
		(width 0.256)
		(layer "F.Cu")
		(net 885)
	)
	(via
		(at 249.6 174.9)
		(size 0.45)
		(drill 0.2)
		(layers "F.Cu" "B.Cu")
		(net 885)
	)
	(segment
		(start 248.6 176)
		(end 249.6 175)
		(width 0.1)
		(layer "B.Cu")
		(net 885)
	)
	(segment
		(start 249.6 175)
		(end 249.6 174.9)
		(width 0.1)
		(layer "B.Cu")
		(net 885)
	)
	(segment
		(start 251.3 177.225)
		(end 251.3 177.9)
		(width 0.256)
		(layer "F.Cu")
		(net 886)
	)
	(via
		(at 251.3 177.9)
		(size 0.45)
		(drill 0.2)
		(layers "F.Cu" "B.Cu")
		(net 886)
	)
	(segment
		(start 251.3 177.9)
		(end 251.3 178.3)
		(width 0.256)
		(layer "B.Cu")
		(net 886)
	)
	(segment
		(start 251.3 178.3)
		(end 251.1 178.5)
		(width 0.256)
		(layer "B.Cu")
		(net 886)
	)
	(segment
		(start 250.275 174.25)
		(end 249.64077 174.25)
		(width 0.256)
		(layer "F.Cu")
		(net 887)
	)
	(segment
		(start 249.64077 174.25)
		(end 249.622772 174.232002)
		(width 0.256)
		(layer "F.Cu")
		(net 887)
	)
	(via
		(at 249.622772 174.232002)
		(size 0.45)
		(drill 0.2)
		(layers "F.Cu" "B.Cu")
		(net 887)
	)
	(segment
		(start 248.969774 174.885)
		(end 249.622772 174.232002)
		(width 0.256)
		(layer "B.Cu")
		(net 887)
	)
	(segment
		(start 248.8 174.885)
		(end 248.969774 174.885)
		(width 0.256)
		(layer "B.Cu")
		(net 887)
	)
	(segment
		(start 228.65 160.052121)
		(end 229.002121 159.7)
		(width 0.1)
		(layer "F.Cu")
		(net 888)
	)
	(segment
		(start 228.65 161.5)
		(end 228.65 160.052121)
		(width 0.1)
		(layer "F.Cu")
		(net 888)
	)
	(segment
		(start 254.925 174.9)
		(end 255.6 174.9)
		(width 0.256)
		(layer "F.Cu")
		(net 889)
	)
	(segment
		(start 255.6 174.9)
		(end 256 174.5)
		(width 0.256)
		(layer "F.Cu")
		(net 889)
	)
	(via
		(at 256 174.5)
		(size 0.45)
		(drill 0.2)
		(layers "F.Cu" "B.Cu")
		(net 889)
	)
	(segment
		(start 253.6 170.415)
		(end 254.8 170.415)
		(width 0.1)
		(layer "B.Cu")
		(net 889)
	)
	(segment
		(start 256.415 171.35762)
		(end 256.25 171.52262)
		(width 0.256)
		(layer "B.Cu")
		(net 889)
	)
	(segment
		(start 256.415 170.34762)
		(end 254.86738 170.34762)
		(width 0.256)
		(layer "B.Cu")
		(net 889)
	)
	(segment
		(start 256.415 170.34762)
		(end 256.415 171.35762)
		(width 0.256)
		(layer "B.Cu")
		(net 889)
	)
	(segment
		(start 256 174.5)
		(end 256 172.5)
		(width 0.1)
		(layer "B.Cu")
		(net 889)
	)
	(segment
		(start 256.25 172.25)
		(end 256.25 171.52262)
		(width 0.1)
		(layer "B.Cu")
		(net 889)
	)
	(segment
		(start 254.86738 170.34762)
		(end 254.8 170.415)
		(width 0.256)
		(layer "B.Cu")
		(net 889)
	)
	(segment
		(start 256 172.5)
		(end 256.25 172.25)
		(width 0.1)
		(layer "B.Cu")
		(net 889)
	)
	(segment
		(start 201.5 116.3)
		(end 201 115.8)
		(width 0.182)
		(layer "F.Cu")
		(net 893)
	)
	(segment
		(start 201 115.8)
		(end 201 114.3)
		(width 0.182)
		(layer "F.Cu")
		(net 893)
	)
	(segment
		(start 200.1 113.4)
		(end 201 114.3)
		(width 0.184)
		(layer "F.Cu")
		(net 893)
	)
	(segment
		(start 196.075 111.225)
		(end 196.075 112.875)
		(width 0.182)
		(layer "F.Cu")
		(net 893)
	)
	(segment
		(start 196.6 113.4)
		(end 200.1 113.4)
		(width 0.184)
		(layer "F.Cu")
		(net 893)
	)
	(segment
		(start 196.075 112.875)
		(end 196.6 113.4)
		(width 0.184)
		(layer "F.Cu")
		(net 893)
	)
	(segment
		(start 201.5 116.5)
		(end 201.5 116.3)
		(width 0.182)
		(layer "F.Cu")
		(net 893)
	)
	(segment
		(start 226.97235 118.0209)
		(end 225.9891 118.0209)
		(width 0.184)
		(layer "F.Cu")
		(net 894)
	)
	(segment
		(start 225.9891 118.0209)
		(end 225.51 118.5)
		(width 0.184)
		(layer "F.Cu")
		(net 894)
	)
	(segment
		(start 233.87765 120.56)
		(end 235.37 120.56)
		(width 0.184)
		(layer "F.Cu")
		(net 895)
	)
	(segment
		(start 235.37 120.56)
		(end 235.43 120.5)
		(width 0.184)
		(layer "F.Cu")
		(net 895)
	)
	(segment
		(start 234.2 122.5)
		(end 233.87765 122.17765)
		(width 0.184)
		(layer "F.Cu")
		(net 896)
	)
	(segment
		(start 233.87765 122.17765)
		(end 233.87765 121.8259)
		(width 0.184)
		(layer "F.Cu")
		(net 896)
	)
	(segment
		(start 235.43 122.5)
		(end 234.2 122.5)
		(width 0.184)
		(layer "F.Cu")
		(net 896)
	)
	(segment
		(start 226.97235 119.3059)
		(end 225.7041 119.3059)
		(width 0.184)
		(layer "F.Cu")
		(net 897)
	)
	(segment
		(start 225.7041 119.3059)
		(end 225.51 119.5)
		(width 0.184)
		(layer "F.Cu")
		(net 897)
	)
	(segment
		(start 226.025 121.5)
		(end 226.175 121.35)
		(width 0.184)
		(layer "F.Cu")
		(net 898)
	)
	(segment
		(start 226.97235 120.56)
		(end 226.97235 121.15265)
		(width 0.184)
		(layer "F.Cu")
		(net 898)
	)
	(segment
		(start 226.97235 121.15265)
		(end 226.775 121.35)
		(width 0.184)
		(layer "F.Cu")
		(net 898)
	)
	(segment
		(start 225.51 121.5)
		(end 226.025 121.5)
		(width 0.184)
		(layer "F.Cu")
		(net 898)
	)
	(segment
		(start 226.775 121.35)
		(end 226.175 121.35)
		(width 0.184)
		(layer "F.Cu")
		(net 898)
	)
	(segment
		(start 235.43 118.5)
		(end 234.64 119.29)
		(width 0.184)
		(layer "F.Cu")
		(net 899)
	)
	(segment
		(start 234.64 119.29)
		(end 233.87765 119.29)
		(width 0.184)
		(layer "F.Cu")
		(net 899)
	)
	(segment
		(start 233.725 119.29)
		(end 234.225 119.29)
		(width 0.1)
		(layer "F.Cu")
		(net 899)
	)
	(segment
		(start 211.625 164.375)
		(end 211.625 163.9)
		(width 0.184)
		(layer "F.Cu")
		(net 900)
	)
	(segment
		(start 211.9 164.915)
		(end 211.9 164.65)
		(width 0.184)
		(layer "F.Cu")
		(net 900)
	)
	(segment
		(start 211.23765 163.51265)
		(end 210.9859 163.51265)
		(width 0.184)
		(layer "F.Cu")
		(net 900)
	)
	(segment
		(start 211.625 163.9)
		(end 211.23765 163.51265)
		(width 0.184)
		(layer "F.Cu")
		(net 900)
	)
	(segment
		(start 211.9 164.65)
		(end 211.625 164.375)
		(width 0.184)
		(layer "F.Cu")
		(net 900)
	)
	(segment
		(start 213.9 155.6)
		(end 214.05 155.75)
		(width 0.184)
		(layer "F.Cu")
		(net 901)
	)
	(segment
		(start 214.05 155.75)
		(end 214.05 156.5)
		(width 0.184)
		(layer "F.Cu")
		(net 901)
	)
	(segment
		(start 213.9 155.195)
		(end 213.9 155.6)
		(width 0.184)
		(layer "F.Cu")
		(net 901)
	)
	(segment
		(start 214.05 156.5)
		(end 213.94265 156.60735)
		(width 0.184)
		(layer "F.Cu")
		(net 901)
	)
	(segment
		(start 213.94265 156.60735)
		(end 213.525 156.60735)
		(width 0.184)
		(layer "F.Cu")
		(net 901)
	)
	(segment
		(start 215.47235 156.60735)
		(end 214.7909 156.60735)
		(width 0.184)
		(layer "F.Cu")
		(net 902)
	)
	(segment
		(start 216.45 157.585)
		(end 215.47235 156.60735)
		(width 0.184)
		(layer "F.Cu")
		(net 902)
	)
	(segment
		(start 212.58765 163.51265)
		(end 212.2709 163.51265)
		(width 0.184)
		(layer "F.Cu")
		(net 903)
	)
	(segment
		(start 212.9 164.915)
		(end 212.9 163.825)
		(width 0.184)
		(layer "F.Cu")
		(net 903)
	)
	(segment
		(start 212.9 163.825)
		(end 212.58765 163.51265)
		(width 0.184)
		(layer "F.Cu")
		(net 903)
	)
	(segment
		(start 214.2 164.325)
		(end 214.2 163.775)
		(width 0.184)
		(layer "F.Cu")
		(net 904)
	)
	(segment
		(start 213.93765 163.51265)
		(end 213.525 163.51265)
		(width 0.184)
		(layer "F.Cu")
		(net 904)
	)
	(segment
		(start 214.9 164.915)
		(end 214.79 164.915)
		(width 0.184)
		(layer "F.Cu")
		(net 904)
	)
	(segment
		(start 214.79 164.915)
		(end 214.2 164.325)
		(width 0.184)
		(layer "F.Cu")
		(net 904)
	)
	(segment
		(start 214.2 163.775)
		(end 213.93765 163.51265)
		(width 0.184)
		(layer "F.Cu")
		(net 904)
	)
	(segment
		(start 211.7 156.5)
		(end 211.7 155.9)
		(width 0.184)
		(layer "F.Cu")
		(net 905)
	)
	(segment
		(start 211.9 155.7)
		(end 211.9 155.195)
		(width 0.184)
		(layer "F.Cu")
		(net 905)
	)
	(segment
		(start 211.80735 156.60735)
		(end 211.7 156.5)
		(width 0.184)
		(layer "F.Cu")
		(net 905)
	)
	(segment
		(start 212.255 156.60735)
		(end 211.80735 156.60735)
		(width 0.184)
		(layer "F.Cu")
		(net 905)
	)
	(segment
		(start 211.7 155.9)
		(end 211.9 155.7)
		(width 0.184)
		(layer "F.Cu")
		(net 905)
	)
	(segment
		(start 226 112.2)
		(end 226.2 112)
		(width 0.184)
		(layer "F.Cu")
		(net 906)
	)
	(segment
		(start 227.02235 111.87765)
		(end 227.02235 111.2459)
		(width 0.184)
		(layer "F.Cu")
		(net 906)
	)
	(segment
		(start 225.585 112.2)
		(end 226 112.2)
		(width 0.184)
		(layer "F.Cu")
		(net 906)
	)
	(segment
		(start 226.9 112)
		(end 227.02235 111.87765)
		(width 0.184)
		(layer "F.Cu")
		(net 906)
	)
	(segment
		(start 226.2 112)
		(end 226.9 112)
		(width 0.184)
		(layer "F.Cu")
		(net 906)
	)
	(segment
		(start 233.92765 113.785)
		(end 235.23 113.785)
		(width 0.184)
		(layer "F.Cu")
		(net 907)
	)
	(segment
		(start 235.23 113.785)
		(end 235.415 113.6)
		(width 0.184)
		(layer "F.Cu")
		(net 907)
	)
	(segment
		(start 233.92765 115.0509)
		(end 234.9159 115.0509)
		(width 0.184)
		(layer "F.Cu")
		(net 908)
	)
	(segment
		(start 234.9159 115.0509)
		(end 235.415 115.55)
		(width 0.184)
		(layer "F.Cu")
		(net 908)
	)
	(segment
		(start 226.9 113.2)
		(end 227.02235 113.07765)
		(width 0.184)
		(layer "F.Cu")
		(net 909)
	)
	(segment
		(start 227.02235 113.07765)
		(end 227.02235 112.5309)
		(width 0.184)
		(layer "F.Cu")
		(net 909)
	)
	(segment
		(start 225.585 113.2)
		(end 226.9 113.2)
		(width 0.184)
		(layer "F.Cu")
		(net 909)
	)
	(segment
		(start 226.2 114.6)
		(end 226.9 114.6)
		(width 0.184)
		(layer "F.Cu")
		(net 910)
	)
	(segment
		(start 225.6 115.2)
		(end 226.2 114.6)
		(width 0.184)
		(layer "F.Cu")
		(net 910)
	)
	(segment
		(start 225.585 115.2)
		(end 225.6 115.2)
		(width 0.184)
		(layer "F.Cu")
		(net 910)
	)
	(segment
		(start 227.02235 114.47765)
		(end 227.02235 113.785)
		(width 0.184)
		(layer "F.Cu")
		(net 910)
	)
	(segment
		(start 226.9 114.6)
		(end 227.02235 114.47765)
		(width 0.184)
		(layer "F.Cu")
		(net 910)
	)
	(segment
		(start 234.525 112.515)
		(end 235.415 111.625)
		(width 0.184)
		(layer "F.Cu")
		(net 911)
	)
	(segment
		(start 233.92765 112.515)
		(end 234.525 112.515)
		(width 0.184)
		(layer "F.Cu")
		(net 911)
	)
	(segment
		(start 233.5 112.63)
		(end 234.45 112.63)
		(width 0.1)
		(layer "F.Cu")
		(net 911)
	)
	(segment
		(start 263.1 137.45)
		(end 264.665 139.015)
		(width 0.182)
		(layer "F.Cu")
		(net 912)
	)
	(segment
		(start 263.1 135.9)
		(end 263.1 137.45)
		(width 0.182)
		(layer "F.Cu")
		(net 912)
	)
	(segment
		(start 264.665 139.015)
		(end 264.7 139.015)
		(width 0.182)
		(layer "F.Cu")
		(net 912)
	)
	(segment
		(start 263.915 137.115)
		(end 264.7 137.115)
		(width 0.182)
		(layer "F.Cu")
		(net 913)
	)
	(segment
		(start 263.65 135.35)
		(end 263.65 136.85)
		(width 0.182)
		(layer "F.Cu")
		(net 913)
	)
	(segment
		(start 263.65 136.85)
		(end 263.915 137.115)
		(width 0.182)
		(layer "F.Cu")
		(net 913)
	)
	(segment
		(start 263.65 134.95)
		(end 264.535 134.95)
		(width 0.182)
		(layer "F.Cu")
		(net 914)
	)
	(segment
		(start 264.535 134.95)
		(end 264.7 135.115)
		(width 0.182)
		(layer "F.Cu")
		(net 914)
	)
	(segment
		(start 264.335 134.55)
		(end 264.7 134.185)
		(width 0.182)
		(layer "F.Cu")
		(net 915)
	)
	(segment
		(start 263.65 134.55)
		(end 264.335 134.55)
		(width 0.182)
		(layer "F.Cu")
		(net 915)
	)
	(segment
		(start 199.1525 108.9875)
		(end 199.415 109.25)
		(width 0.198)
		(layer "F.Cu")
		(net 916)
	)
	(segment
		(start 198.437501 109)
		(end 198.450001 108.9875)
		(width 0.198)
		(layer "F.Cu")
		(net 916)
	)
	(segment
		(start 198.450001 108.9875)
		(end 199.1525 108.9875)
		(width 0.198)
		(layer "F.Cu")
		(net 916)
	)
	(segment
		(start 197.8 109)
		(end 198.437501 109)
		(width 0.198)
		(layer "F.Cu")
		(net 916)
	)
	(segment
		(start 197.8 108.5)
		(end 198.437501 108.5)
		(width 0.198)
		(layer "F.Cu")
		(net 917)
	)
	(segment
		(start 198.437501 108.5)
		(end 198.450001 108.5125)
		(width 0.198)
		(layer "F.Cu")
		(net 917)
	)
	(segment
		(start 198.450001 108.5125)
		(end 199.1525 108.5125)
		(width 0.198)
		(layer "F.Cu")
		(net 917)
	)
	(segment
		(start 199.1525 108.5125)
		(end 199.415 108.25)
		(width 0.198)
		(layer "F.Cu")
		(net 917)
	)
	(segment
		(start 250.7 139.8875)
		(end 250.65 139.8375)
		(width 0.1)
		(layer "F.Cu")
		(net 918)
	)
	(segment
		(start 250.7 141.4)
		(end 250.7 139.8875)
		(width 0.1)
		(layer "F.Cu")
		(net 918)
	)
	(segment
		(start 251.05 141.75)
		(end 250.7 141.4)
		(width 0.1)
		(layer "F.Cu")
		(net 918)
	)
	(segment
		(start 261.35 134.15)
		(end 261.35 133.7)
		(width 0.1)
		(layer "F.Cu")
		(net 918)
	)
	(segment
		(start 261.35 134.15)
		(end 260.335 134.15)
		(width 0.1)
		(layer "F.Cu")
		(net 918)
	)
	(segment
		(start 260.335 134.15)
		(end 260.3 134.185)
		(width 0.1)
		(layer "F.Cu")
		(net 918)
	)
	(segment
		(start 252.125 141.75)
		(end 251.05 141.75)
		(width 0.1)
		(layer "F.Cu")
		(net 918)
	)
	(segment
		(start 261.35 133.7)
		(end 261.375 133.675)
		(width 0.1)
		(layer "F.Cu")
		(net 918)
	)
	(via
		(at 261.375 133.675)
		(size 0.45)
		(drill 0.2)
		(layers "F.Cu" "B.Cu")
		(net 918)
	)
	(via
		(at 252.125 141.75)
		(size 0.45)
		(drill 0.2)
		(layers "F.Cu" "B.Cu")
		(net 918)
	)
	(segment
		(start 261.2 133.85)
		(end 261.2 134.9)
		(width 0.1)
		(layer "In3.Cu")
		(net 918)
	)
	(segment
		(start 259.5 141.4)
		(end 252.475 141.4)
		(width 0.1)
		(layer "In3.Cu")
		(net 918)
	)
	(segment
		(start 252.475 141.4)
		(end 252.125 141.75)
		(width 0.1)
		(layer "In3.Cu")
		(net 918)
	)
	(segment
		(start 260.9 140)
		(end 259.5 141.4)
		(width 0.1)
		(layer "In3.Cu")
		(net 918)
	)
	(segment
		(start 261.375 133.675)
		(end 261.2 133.85)
		(width 0.1)
		(layer "In3.Cu")
		(net 918)
	)
	(segment
		(start 261.2 134.9)
		(end 260.9 135.2)
		(width 0.1)
		(layer "In3.Cu")
		(net 918)
	)
	(segment
		(start 260.9 135.2)
		(end 260.9 140)
		(width 0.1)
		(layer "In3.Cu")
		(net 918)
	)
	(segment
		(start 252.975 133.925)
		(end 253.87 133.925)
		(width 0.1)
		(layer "F.Cu")
		(net 919)
	)
	(segment
		(start 252.75 134.15)
		(end 252.975 133.925)
		(width 0.1)
		(layer "F.Cu")
		(net 919)
	)
	(segment
		(start 252.3375 134.15)
		(end 252.75 134.15)
		(width 0.1)
		(layer "F.Cu")
		(net 919)
	)
	(segment
		(start 253.87 133.925)
		(end 253.96 133.835)
		(width 0.1)
		(layer "F.Cu")
		(net 919)
	)
	(segment
		(start 252.3375 136.65)
		(end 253.775 136.65)
		(width 0.198)
		(layer "F.Cu")
		(net 920)
	)
	(segment
		(start 253.775 136.65)
		(end 253.96 136.835)
		(width 0.198)
		(layer "F.Cu")
		(net 920)
	)
	(segment
		(start 244.4625 134.15)
		(end 243.7 134.15)
		(width 0.1)
		(layer "F.Cu")
		(net 921)
	)
	(segment
		(start 243.7 134.15)
		(end 243.65 134.1)
		(width 0.1)
		(layer "F.Cu")
		(net 921)
	)
	(via
		(at 243.65 134.1)
		(size 0.45)
		(drill 0.2)
		(layers "F.Cu" "B.Cu")
		(net 921)
	)
	(segment
		(start 242.55 134.4)
		(end 243.35 134.4)
		(width 0.1)
		(layer "B.Cu")
		(net 921)
	)
	(segment
		(start 242.015 133.9)
		(end 242.05 133.9)
		(width 0.1)
		(layer "B.Cu")
		(net 921)
	)
	(segment
		(start 243.35 134.4)
		(end 243.65 134.1)
		(width 0.1)
		(layer "B.Cu")
		(net 921)
	)
	(segment
		(start 242.05 133.9)
		(end 242.55 134.4)
		(width 0.1)
		(layer "B.Cu")
		(net 921)
	)
	(segment
		(start 244.4625 134.65)
		(end 243.95 134.65)
		(width 0.1)
		(layer "F.Cu")
		(net 922)
	)
	(segment
		(start 243.95 134.65)
		(end 243.7 134.9)
		(width 0.1)
		(layer "F.Cu")
		(net 922)
	)
	(via
		(at 243.7 134.9)
		(size 0.45)
		(drill 0.2)
		(layers "F.Cu" "B.Cu")
		(net 922)
	)
	(segment
		(start 243.5 135.45)
		(end 243.7 135.25)
		(width 0.1)
		(layer "B.Cu")
		(net 922)
	)
	(segment
		(start 242.015 135.015)
		(end 242.45 135.45)
		(width 0.1)
		(layer "B.Cu")
		(net 922)
	)
	(segment
		(start 243.7 135.25)
		(end 243.7 134.9)
		(width 0.1)
		(layer "B.Cu")
		(net 922)
	)
	(segment
		(start 242.45 135.45)
		(end 243.5 135.45)
		(width 0.1)
		(layer "B.Cu")
		(net 922)
	)
	(segment
		(start 242.015 134.9)
		(end 242.015 135.015)
		(width 0.1)
		(layer "B.Cu")
		(net 922)
	)
	(segment
		(start 244.15 139.15)
		(end 243.55 138.55)
		(width 0.1)
		(layer "F.Cu")
		(net 923)
	)
	(segment
		(start 244.4625 139.15)
		(end 244.15 139.15)
		(width 0.1)
		(layer "F.Cu")
		(net 923)
	)
	(via
		(at 243.55 138.55)
		(size 0.45)
		(drill 0.2)
		(layers "F.Cu" "B.Cu")
		(net 923)
	)
	(segment
		(start 243 139.1)
		(end 242.985 139.1)
		(width 0.1)
		(layer "B.Cu")
		(net 923)
	)
	(segment
		(start 243.55 138.55)
		(end 243 139.1)
		(width 0.1)
		(layer "B.Cu")
		(net 923)
	)
	(segment
		(start 246.65 139.8375)
		(end 246.65 141.065)
		(width 0.1)
		(layer "F.Cu")
		(net 924)
	)
	(segment
		(start 246.65 141.065)
		(end 246.6 141.115)
		(width 0.1)
		(layer "F.Cu")
		(net 924)
	)
	(segment
		(start 246.75 130.9)
		(end 246.75 131.8625)
		(width 0.1)
		(layer "F.Cu")
		(net 925)
	)
	(segment
		(start 242.3 137.3)
		(end 242.3 143.68)
		(width 0.1)
		(layer "F.Cu")
		(net 925)
	)
	(segment
		(start 239.685 134.215)
		(end 239.7 134.2)
		(width 0.1)
		(layer "F.Cu")
		(net 925)
	)
	(segment
		(start 241.68 144.3)
		(end 241.28 144.7)
		(width 0.1)
		(layer "F.Cu")
		(net 925)
	)
	(segment
		(start 243.65 130.725)
		(end 246.575 130.725)
		(width 0.1)
		(layer "F.Cu")
		(net 925)
	)
	(segment
		(start 239 134.215)
		(end 239.685 134.215)
		(width 0.1)
		(layer "F.Cu")
		(net 925)
	)
	(segment
		(start 242.3 143.68)
		(end 241.68 144.3)
		(width 0.1)
		(layer "F.Cu")
		(net 925)
	)
	(segment
		(start 246.75 131.8625)
		(end 246.65 131.9625)
		(width 0.1)
		(layer "F.Cu")
		(net 925)
	)
	(segment
		(start 246.575 130.725)
		(end 246.75 130.9)
		(width 0.1)
		(layer "F.Cu")
		(net 925)
	)
	(segment
		(start 242.275 133.01)
		(end 242.16 132.895)
		(width 0.1)
		(layer "F.Cu")
		(net 925)
	)
	(segment
		(start 242.16 132.895)
		(end 242.16 132.215)
		(width 0.1)
		(layer "F.Cu")
		(net 925)
	)
	(segment
		(start 242.275 133.01)
		(end 242.6 133.335)
		(width 0.1)
		(layer "F.Cu")
		(net 925)
	)
	(segment
		(start 242.6 137)
		(end 242.3 137.3)
		(width 0.1)
		(layer "F.Cu")
		(net 925)
	)
	(segment
		(start 242.16 132.215)
		(end 243.65 130.725)
		(width 0.1)
		(layer "F.Cu")
		(net 925)
	)
	(segment
		(start 242.6 133.335)
		(end 242.6 137)
		(width 0.1)
		(layer "F.Cu")
		(net 925)
	)
	(segment
		(start 241.28 144.7)
		(end 240.5 144.7)
		(width 0.1)
		(layer "F.Cu")
		(net 925)
	)
	(via
		(at 241.68 144.3)
		(size 0.45)
		(drill 0.2)
		(layers "F.Cu" "B.Cu")
		(net 925)
	)
	(via
		(at 242.275 133.01)
		(size 0.45)
		(drill 0.2)
		(layers "F.Cu" "B.Cu")
		(net 925)
	)
	(via
		(at 239.7 134.2)
		(size 0.45)
		(drill 0.2)
		(layers "F.Cu" "B.Cu")
		(net 925)
	)
	(segment
		(start 241.1 134.2)
		(end 239.7 134.2)
		(width 0.1)
		(layer "B.Cu")
		(net 925)
	)
	(segment
		(start 241.4 133.3)
		(end 241.4 133.9)
		(width 0.1)
		(layer "B.Cu")
		(net 925)
	)
	(segment
		(start 241.9 144.3)
		(end 242.3 143.9)
		(width 0.1)
		(layer "B.Cu")
		(net 925)
	)
	(segment
		(start 241.4 133.9)
		(end 241.1 134.2)
		(width 0.1)
		(layer "B.Cu")
		(net 925)
	)
	(segment
		(start 242.275 133.01)
		(end 241.69 133.01)
		(width 0.1)
		(layer "B.Cu")
		(net 925)
	)
	(segment
		(start 241.69 133.01)
		(end 241.4 133.3)
		(width 0.1)
		(layer "B.Cu")
		(net 925)
	)
	(segment
		(start 241.68 144.3)
		(end 241.9 144.3)
		(width 0.1)
		(layer "B.Cu")
		(net 925)
	)
	(segment
		(start 242.3 143.9)
		(end 242.3 143.635)
		(width 0.1)
		(layer "B.Cu")
		(net 925)
	)
	(segment
		(start 233.5 146.65)
		(end 233.375 146.525)
		(width 0.1)
		(layer "F.Cu")
		(net 926)
	)
	(segment
		(start 233.5 147.2)
		(end 233.5 146.65)
		(width 0.1)
		(layer "F.Cu")
		(net 926)
	)
	(via
		(at 251.71 125.48)
		(size 0.45)
		(drill 0.2)
		(layers "F.Cu" "B.Cu")
		(net 926)
	)
	(via
		(at 255.83 144.16)
		(size 0.45)
		(drill 0.2)
		(layers "F.Cu" "B.Cu")
		(net 926)
	)
	(via
		(at 265.525 128.475)
		(size 0.45)
		(drill 0.2)
		(layers "F.Cu" "B.Cu")
		(net 926)
	)
	(via
		(at 233.375 146.525)
		(size 0.45)
		(drill 0.2)
		(layers "F.Cu" "B.Cu")
		(net 926)
	)
	(via
		(at 254.26 130.51)
		(size 0.45)
		(drill 0.2)
		(layers "F.Cu" "B.Cu")
		(net 926)
	)
	(segment
		(start 266.025 127.975)
		(end 265.525 128.475)
		(width 0.1)
		(layer "B.Cu")
		(net 926)
	)
	(segment
		(start 266.025 127.125)
		(end 266.025 127.975)
		(width 0.1)
		(layer "B.Cu")
		(net 926)
	)
	(segment
		(start 256.09 144.16)
		(end 257.25 143)
		(width 0.1)
		(layer "B.Cu")
		(net 926)
	)
	(segment
		(start 266.485 126.7)
		(end 266.45 126.7)
		(width 0.1)
		(layer "B.Cu")
		(net 926)
	)
	(segment
		(start 266.485 125.7)
		(end 266.485 126.7)
		(width 0.1)
		(layer "B.Cu")
		(net 926)
	)
	(segment
		(start 254.55 132)
		(end 254.55 130.8)
		(width 0.1)
		(layer "B.Cu")
		(net 926)
	)
	(segment
		(start 256 133.45)
		(end 254.55 132)
		(width 0.1)
		(layer "B.Cu")
		(net 926)
	)
	(segment
		(start 266.45 126.7)
		(end 266.025 127.125)
		(width 0.1)
		(layer "B.Cu")
		(net 926)
	)
	(segment
		(start 254.55 130.8)
		(end 254.26 130.51)
		(width 0.1)
		(layer "B.Cu")
		(net 926)
	)
	(segment
		(start 257.25 143)
		(end 257.25 139.425)
		(width 0.1)
		(layer "B.Cu")
		(net 926)
	)
	(segment
		(start 255.83 144.16)
		(end 256.09 144.16)
		(width 0.1)
		(layer "B.Cu")
		(net 926)
	)
	(segment
		(start 257.25 139.425)
		(end 256 138.175)
		(width 0.1)
		(layer "B.Cu")
		(net 926)
	)
	(segment
		(start 256 138.175)
		(end 256 133.45)
		(width 0.1)
		(layer "B.Cu")
		(net 926)
	)
	(segment
		(start 263.65 126.175)
		(end 265.175 126.175)
		(width 0.1)
		(layer "In3.Cu")
		(net 926)
	)
	(segment
		(start 251.71 125.48)
		(end 251.715 125.475)
		(width 0.1)
		(layer "In3.Cu")
		(net 926)
	)
	(segment
		(start 265.425 128.375)
		(end 265.525 128.475)
		(width 0.1)
		(layer "In3.Cu")
		(net 926)
	)
	(segment
		(start 251.715 125.475)
		(end 262.95 125.475)
		(width 0.1)
		(layer "In3.Cu")
		(net 926)
	)
	(segment
		(start 265.425 126.425)
		(end 265.425 128.375)
		(width 0.1)
		(layer "In3.Cu")
		(net 926)
	)
	(segment
		(start 265.175 126.175)
		(end 265.425 126.425)
		(width 0.1)
		(layer "In3.Cu")
		(net 926)
	)
	(segment
		(start 262.95 125.475)
		(end 263.65 126.175)
		(width 0.1)
		(layer "In3.Cu")
		(net 926)
	)
	(segment
		(start 256.07 147.4)
		(end 256.07 144.4)
		(width 0.1)
		(layer "In5.Cu")
		(net 926)
	)
	(segment
		(start 255.1 129.67)
		(end 255.1 127.09)
		(width 0.1)
		(layer "In5.Cu")
		(net 926)
	)
	(segment
		(start 233.375 144.675)
		(end 235.9 142.15)
		(width 0.1)
		(layer "In5.Cu")
		(net 926)
	)
	(segment
		(start 249.4 147.87)
		(end 249.4 148.55)
		(width 0.1)
		(layer "In5.Cu")
		(net 926)
	)
	(segment
		(start 249.93 149.08)
		(end 254.39 149.08)
		(width 0.1)
		(layer "In5.Cu")
		(net 926)
	)
	(segment
		(start 235.9 142.15)
		(end 243.68 142.15)
		(width 0.1)
		(layer "In5.Cu")
		(net 926)
	)
	(segment
		(start 253.49 125.48)
		(end 255.1 127.09)
		(width 0.1)
		(layer "In5.Cu")
		(net 926)
	)
	(segment
		(start 253.49 125.48)
		(end 251.71 125.48)
		(width 0.1)
		(layer "In5.Cu")
		(net 926)
	)
	(segment
		(start 243.68 142.15)
		(end 249.4 147.87)
		(width 0.1)
		(layer "In5.Cu")
		(net 926)
	)
	(segment
		(start 249.4 148.55)
		(end 249.93 149.08)
		(width 0.1)
		(layer "In5.Cu")
		(net 926)
	)
	(segment
		(start 256.07 144.4)
		(end 255.83 144.16)
		(width 0.1)
		(layer "In5.Cu")
		(net 926)
	)
	(segment
		(start 254.39 149.08)
		(end 256.07 147.4)
		(width 0.1)
		(layer "In5.Cu")
		(net 926)
	)
	(segment
		(start 254.26 130.51)
		(end 255.1 129.67)
		(width 0.1)
		(layer "In5.Cu")
		(net 926)
	)
	(segment
		(start 233.375 146.525)
		(end 233.375 144.675)
		(width 0.1)
		(layer "In5.Cu")
		(net 926)
	)
	(segment
		(start 235.792966 149.178842)
		(end 235.792966 149.357034)
		(width 0.198)
		(layer "F.Cu")
		(net 927)
	)
	(segment
		(start 234.5375 149.0375)
		(end 235.651624 149.0375)
		(width 0.198)
		(layer "F.Cu")
		(net 927)
	)
	(segment
		(start 258.8525 126.7625)
		(end 258.45577 126.7625)
		(width 0.198)
		(layer "F.Cu")
		(net 927)
	)
	(segment
		(start 258.45577 126.7625)
		(end 258.32977 126.6365)
		(width 0.198)
		(layer "F.Cu")
		(net 927)
	)
	(segment
		(start 259.115 126.5)
		(end 258.8525 126.7625)
		(width 0.198)
		(layer "F.Cu")
		(net 927)
	)
	(segment
		(start 235.651624 149.0375)
		(end 235.792966 149.178842)
		(width 0.198)
		(layer "F.Cu")
		(net 927)
	)
	(segment
		(start 234.5 149)
		(end 234.5375 149.0375)
		(width 0.198)
		(layer "F.Cu")
		(net 927)
	)
	(via
		(at 258.32977 126.6365)
		(size 0.45)
		(drill 0.2)
		(layers "F.Cu" "B.Cu")
		(net 927)
	)
	(via
		(at 235.792966 149.357034)
		(size 0.45)
		(drill 0.2)
		(layers "F.Cu" "B.Cu")
		(net 927)
	)
	(segment
		(start 258.7605 154.751838)
		(end 258.7605 143.998162)
		(width 0.198)
		(layer "In7.Cu")
		(net 927)
	)
	(segment
		(start 258.1355 135.876838)
		(end 258.1355 133.051838)
		(width 0.198)
		(layer "In7.Cu")
		(net 927)
	)
	(segment
		(start 257.076838 156.4355)
		(end 258.7605 154.751838)
		(width 0.198)
		(layer "In7.Cu")
		(net 927)
	)
	(segment
		(start 258.1355 133.051838)
		(end 260.1105 131.076838)
		(width 0.198)
		(layer "In7.Cu")
		(net 927)
	)
	(segment
		(start 258.50777 126.8145)
		(end 258.32977 126.6365)
		(width 0.198)
		(layer "In7.Cu")
		(net 927)
	)
	(segment
		(start 258.7605 143.998162)
		(end 255.7355 140.973162)
		(width 0.198)
		(layer "In7.Cu")
		(net 927)
	)
	(segment
		(start 260.1105 127.673162)
		(end 259.251838 126.8145)
		(width 0.198)
		(layer "In7.Cu")
		(net 927)
	)
	(segment
		(start 255.7355 138.276838)
		(end 258.1355 135.876838)
		(width 0.198)
		(layer "In7.Cu")
		(net 927)
	)
	(segment
		(start 237.7645 154.636838)
		(end 239.563162 156.4355)
		(width 0.198)
		(layer "In7.Cu")
		(net 927)
	)
	(segment
		(start 259.251838 126.8145)
		(end 258.50777 126.8145)
		(width 0.198)
		(layer "In7.Cu")
		(net 927)
	)
	(segment
		(start 237.7645 151.076837)
		(end 237.7645 154.636838)
		(width 0.198)
		(layer "In7.Cu")
		(net 927)
	)
	(segment
		(start 239.563162 156.4355)
		(end 257.076838 156.4355)
		(width 0.198)
		(layer "In7.Cu")
		(net 927)
	)
	(segment
		(start 260.1105 131.076838)
		(end 260.1105 127.673162)
		(width 0.198)
		(layer "In7.Cu")
		(net 927)
	)
	(segment
		(start 235.792966 149.357034)
		(end 236.044697 149.357034)
		(width 0.198)
		(layer "In7.Cu")
		(net 927)
	)
	(segment
		(start 236.044697 149.357034)
		(end 237.7645 151.076837)
		(width 0.198)
		(layer "In7.Cu")
		(net 927)
	)
	(segment
		(start 255.7355 140.973162)
		(end 255.7355 138.276838)
		(width 0.198)
		(layer "In7.Cu")
		(net 927)
	)
	(segment
		(start 234.5 148.6)
		(end 234.5375 148.5625)
		(width 0.198)
		(layer "F.Cu")
		(net 928)
	)
	(segment
		(start 236.128842 148.842966)
		(end 236.307034 148.842966)
		(width 0.198)
		(layer "F.Cu")
		(net 928)
	)
	(segment
		(start 235.848376 148.5625)
		(end 236.128842 148.842966)
		(width 0.198)
		(layer "F.Cu")
		(net 928)
	)
	(segment
		(start 258.8525 127.2375)
		(end 258.45577 127.2375)
		(width 0.198)
		(layer "F.Cu")
		(net 928)
	)
	(segment
		(start 259.115 127.5)
		(end 258.8525 127.2375)
		(width 0.198)
		(layer "F.Cu")
		(net 928)
	)
	(segment
		(start 258.45577 127.2375)
		(end 258.32977 127.3635)
		(width 0.198)
		(layer "F.Cu")
		(net 928)
	)
	(segment
		(start 234.5375 148.5625)
		(end 235.848376 148.5625)
		(width 0.198)
		(layer "F.Cu")
		(net 928)
	)
	(via
		(at 236.307034 148.842966)
		(size 0.45)
		(drill 0.2)
		(layers "F.Cu" "B.Cu")
		(net 928)
	)
	(via
		(at 258.32977 127.3635)
		(size 0.45)
		(drill 0.2)
		(layers "F.Cu" "B.Cu")
		(net 928)
	)
	(segment
		(start 238.1355 154.483162)
		(end 239.716838 156.0645)
		(width 0.198)
		(layer "In7.Cu")
		(net 928)
	)
	(segment
		(start 258.3895 144.151838)
		(end 255.3645 141.126838)
		(width 0.198)
		(layer "In7.Cu")
		(net 928)
	)
	(segment
		(start 258.50777 127.1855)
		(end 258.32977 127.3635)
		(width 0.198)
		(layer "In7.Cu")
		(net 928)
	)
	(segment
		(start 259.7395 130.923162)
		(end 259.7395 127.826838)
		(width 0.198)
		(layer "In7.Cu")
		(net 928)
	)
	(segment
		(start 255.3645 138.123162)
		(end 257.7645 135.723162)
		(width 0.198)
		(layer "In7.Cu")
		(net 928)
	)
	(segment
		(start 239.716838 156.0645)
		(end 256.923162 156.0645)
		(width 0.198)
		(layer "In7.Cu")
		(net 928)
	)
	(segment
		(start 236.307034 149.094697)
		(end 238.1355 150.923163)
		(width 0.198)
		(layer "In7.Cu")
		(net 928)
	)
	(segment
		(start 257.7645 132.898162)
		(end 259.7395 130.923162)
		(width 0.198)
		(layer "In7.Cu")
		(net 928)
	)
	(segment
		(start 236.307034 148.842966)
		(end 236.307034 149.094697)
		(width 0.198)
		(layer "In7.Cu")
		(net 928)
	)
	(segment
		(start 258.3895 154.598162)
		(end 258.3895 144.151838)
		(width 0.198)
		(layer "In7.Cu")
		(net 928)
	)
	(segment
		(start 259.098162 127.1855)
		(end 258.50777 127.1855)
		(width 0.198)
		(layer "In7.Cu")
		(net 928)
	)
	(segment
		(start 238.1355 150.923163)
		(end 238.1355 154.483162)
		(width 0.198)
		(layer "In7.Cu")
		(net 928)
	)
	(segment
		(start 255.3645 141.126838)
		(end 255.3645 138.123162)
		(width 0.198)
		(layer "In7.Cu")
		(net 928)
	)
	(segment
		(start 256.923162 156.0645)
		(end 258.3895 154.598162)
		(width 0.198)
		(layer "In7.Cu")
		(net 928)
	)
	(segment
		(start 259.7395 127.826838)
		(end 259.098162 127.1855)
		(width 0.198)
		(layer "In7.Cu")
		(net 928)
	)
	(segment
		(start 257.7645 135.723162)
		(end 257.7645 132.898162)
		(width 0.198)
		(layer "In7.Cu")
		(net 928)
	)
	(segment
		(start 237.65 141.215)
		(end 237.65 140.7)
		(width 0.1)
		(layer "F.Cu")
		(net 934)
	)
	(segment
		(start 237.075 139.425)
		(end 237.05 139.45)
		(width 0.1)
		(layer "F.Cu")
		(net 934)
	)
	(segment
		(start 243.75 130.925)
		(end 244.4 130.925)
		(width 0.1)
		(layer "F.Cu")
		(net 934)
	)
	(segment
		(start 237.525 139.95)
		(end 237.525 139.5)
		(width 0.1)
		(layer "F.Cu")
		(net 934)
	)
	(segment
		(start 244.525 131.05)
		(end 245.725 131.05)
		(width 0.1)
		(layer "F.Cu")
		(net 934)
	)
	(segment
		(start 242.664783 132.47768)
		(end 242.8 132.342463)
		(width 0.1)
		(layer "F.Cu")
		(net 934)
	)
	(segment
		(start 237.5 139.975)
		(end 237.525 139.95)
		(width 0.1)
		(layer "F.Cu")
		(net 934)
	)
	(segment
		(start 237.5 140.55)
		(end 237.5 139.975)
		(width 0.1)
		(layer "F.Cu")
		(net 934)
	)
	(segment
		(start 237.65 140.7)
		(end 237.5 140.55)
		(width 0.1)
		(layer "F.Cu")
		(net 934)
	)
	(segment
		(start 242.8 132.342463)
		(end 242.8 131.875)
		(width 0.1)
		(layer "F.Cu")
		(net 934)
	)
	(segment
		(start 237.525 139.5)
		(end 237.45 139.425)
		(width 0.1)
		(layer "F.Cu")
		(net 934)
	)
	(segment
		(start 245.85 131.175)
		(end 245.85 131.275)
		(width 0.1)
		(layer "F.Cu")
		(net 934)
	)
	(segment
		(start 245.725 131.05)
		(end 245.85 131.175)
		(width 0.1)
		(layer "F.Cu")
		(net 934)
	)
	(segment
		(start 242.8 131.875)
		(end 243.75 130.925)
		(width 0.1)
		(layer "F.Cu")
		(net 934)
	)
	(segment
		(start 245.85 131.275)
		(end 246.15 131.575)
		(width 0.1)
		(layer "F.Cu")
		(net 934)
	)
	(segment
		(start 244.4 130.925)
		(end 244.525 131.05)
		(width 0.1)
		(layer "F.Cu")
		(net 934)
	)
	(segment
		(start 246.15 131.575)
		(end 246.15 131.9625)
		(width 0.1)
		(layer "F.Cu")
		(net 934)
	)
	(segment
		(start 237.45 139.425)
		(end 237.075 139.425)
		(width 0.1)
		(layer "F.Cu")
		(net 934)
	)
	(via
		(at 242.664783 132.47768)
		(size 0.45)
		(drill 0.2)
		(layers "F.Cu" "B.Cu")
		(net 934)
	)
	(via
		(at 237.05 139.45)
		(size 0.45)
		(drill 0.2)
		(layers "F.Cu" "B.Cu")
		(net 934)
	)
	(segment
		(start 237.975 140.025)
		(end 237.4 139.45)
		(width 0.1)
		(layer "In3.Cu")
		(net 934)
	)
	(segment
		(start 237.4 139.45)
		(end 237.05 139.45)
		(width 0.1)
		(layer "In3.Cu")
		(net 934)
	)
	(segment
		(start 242.983011 132.47768)
		(end 244.15 133.644669)
		(width 0.1)
		(layer "In3.Cu")
		(net 934)
	)
	(segment
		(start 242.664783 132.47768)
		(end 242.983011 132.47768)
		(width 0.1)
		(layer "In3.Cu")
		(net 934)
	)
	(segment
		(start 242.675 140.025)
		(end 237.975 140.025)
		(width 0.1)
		(layer "In3.Cu")
		(net 934)
	)
	(segment
		(start 243.425 139.275)
		(end 242.675 140.025)
		(width 0.1)
		(layer "In3.Cu")
		(net 934)
	)
	(segment
		(start 244.15 139.075)
		(end 243.95 139.275)
		(width 0.1)
		(layer "In3.Cu")
		(net 934)
	)
	(segment
		(start 244.15 133.644669)
		(end 244.15 139.075)
		(width 0.1)
		(layer "In3.Cu")
		(net 934)
	)
	(segment
		(start 243.95 139.275)
		(end 243.425 139.275)
		(width 0.1)
		(layer "In3.Cu")
		(net 934)
	)
	(segment
		(start 200.9 112.5)
		(end 197.7 112.5)
		(width 0.184)
		(layer "F.Cu")
		(net 938)
	)
	(segment
		(start 202 114)
		(end 202 113.6)
		(width 0.184)
		(layer "F.Cu")
		(net 938)
	)
	(segment
		(start 202 117)
		(end 202 114)
		(width 0.182)
		(layer "F.Cu")
		(net 938)
	)
	(segment
		(start 201.5 117.5)
		(end 202 117)
		(width 0.182)
		(layer "F.Cu")
		(net 938)
	)
	(segment
		(start 202 113.6)
		(end 200.9 112.5)
		(width 0.184)
		(layer "F.Cu")
		(net 938)
	)
	(segment
		(start 197.7 112.5)
		(end 197.075 111.875)
		(width 0.184)
		(layer "F.Cu")
		(net 938)
	)
	(segment
		(start 197.075 111.225)
		(end 197.075 111.875)
		(width 0.182)
		(layer "F.Cu")
		(net 938)
	)
	(segment
		(start 206.5 117.5)
		(end 207 117)
		(width 0.256)
		(layer "F.Cu")
		(net 939)
	)
	(segment
		(start 201.2 89.483748)
		(end 201.141252 89.425)
		(width 0.184)
		(layer "F.Cu")
		(net 939)
	)
	(segment
		(start 201.2 90.422851)
		(end 201.2 89.483748)
		(width 0.184)
		(layer "F.Cu")
		(net 939)
	)
	(via
		(at 207 117)
		(size 0.45)
		(drill 0.2)
		(layers "F.Cu" "B.Cu")
		(net 939)
	)
	(via
		(at 201.141252 89.425)
		(size 0.45)
		(drill 0.2)
		(layers "F.Cu" "B.Cu")
		(net 939)
	)
	(segment
		(start 205.135 102.075)
		(end 204.535 102.075)
		(width 0.1)
		(layer "In7.Cu")
		(net 939)
	)
	(segment
		(start 205.31 110.31)
		(end 205.31 104.55)
		(width 0.1)
		(layer "In7.Cu")
		(net 939)
	)
	(segment
		(start 204.535 104.025)
		(end 205.135 104.025)
		(width 0.1)
		(layer "In7.Cu")
		(net 939)
	)
	(segment
		(start 204.580599 98.455)
		(end 205.135 98.455)
		(width 0.1)
		(layer "In7.Cu")
		(net 939)
	)
	(segment
		(start 204.535 101.025)
		(end 205.135 101.025)
		(width 0.1)
		(layer "In7.Cu")
		(net 939)
	)
	(segment
		(start 205.135 104.375)
		(end 204.535 104.375)
		(width 0.1)
		(layer "In7.Cu")
		(net 939)
	)
	(segment
		(start 207 112)
		(end 205.31 110.31)
		(width 0.1)
		(layer "In7.Cu")
		(net 939)
	)
	(segment
		(start 205.135 101.375)
		(end 204.535 101.375)
		(width 0.1)
		(layer "In7.Cu")
		(net 939)
	)
	(segment
		(start 205.135 99.505)
		(end 204.580599 99.505)
		(width 0.1)
		(layer "In7.Cu")
		(net 939)
	)
	(segment
		(start 205.31 98.230001)
		(end 205.31 96.193748)
		(width 0.1)
		(layer "In7.Cu")
		(net 939)
	)
	(segment
		(start 205.31 103.1)
		(end 205.31 102.25)
		(width 0.1)
		(layer "In7.Cu")
		(net 939)
	)
	(segment
		(start 205.31 98.28)
		(end 205.31 98.230001)
		(width 0.1)
		(layer "In7.Cu")
		(net 939)
	)
	(segment
		(start 205.31 96.193748)
		(end 201.141252 92.025)
		(width 0.1)
		(layer "In7.Cu")
		(net 939)
	)
	(segment
		(start 201.141252 92.025)
		(end 201.141252 89.425)
		(width 0.1)
		(layer "In7.Cu")
		(net 939)
	)
	(segment
		(start 204.535 101.725)
		(end 205.135 101.725)
		(width 0.1)
		(layer "In7.Cu")
		(net 939)
	)
	(segment
		(start 205.135 98.805)
		(end 204.580599 98.805)
		(width 0.1)
		(layer "In7.Cu")
		(net 939)
	)
	(segment
		(start 204.535 103.325)
		(end 205.135 103.325)
		(width 0.1)
		(layer "In7.Cu")
		(net 939)
	)
	(segment
		(start 204.580599 99.155)
		(end 205.135 99.155)
		(width 0.1)
		(layer "In7.Cu")
		(net 939)
	)
	(segment
		(start 205.31 100.8)
		(end 205.31 99.68)
		(width 0.1)
		(layer "In7.Cu")
		(net 939)
	)
	(segment
		(start 205.135 103.675)
		(end 204.535 103.675)
		(width 0.1)
		(layer "In7.Cu")
		(net 939)
	)
	(segment
		(start 205.31 100.85)
		(end 205.31 100.8)
		(width 0.1)
		(layer "In7.Cu")
		(net 939)
	)
	(segment
		(start 207 117)
		(end 207 112)
		(width 0.1)
		(layer "In7.Cu")
		(net 939)
	)
	(segment
		(start 205.31 103.15)
		(end 205.31 103.1)
		(width 0.1)
		(layer "In7.Cu")
		(net 939)
	)
	(arc
		(start 205.135 101.025)
		(mid 205.258744 100.973744)
		(end 205.31 100.85)
		(width 0.1)
		(layer "In7.Cu")
		(net 939)
	)
	(arc
		(start 204.535 101.375)
		(mid 204.411256 101.323744)
		(end 204.36 101.2)
		(width 0.1)
		(layer "In7.Cu")
		(net 939)
	)
	(arc
		(start 204.405599 98.63)
		(mid 204.456855 98.506256)
		(end 204.580599 98.455)
		(width 0.1)
		(layer "In7.Cu")
		(net 939)
	)
	(arc
		(start 205.31 103.85)
		(mid 205.258744 103.726256)
		(end 205.135 103.675)
		(width 0.1)
		(layer "In7.Cu")
		(net 939)
	)
	(arc
		(start 204.36 104.2)
		(mid 204.411256 104.076256)
		(end 204.535 104.025)
		(width 0.1)
		(layer "In7.Cu")
		(net 939)
	)
	(arc
		(start 205.31 104.55)
		(mid 205.258744 104.426256)
		(end 205.135 104.375)
		(width 0.1)
		(layer "In7.Cu")
		(net 939)
	)
	(arc
		(start 204.36 101.9)
		(mid 204.411256 101.776256)
		(end 204.535 101.725)
		(width 0.1)
		(layer "In7.Cu")
		(net 939)
	)
	(arc
		(start 204.36 101.2)
		(mid 204.411256 101.076256)
		(end 204.535 101.025)
		(width 0.1)
		(layer "In7.Cu")
		(net 939)
	)
	(arc
		(start 205.135 103.325)
		(mid 205.258744 103.273744)
		(end 205.31 103.15)
		(width 0.1)
		(layer "In7.Cu")
		(net 939)
	)
	(arc
		(start 205.135 104.025)
		(mid 205.258744 103.973744)
		(end 205.31 103.85)
		(width 0.1)
		(layer "In7.Cu")
		(net 939)
	)
	(arc
		(start 205.135 101.725)
		(mid 205.258744 101.673744)
		(end 205.31 101.55)
		(width 0.1)
		(layer "In7.Cu")
		(net 939)
	)
	(arc
		(start 204.535 102.075)
		(mid 204.411256 102.023744)
		(end 204.36 101.9)
		(width 0.1)
		(layer "In7.Cu")
		(net 939)
	)
	(arc
		(start 204.535 104.375)
		(mid 204.411256 104.323744)
		(end 204.36 104.2)
		(width 0.1)
		(layer "In7.Cu")
		(net 939)
	)
	(arc
		(start 205.31 99.68)
		(mid 205.258744 99.556256)
		(end 205.135 99.505)
		(width 0.1)
		(layer "In7.Cu")
		(net 939)
	)
	(arc
		(start 205.31 101.55)
		(mid 205.258744 101.426256)
		(end 205.135 101.375)
		(width 0.1)
		(layer "In7.Cu")
		(net 939)
	)
	(arc
		(start 204.580599 98.805)
		(mid 204.456855 98.753744)
		(end 204.405599 98.63)
		(width 0.1)
		(layer "In7.Cu")
		(net 939)
	)
	(arc
		(start 205.31 98.98)
		(mid 205.258744 98.856256)
		(end 205.135 98.805)
		(width 0.1)
		(layer "In7.Cu")
		(net 939)
	)
	(arc
		(start 204.36 103.5)
		(mid 204.411256 103.376256)
		(end 204.535 103.325)
		(width 0.1)
		(layer "In7.Cu")
		(net 939)
	)
	(arc
		(start 204.535 103.675)
		(mid 204.411256 103.623744)
		(end 204.36 103.5)
		(width 0.1)
		(layer "In7.Cu")
		(net 939)
	)
	(arc
		(start 205.31 102.25)
		(mid 205.258744 102.126256)
		(end 205.135 102.075)
		(width 0.1)
		(layer "In7.Cu")
		(net 939)
	)
	(arc
		(start 205.135 99.155)
		(mid 205.258744 99.103744)
		(end 205.31 98.98)
		(width 0.1)
		(layer "In7.Cu")
		(net 939)
	)
	(arc
		(start 204.405599 99.33)
		(mid 204.456855 99.206256)
		(end 204.580599 99.155)
		(width 0.1)
		(layer "In7.Cu")
		(net 939)
	)
	(arc
		(start 204.580599 99.505)
		(mid 204.456855 99.453744)
		(end 204.405599 99.33)
		(width 0.1)
		(layer "In7.Cu")
		(net 939)
	)
	(arc
		(start 205.135 98.455)
		(mid 205.258744 98.403744)
		(end 205.31 98.28)
		(width 0.1)
		(layer "In7.Cu")
		(net 939)
	)
	(segment
		(start 244.4 132.075)
		(end 244.7 131.775)
		(width 0.1)
		(layer "F.Cu")
		(net 940)
	)
	(segment
		(start 245.6 131.3)
		(end 245.65 131.35)
		(width 0.1)
		(layer "F.Cu")
		(net 940)
	)
	(segment
		(start 244.775 131.3)
		(end 245.6 131.3)
		(width 0.1)
		(layer "F.Cu")
		(net 940)
	)
	(segment
		(start 243.675 131.75)
		(end 244 132.075)
		(width 0.1)
		(layer "F.Cu")
		(net 940)
	)
	(segment
		(start 236.44 134.215)
		(end 238 134.215)
		(width 0.1)
		(layer "F.Cu")
		(net 940)
	)
	(segment
		(start 244 132.075)
		(end 244.4 132.075)
		(width 0.1)
		(layer "F.Cu")
		(net 940)
	)
	(segment
		(start 244.7 131.375)
		(end 244.775 131.3)
		(width 0.1)
		(layer "F.Cu")
		(net 940)
	)
	(segment
		(start 243.5 131.75)
		(end 243.675 131.75)
		(width 0.1)
		(layer "F.Cu")
		(net 940)
	)
	(segment
		(start 236.425 134.2)
		(end 236.44 134.215)
		(width 0.1)
		(layer "F.Cu")
		(net 940)
	)
	(segment
		(start 245.65 131.35)
		(end 245.65 131.9625)
		(width 0.1)
		(layer "F.Cu")
		(net 940)
	)
	(segment
		(start 244.7 131.775)
		(end 244.7 131.375)
		(width 0.1)
		(layer "F.Cu")
		(net 940)
	)
	(via
		(at 243.5 131.75)
		(size 0.45)
		(drill 0.2)
		(layers "F.Cu" "B.Cu")
		(net 940)
	)
	(via
		(at 236.425 134.2)
		(size 0.45)
		(drill 0.2)
		(layers "F.Cu" "B.Cu")
		(net 940)
	)
	(segment
		(start 236.9 132.32)
		(end 236.425 132.795)
		(width 0.1)
		(layer "In3.Cu")
		(net 940)
	)
	(segment
		(start 236.425 132.795)
		(end 236.425 134.2)
		(width 0.1)
		(layer "In3.Cu")
		(net 940)
	)
	(segment
		(start 241.92 132.32)
		(end 236.9 132.32)
		(width 0.1)
		(layer "In3.Cu")
		(net 940)
	)
	(segment
		(start 243.5 131.75)
		(end 242.49 131.75)
		(width 0.1)
		(layer "In3.Cu")
		(net 940)
	)
	(segment
		(start 242.49 131.75)
		(end 241.92 132.32)
		(width 0.1)
		(layer "In3.Cu")
		(net 940)
	)
	(segment
		(start 236.785 138.7)
		(end 238.35 138.7)
		(width 0.177)
		(layer "F.Cu")
		(net 941)
	)
	(segment
		(start 178.77 186.62)
		(end 178.77 188.64)
		(width 0.1)
		(layer "F.Cu")
		(net 941)
	)
	(segment
		(start 236.485 139)
		(end 236.785 138.7)
		(width 0.177)
		(layer "F.Cu")
		(net 941)
	)
	(via
		(at 238.35 138.7)
		(size 0.45)
		(drill 0.2)
		(layers "F.Cu" "B.Cu")
		(net 941)
	)
	(via
		(at 178.77 186.62)
		(size 0.45)
		(drill 0.2)
		(layers "F.Cu" "B.Cu")
		(net 941)
	)
	(via
		(at 240.56 149.26)
		(size 0.45)
		(drill 0.2)
		(layers "F.Cu" "B.Cu")
		(net 941)
	)
	(segment
		(start 231.82 161.201475)
		(end 230.321475 162.7)
		(width 0.1)
		(layer "In5.Cu")
		(net 941)
	)
	(segment
		(start 239.41 151.32)
		(end 239.06 151.67)
		(width 0.1)
		(layer "In5.Cu")
		(net 941)
	)
	(segment
		(start 198.35 166.99)
		(end 196.14 169.2)
		(width 0.1)
		(layer "In5.Cu")
		(net 941)
	)
	(segment
		(start 227.628526 162.7)
		(end 226.673526 163.655)
		(width 0.1)
		(layer "In5.Cu")
		(net 941)
	)
	(segment
		(start 216.277158 166.99)
		(end 198.35 166.99)
		(width 0.1)
		(layer "In5.Cu")
		(net 941)
	)
	(segment
		(start 238.77 151.67)
		(end 237.7 150.6)
		(width 0.1)
		(layer "In5.Cu")
		(net 941)
	)
	(segment
		(start 239.41 150.41)
		(end 239.41 151.32)
		(width 0.1)
		(layer "In5.Cu")
		(net 941)
	)
	(segment
		(start 230.321475 162.7)
		(end 227.628526 162.7)
		(width 0.1)
		(layer "In5.Cu")
		(net 941)
	)
	(segment
		(start 182.49 183.338529)
		(end 179.208526 186.62)
		(width 0.1)
		(layer "In5.Cu")
		(net 941)
	)
	(segment
		(start 231.82 153.678526)
		(end 231.82 161.201475)
		(width 0.1)
		(layer "In5.Cu")
		(net 941)
	)
	(segment
		(start 239.06 151.67)
		(end 238.77 151.67)
		(width 0.1)
		(layer "In5.Cu")
		(net 941)
	)
	(segment
		(start 189.419999 169.2)
		(end 182.49 176.13)
		(width 0.1)
		(layer "In5.Cu")
		(net 941)
	)
	(segment
		(start 237.7 150.6)
		(end 234.898525 150.6)
		(width 0.1)
		(layer "In5.Cu")
		(net 941)
	)
	(segment
		(start 182.49 176.13)
		(end 182.49 183.338529)
		(width 0.1)
		(layer "In5.Cu")
		(net 941)
	)
	(segment
		(start 234.898525 150.6)
		(end 231.82 153.678526)
		(width 0.1)
		(layer "In5.Cu")
		(net 941)
	)
	(segment
		(start 196.14 169.2)
		(end 189.419999 169.2)
		(width 0.1)
		(layer "In5.Cu")
		(net 941)
	)
	(segment
		(start 179.208526 186.62)
		(end 178.77 186.62)
		(width 0.1)
		(layer "In5.Cu")
		(net 941)
	)
	(segment
		(start 226.673526 163.655)
		(end 219.612157 163.655)
		(width 0.1)
		(layer "In5.Cu")
		(net 941)
	)
	(segment
		(start 240.56 149.26)
		(end 239.41 150.41)
		(width 0.1)
		(layer "In5.Cu")
		(net 941)
	)
	(segment
		(start 219.612157 163.655)
		(end 216.277158 166.99)
		(width 0.1)
		(layer "In5.Cu")
		(net 941)
	)
	(segment
		(start 238 141.24)
		(end 238 147.74)
		(width 0.1)
		(layer "In7.Cu")
		(net 941)
	)
	(segment
		(start 239.52 149.26)
		(end 240.56 149.26)
		(width 0.1)
		(layer "In7.Cu")
		(net 941)
	)
	(segment
		(start 238 147.74)
		(end 239.52 149.26)
		(width 0.1)
		(layer "In7.Cu")
		(net 941)
	)
	(segment
		(start 239.43 139.3)
		(end 239.43 139.81)
		(width 0.1)
		(layer "In7.Cu")
		(net 941)
	)
	(segment
		(start 238.83 138.7)
		(end 239.43 139.3)
		(width 0.1)
		(layer "In7.Cu")
		(net 941)
	)
	(segment
		(start 238.35 138.7)
		(end 238.83 138.7)
		(width 0.1)
		(layer "In7.Cu")
		(net 941)
	)
	(segment
		(start 239.43 139.81)
		(end 238 141.24)
		(width 0.1)
		(layer "In7.Cu")
		(net 941)
	)
	(segment
		(start 236.45 137.2)
		(end 236.25 137.2)
		(width 0.177)
		(layer "F.Cu")
		(net 942)
	)
	(segment
		(start 237.05 137.2)
		(end 236.45 137.2)
		(width 0.177)
		(layer "F.Cu")
		(net 942)
	)
	(segment
		(start 236.57 137.2)
		(end 236.485 137.115)
		(width 0.177)
		(layer "F.Cu")
		(net 942)
	)
	(segment
		(start 238.35 137.2)
		(end 237.05 137.2)
		(width 0.177)
		(layer "F.Cu")
		(net 942)
	)
	(segment
		(start 236.25 137.2)
		(end 236.4 137.2)
		(width 0.177)
		(layer "F.Cu")
		(net 942)
	)
	(segment
		(start 237.05 137.2)
		(end 236.57 137.2)
		(width 0.177)
		(layer "F.Cu")
		(net 942)
	)
	(segment
		(start 176.77 185.77)
		(end 176.77 188.64)
		(width 0.1)
		(layer "F.Cu")
		(net 942)
	)
	(segment
		(start 236.25 137.2)
		(end 236.05 137.2)
		(width 0.177)
		(layer "F.Cu")
		(net 942)
	)
	(segment
		(start 236.485 136.4)
		(end 236.485 137.115)
		(width 0.177)
		(layer "F.Cu")
		(net 942)
	)
	(segment
		(start 236.485 137.115)
		(end 236.485 137.165)
		(width 0.177)
		(layer "F.Cu")
		(net 942)
	)
	(segment
		(start 236.485 137.165)
		(end 236.45 137.2)
		(width 0.177)
		(layer "F.Cu")
		(net 942)
	)
	(segment
		(start 236.4 137.2)
		(end 236.485 137.115)
		(width 0.177)
		(layer "F.Cu")
		(net 942)
	)
	(segment
		(start 236.05 137.2)
		(end 235.55 137.7)
		(width 0.177)
		(layer "F.Cu")
		(net 942)
	)
	(via
		(at 236.485 136.4)
		(size 0.45)
		(drill 0.2)
		(layers "F.Cu" "B.Cu")
		(net 942)
	)
	(via
		(at 238.93 150.57)
		(size 0.45)
		(drill 0.2)
		(layers "F.Cu" "B.Cu")
		(net 942)
	)
	(via
		(at 176.77 185.77)
		(size 0.45)
		(drill 0.2)
		(layers "F.Cu" "B.Cu")
		(net 942)
	)
	(segment
		(start 179.492842 185.77)
		(end 176.77 185.77)
		(width 0.1)
		(layer "In5.Cu")
		(net 942)
	)
	(segment
		(start 219.446473 163.255)
		(end 216.111474 166.59)
		(width 0.1)
		(layer "In5.Cu")
		(net 942)
	)
	(segment
		(start 230.155791 162.3)
		(end 227.462842 162.3)
		(width 0.1)
		(layer "In5.Cu")
		(net 942)
	)
	(segment
		(start 227.462842 162.3)
		(end 226.507842 163.255)
		(width 0.1)
		(layer "In5.Cu")
		(net 942)
	)
	(segment
		(start 238.93 150.57)
		(end 238.56 150.2)
		(width 0.1)
		(layer "In5.Cu")
		(net 942)
	)
	(segment
		(start 195.932842 168.8)
		(end 189.232842 168.8)
		(width 0.1)
		(layer "In5.Cu")
		(net 942)
	)
	(segment
		(start 238.56 150.2)
		(end 234.73284 150.2)
		(width 0.1)
		(layer "In5.Cu")
		(net 942)
	)
	(segment
		(start 231.41 161.045791)
		(end 230.155791 162.3)
		(width 0.1)
		(layer "In5.Cu")
		(net 942)
	)
	(segment
		(start 189.232842 168.8)
		(end 182.09 175.942842)
		(width 0.1)
		(layer "In5.Cu")
		(net 942)
	)
	(segment
		(start 226.507842 163.255)
		(end 219.446473 163.255)
		(width 0.1)
		(layer "In5.Cu")
		(net 942)
	)
	(segment
		(start 182.09 183.172843)
		(end 179.492842 185.77)
		(width 0.1)
		(layer "In5.Cu")
		(net 942)
	)
	(segment
		(start 231.41 153.522842)
		(end 231.41 161.045791)
		(width 0.1)
		(layer "In5.Cu")
		(net 942)
	)
	(segment
		(start 198.142842 166.59)
		(end 195.932842 168.8)
		(width 0.1)
		(layer "In5.Cu")
		(net 942)
	)
	(segment
		(start 234.73284 150.2)
		(end 231.41 153.522842)
		(width 0.1)
		(layer "In5.Cu")
		(net 942)
	)
	(segment
		(start 216.111474 166.59)
		(end 198.142842 166.59)
		(width 0.1)
		(layer "In5.Cu")
		(net 942)
	)
	(segment
		(start 182.09 175.942842)
		(end 182.09 183.172843)
		(width 0.1)
		(layer "In5.Cu")
		(net 942)
	)
	(segment
		(start 236.485 136.4)
		(end 236.11 136.775)
		(width 0.1)
		(layer "In7.Cu")
		(net 942)
	)
	(segment
		(start 237.35 144.647158)
		(end 237.35 147.98)
		(width 0.1)
		(layer "In7.Cu")
		(net 942)
	)
	(segment
		(start 236.11 143.407158)
		(end 237.35 144.647158)
		(width 0.1)
		(layer "In7.Cu")
		(net 942)
	)
	(segment
		(start 236.11 136.775)
		(end 236.11 143.407158)
		(width 0.1)
		(layer "In7.Cu")
		(net 942)
	)
	(segment
		(start 237.35 148.99)
		(end 238.93 150.57)
		(width 0.1)
		(layer "In7.Cu")
		(net 942)
	)
	(segment
		(start 237.35 147.98)
		(end 237.35 148.99)
		(width 0.1)
		(layer "In7.Cu")
		(net 942)
	)
	(segment
		(start 260.085 129.7)
		(end 260.085 129.73)
		(width 0.1)
		(layer "F.Cu")
		(net 943)
	)
	(segment
		(start 260.085 129.73)
		(end 259.115 130.7)
		(width 0.1)
		(layer "F.Cu")
		(net 943)
	)
	(segment
		(start 221.65 148.3625)
		(end 221.65 147.95)
		(width 0.184)
		(layer "F.Cu")
		(net 944)
	)
	(segment
		(start 221.65 147.95)
		(end 221.1 147.4)
		(width 0.184)
		(layer "F.Cu")
		(net 944)
	)
	(via
		(at 221.1 147.4)
		(size 0.45)
		(drill 0.2)
		(layers "F.Cu" "B.Cu")
		(net 944)
	)
	(segment
		(start 220.238 148.216)
		(end 221.054 147.4)
		(width 0.184)
		(layer "B.Cu")
		(net 944)
	)
	(segment
		(start 221.054 147.4)
		(end 221.1 147.4)
		(width 0.184)
		(layer "B.Cu")
		(net 944)
	)
	(segment
		(start 221.084 147.384)
		(end 221.1 147.4)
		(width 0.184)
		(layer "B.Cu")
		(net 944)
	)
	(segment
		(start 220.238 149.216)
		(end 220.238 148.216)
		(width 0.184)
		(layer "B.Cu")
		(net 944)
	)
	(segment
		(start 221.084 146.685)
		(end 221.084 147.384)
		(width 0.184)
		(layer "B.Cu")
		(net 944)
	)
	(segment
		(start 223.65 148.3625)
		(end 223.65 147.95)
		(width 0.184)
		(layer "F.Cu")
		(net 945)
	)
	(segment
		(start 223.65 147.95)
		(end 224.2 147.4)
		(width 0.184)
		(layer "F.Cu")
		(net 945)
	)
	(via
		(at 224.2 147.4)
		(size 0.45)
		(drill 0.2)
		(layers "F.Cu" "B.Cu")
		(net 945)
	)
	(segment
		(start 224.2 146.685)
		(end 224.2 147.4)
		(width 0.184)
		(layer "B.Cu")
		(net 945)
	)
	(segment
		(start 225.141 149.217)
		(end 225.141 148.201)
		(width 0.184)
		(layer "B.Cu")
		(net 945)
	)
	(segment
		(start 224.34 147.4)
		(end 225.141 148.201)
		(width 0.184)
		(layer "B.Cu")
		(net 945)
	)
	(segment
		(start 224.2 147.4)
		(end 224.34 147.4)
		(width 0.184)
		(layer "B.Cu")
		(net 945)
	)
	(segment
		(start 223.15 147.45)
		(end 223.2 147.4)
		(width 0.184)
		(layer "F.Cu")
		(net 946)
	)
	(segment
		(start 223.15 148.3625)
		(end 223.15 147.45)
		(width 0.184)
		(layer "F.Cu")
		(net 946)
	)
	(via
		(at 223.2 147.4)
		(size 0.45)
		(drill 0.2)
		(layers "F.Cu" "B.Cu")
		(net 946)
	)
	(segment
		(start 224.071 148.2)
		(end 223.271 147.4)
		(width 0.184)
		(layer "B.Cu")
		(net 946)
	)
	(segment
		(start 224.071 149.2)
		(end 224.071 148.2)
		(width 0.184)
		(layer "B.Cu")
		(net 946)
	)
	(segment
		(start 223.2 146.685)
		(end 223.2 147.4)
		(width 0.184)
		(layer "B.Cu")
		(net 946)
	)
	(segment
		(start 223.271 147.4)
		(end 223.2 147.4)
		(width 0.184)
		(layer "B.Cu")
		(net 946)
	)
	(segment
		(start 222.15 148.3625)
		(end 222.15 147.45)
		(width 0.184)
		(layer "F.Cu")
		(net 947)
	)
	(segment
		(start 222.15 147.45)
		(end 222.1 147.4)
		(width 0.184)
		(layer "F.Cu")
		(net 947)
	)
	(via
		(at 222.1 147.4)
		(size 0.45)
		(drill 0.2)
		(layers "F.Cu" "B.Cu")
		(net 947)
	)
	(segment
		(start 222.1 146.685)
		(end 222.1 147.4)
		(width 0.184)
		(layer "B.Cu")
		(net 947)
	)
	(segment
		(start 221.23 148.2)
		(end 222.03 147.4)
		(width 0.184)
		(layer "B.Cu")
		(net 947)
	)
	(segment
		(start 221.23 149.216)
		(end 221.23 148.2)
		(width 0.184)
		(layer "B.Cu")
		(net 947)
	)
	(segment
		(start 222.03 147.4)
		(end 222.1 147.4)
		(width 0.184)
		(layer "B.Cu")
		(net 947)
	)
	(segment
		(start 220.4625 150.55)
		(end 219.135 150.55)
		(width 0.198)
		(layer "F.Cu")
		(net 948)
	)
	(segment
		(start 219.135 150.55)
		(end 218.885 150.8)
		(width 0.198)
		(layer "F.Cu")
		(net 948)
	)
	(segment
		(start 219.635 151.05)
		(end 218.885 151.8)
		(width 0.198)
		(layer "F.Cu")
		(net 949)
	)
	(segment
		(start 220.4625 151.05)
		(end 219.635 151.05)
		(width 0.198)
		(layer "F.Cu")
		(net 949)
	)
	(segment
		(start 220.135 151.55)
		(end 218.885 152.8)
		(width 0.198)
		(layer "F.Cu")
		(net 950)
	)
	(segment
		(start 220.4625 151.55)
		(end 220.135 151.55)
		(width 0.198)
		(layer "F.Cu")
		(net 950)
	)
	(segment
		(start 219.635 149.55)
		(end 218.885 148.8)
		(width 0.198)
		(layer "F.Cu")
		(net 951)
	)
	(segment
		(start 220.4625 149.55)
		(end 219.635 149.55)
		(width 0.198)
		(layer "F.Cu")
		(net 951)
	)
	(segment
		(start 224.4 153.515)
		(end 224.4 152.6)
		(width 0.256)
		(layer "F.Cu")
		(net 952)
	)
	(segment
		(start 224.4 152.6)
		(end 224.0375 152.2375)
		(width 0.256)
		(layer "F.Cu")
		(net 952)
	)
	(segment
		(start 224.0375 152.2375)
		(end 223.65 152.2375)
		(width 0.256)
		(layer "F.Cu")
		(net 952)
	)
	(segment
		(start 205.0265 98.4765)
		(end 204.199 97.649)
		(width 0.182)
		(layer "F.Cu")
		(net 953)
	)
	(segment
		(start 204.199 97.649)
		(end 204.199 97.349)
		(width 0.182)
		(layer "F.Cu")
		(net 953)
	)
	(segment
		(start 205.103752 98.4765)
		(end 205.0265 98.4765)
		(width 0.182)
		(layer "F.Cu")
		(net 953)
	)
	(segment
		(start 205.091252 98.465)
		(end 205.065 98.465)
		(width 0.182)
		(layer "F.Cu")
		(net 953)
	)
	(segment
		(start 175 174.9625)
		(end 175.1375 174.825)
		(width 0.182)
		(layer "F.Cu")
		(net 954)
	)
	(segment
		(start 175.1375 174.825)
		(end 175.1375 173.9625)
		(width 0.182)
		(layer "F.Cu")
		(net 954)
	)
	(via
		(at 175 174.9625)
		(size 0.45)
		(drill 0.2)
		(layers "F.Cu" "B.Cu")
		(net 954)
	)
	(segment
		(start 174.845 176.2)
		(end 174.845 176.235)
		(width 0.182)
		(layer "B.Cu")
		(net 954)
	)
	(segment
		(start 174.845 176.235)
		(end 175.815 177.205)
		(width 0.182)
		(layer "B.Cu")
		(net 954)
	)
	(segment
		(start 174.845 175.1175)
		(end 175 174.9625)
		(width 0.182)
		(layer "B.Cu")
		(net 954)
	)
	(segment
		(start 175.815 177.205)
		(end 175.815 177.26)
		(width 0.182)
		(layer "B.Cu")
		(net 954)
	)
	(segment
		(start 174.845 176.2)
		(end 174.845 175.1175)
		(width 0.182)
		(layer "B.Cu")
		(net 954)
	)
	(segment
		(start 252.15 144.65)
		(end 252.1 144.6)
		(width 0.177)
		(layer "F.Cu")
		(net 955)
	)
	(segment
		(start 252.15 146.125)
		(end 252.15 144.65)
		(width 0.177)
		(layer "F.Cu")
		(net 955)
	)
	(via
		(at 166.5 183.5)
		(size 0.45)
		(drill 0.2)
		(layers "F.Cu" "B.Cu")
		(net 956)
	)
	(via
		(at 193.1 181.6)
		(size 0.45)
		(drill 0.2)
		(layers "F.Cu" "B.Cu")
		(net 956)
	)
	(segment
		(start 165.8 183.215)
		(end 166.215 183.215)
		(width 0.1)
		(layer "B.Cu")
		(net 956)
	)
	(segment
		(start 166.215 183.215)
		(end 166.5 183.5)
		(width 0.1)
		(layer "B.Cu")
		(net 956)
	)
	(segment
		(start 168.7 181.3)
		(end 192.8 181.3)
		(width 0.1)
		(layer "In7.Cu")
		(net 956)
	)
	(segment
		(start 166.5 183.5)
		(end 168.7 181.3)
		(width 0.1)
		(layer "In7.Cu")
		(net 956)
	)
	(segment
		(start 192.8 181.3)
		(end 193.1 181.6)
		(width 0.1)
		(layer "In7.Cu")
		(net 956)
	)
	(segment
		(start 179.25 169.2)
		(end 180.2375 169.2)
		(width 0.182)
		(layer "F.Cu")
		(net 957)
	)
	(segment
		(start 181.05 169.1975)
		(end 180.265 169.1975)
		(width 0.182)
		(layer "F.Cu")
		(net 957)
	)
	(segment
		(start 180.2375 169.2)
		(end 180.25 169.2125)
		(width 0.182)
		(layer "F.Cu")
		(net 957)
	)
	(segment
		(start 180.265 169.1975)
		(end 180.25 169.2125)
		(width 0.182)
		(layer "F.Cu")
		(net 957)
	)
	(via
		(at 180.25 169.2125)
		(size 0.45)
		(drill 0.2)
		(layers "F.Cu" "B.Cu")
		(net 957)
	)
	(segment
		(start 180.265 169.1975)
		(end 180.25 169.2125)
		(width 0.182)
		(layer "B.Cu")
		(net 957)
	)
	(segment
		(start 182.1 169.1975)
		(end 181.05 169.1975)
		(width 0.182)
		(layer "B.Cu")
		(net 957)
	)
	(segment
		(start 181.05 170.145)
		(end 181.05 169.1975)
		(width 0.182)
		(layer "B.Cu")
		(net 957)
	)
	(segment
		(start 181.05 169.1975)
		(end 180.265 169.1975)
		(width 0.182)
		(layer "B.Cu")
		(net 957)
	)
	(segment
		(start 172.975 169.85)
		(end 171.3025 169.85)
		(width 0.182)
		(layer "F.Cu")
		(net 958)
	)
	(segment
		(start 171.3025 169.85)
		(end 171.25 169.7975)
		(width 0.182)
		(layer "F.Cu")
		(net 958)
	)
	(via
		(at 172.0125 169.85)
		(size 0.45)
		(drill 0.2)
		(layers "F.Cu" "B.Cu")
		(net 958)
	)
	(via
		(at 181.97 172.65)
		(size 0.45)
		(drill 0.2)
		(layers "F.Cu" "B.Cu")
		(net 958)
	)
	(segment
		(start 181.05 171.73)
		(end 181.05 171.115)
		(width 0.182)
		(layer "B.Cu")
		(net 958)
	)
	(segment
		(start 170.25 169.7975)
		(end 171.25 169.7975)
		(width 0.182)
		(layer "B.Cu")
		(net 958)
	)
	(segment
		(start 181.97 172.65)
		(end 181.05 171.73)
		(width 0.182)
		(layer "B.Cu")
		(net 958)
	)
	(segment
		(start 171.96 169.7975)
		(end 172.0125 169.85)
		(width 0.182)
		(layer "B.Cu")
		(net 958)
	)
	(segment
		(start 171.25 169.7975)
		(end 171.96 169.7975)
		(width 0.182)
		(layer "B.Cu")
		(net 958)
	)
	(segment
		(start 181.97 173.47)
		(end 183.2 174.7)
		(width 0.4)
		(layer "In3.Cu")
		(net 958)
	)
	(segment
		(start 172.8 176.3)
		(end 172.8 170.1)
		(width 0.4)
		(layer "In3.Cu")
		(net 958)
	)
	(segment
		(start 181.97 172.65)
		(end 181.97 173.47)
		(width 0.4)
		(layer "In3.Cu")
		(net 958)
	)
	(segment
		(start 172.55 169.85)
		(end 172.0125 169.85)
		(width 0.4)
		(layer "In3.Cu")
		(net 958)
	)
	(segment
		(start 183.2 177.9)
		(end 182.2 178.9)
		(width 0.4)
		(layer "In3.Cu")
		(net 958)
	)
	(segment
		(start 182.2 178.9)
		(end 175.4 178.9)
		(width 0.4)
		(layer "In3.Cu")
		(net 958)
	)
	(segment
		(start 183.2 174.7)
		(end 183.2 177.9)
		(width 0.4)
		(layer "In3.Cu")
		(net 958)
	)
	(segment
		(start 175.4 178.9)
		(end 172.8 176.3)
		(width 0.4)
		(layer "In3.Cu")
		(net 958)
	)
	(segment
		(start 172.8 170.1)
		(end 172.55 169.85)
		(width 0.4)
		(layer "In3.Cu")
		(net 958)
	)
	(segment
		(start 154.4775 169.85)
		(end 154.3125 169.685)
		(width 0.182)
		(layer "F.Cu")
		(net 959)
	)
	(segment
		(start 155.1125 169.85)
		(end 154.4775 169.85)
		(width 0.182)
		(layer "F.Cu")
		(net 959)
	)
	(segment
		(start 156.025 169.85)
		(end 155.1125 169.85)
		(width 0.182)
		(layer "F.Cu")
		(net 959)
	)
	(via
		(at 155.1125 169.85)
		(size 0.45)
		(drill 0.2)
		(layers "F.Cu" "B.Cu")
		(net 959)
	)
	(segment
		(start 155.1125 169.85)
		(end 154.9625 169.7)
		(width 0.182)
		(layer "B.Cu")
		(net 959)
	)
	(segment
		(start 154.9625 169.7)
		(end 154.3275 169.7)
		(width 0.182)
		(layer "B.Cu")
		(net 959)
	)
	(segment
		(start 154.3125 169.685)
		(end 153.2125 169.685)
		(width 0.182)
		(layer "B.Cu")
		(net 959)
	)
	(segment
		(start 154.3275 169.7)
		(end 154.3125 169.685)
		(width 0.182)
		(layer "B.Cu")
		(net 959)
	)
	(segment
		(start 164.0625 169.085)
		(end 163.9475 169.2)
		(width 0.182)
		(layer "F.Cu")
		(net 960)
	)
	(segment
		(start 163.9475 169.2)
		(end 163.2625 169.2)
		(width 0.182)
		(layer "F.Cu")
		(net 960)
	)
	(segment
		(start 162.3 169.2)
		(end 163.2625 169.2)
		(width 0.182)
		(layer "F.Cu")
		(net 960)
	)
	(via
		(at 163.2625 169.2)
		(size 0.45)
		(drill 0.2)
		(layers "F.Cu" "B.Cu")
		(net 960)
	)
	(segment
		(start 164.0625 169.085)
		(end 165.1125 169.085)
		(width 0.182)
		(layer "B.Cu")
		(net 960)
	)
	(segment
		(start 164.0625 169.085)
		(end 163.9475 169.2)
		(width 0.182)
		(layer "B.Cu")
		(net 960)
	)
	(segment
		(start 163.9475 169.2)
		(end 163.2625 169.2)
		(width 0.182)
		(layer "B.Cu")
		(net 960)
	)
	(segment
		(start 170.885 187.885)
		(end 170.885 188.7)
		(width 0.1)
		(layer "F.Cu")
		(net 961)
	)
	(segment
		(start 167.8 187.3)
		(end 170.3 187.3)
		(width 0.1)
		(layer "F.Cu")
		(net 961)
	)
	(segment
		(start 162.8 188.45)
		(end 162.8 187.4)
		(width 0.1)
		(layer "F.Cu")
		(net 961)
	)
	(segment
		(start 162.8 187.4)
		(end 163.2 187)
		(width 0.1)
		(layer "F.Cu")
		(net 961)
	)
	(segment
		(start 163.2 187)
		(end 167.5 187)
		(width 0.1)
		(layer "F.Cu")
		(net 961)
	)
	(segment
		(start 170.3 187.3)
		(end 170.885 187.885)
		(width 0.1)
		(layer "F.Cu")
		(net 961)
	)
	(segment
		(start 167.5 187)
		(end 167.8 187.3)
		(width 0.1)
		(layer "F.Cu")
		(net 961)
	)
	(segment
		(start 161.4375 173.9625)
		(end 161.4375 174.825)
		(width 0.182)
		(layer "F.Cu")
		(net 962)
	)
	(segment
		(start 161.4375 175.125)
		(end 161.4375 174.825)
		(width 0.182)
		(layer "F.Cu")
		(net 962)
	)
	(segment
		(start 162.0425 175.75)
		(end 162.0425 175.73)
		(width 0.182)
		(layer "F.Cu")
		(net 962)
	)
	(segment
		(start 162.0425 175.73)
		(end 161.4375 175.125)
		(width 0.182)
		(layer "F.Cu")
		(net 962)
	)
	(via
		(at 161.4375 174.825)
		(size 0.45)
		(drill 0.2)
		(layers "F.Cu" "B.Cu")
		(net 962)
	)
	(segment
		(start 161.4475 174.815)
		(end 161.4375 174.825)
		(width 0.182)
		(layer "B.Cu")
		(net 962)
	)
	(segment
		(start 162.1625 174.815)
		(end 161.4475 174.815)
		(width 0.182)
		(layer "B.Cu")
		(net 962)
	)
	(segment
		(start 163.1625 174.815)
		(end 162.1625 174.815)
		(width 0.182)
		(layer "B.Cu")
		(net 962)
	)
	(segment
		(start 156.8875 174.825)
		(end 156.8875 175.11)
		(width 0.182)
		(layer "F.Cu")
		(net 963)
	)
	(segment
		(start 156.8875 175.11)
		(end 156.2975 175.7)
		(width 0.182)
		(layer "F.Cu")
		(net 963)
	)
	(segment
		(start 156.8875 173.9625)
		(end 156.8875 174.825)
		(width 0.182)
		(layer "F.Cu")
		(net 963)
	)
	(via
		(at 156.8875 174.825)
		(size 0.45)
		(drill 0.2)
		(layers "F.Cu" "B.Cu")
		(net 963)
	)
	(segment
		(start 156.8875 174.825)
		(end 156.8875 174.61)
		(width 0.182)
		(layer "B.Cu")
		(net 963)
	)
	(segment
		(start 156.8875 174.61)
		(end 156.4625 174.185)
		(width 0.182)
		(layer "B.Cu")
		(net 963)
	)
	(segment
		(start 178.3875 174.875)
		(end 178.3875 175.085)
		(width 0.182)
		(layer "F.Cu")
		(net 964)
	)
	(segment
		(start 178.3875 175.085)
		(end 179.015 175.7125)
		(width 0.182)
		(layer "F.Cu")
		(net 964)
	)
	(segment
		(start 178.3875 173.9625)
		(end 178.3875 174.875)
		(width 0.182)
		(layer "F.Cu")
		(net 964)
	)
	(via
		(at 178.3875 174.875)
		(size 0.45)
		(drill 0.2)
		(layers "F.Cu" "B.Cu")
		(net 964)
	)
	(segment
		(start 178.3875 174.875)
		(end 178.9525 174.875)
		(width 0.182)
		(layer "B.Cu")
		(net 964)
	)
	(segment
		(start 179.05 174.7775)
		(end 180.05 174.7775)
		(width 0.201)
		(layer "B.Cu")
		(net 964)
	)
	(segment
		(start 178.9525 174.875)
		(end 179.05 174.7775)
		(width 0.182)
		(layer "B.Cu")
		(net 964)
	)
	(segment
		(start 173.8375 173.9625)
		(end 173.8375 174.625)
		(width 0.182)
		(layer "F.Cu")
		(net 965)
	)
	(segment
		(start 173.8375 174.625)
		(end 173.5 174.9625)
		(width 0.182)
		(layer "F.Cu")
		(net 965)
	)
	(segment
		(start 173.235 175.7125)
		(end 173.235 175.2275)
		(width 0.182)
		(layer "F.Cu")
		(net 965)
	)
	(segment
		(start 173.235 175.2275)
		(end 173.5 174.9625)
		(width 0.182)
		(layer "F.Cu")
		(net 965)
	)
	(via
		(at 173.5 174.9625)
		(size 0.45)
		(drill 0.2)
		(layers "F.Cu" "B.Cu")
		(net 965)
	)
	(segment
		(start 173.5 175.4475)
		(end 173.235 175.7125)
		(width 0.182)
		(layer "B.Cu")
		(net 965)
	)
	(segment
		(start 173.235 175.7125)
		(end 173.235 176.7625)
		(width 0.182)
		(layer "B.Cu")
		(net 965)
	)
	(segment
		(start 173.5 174.9625)
		(end 173.5 175.4475)
		(width 0.182)
		(layer "B.Cu")
		(net 965)
	)
	(segment
		(start 194.6 159.4)
		(end 194.5 159.3)
		(width 0.177)
		(layer "F.Cu")
		(net 966)
	)
	(segment
		(start 166.596 184.954)
		(end 166.6 184.95)
		(width 0.182)
		(layer "F.Cu")
		(net 966)
	)
	(segment
		(start 166.596 185.836)
		(end 166.596 184.954)
		(width 0.182)
		(layer "F.Cu")
		(net 966)
	)
	(segment
		(start 194.6 160.050001)
		(end 194.6 159.4)
		(width 0.177)
		(layer "F.Cu")
		(net 966)
	)
	(via
		(at 166.6 184.95)
		(size 0.45)
		(drill 0.2)
		(layers "F.Cu" "B.Cu")
		(net 966)
	)
	(via
		(at 195.6 160.95)
		(size 0.45)
		(drill 0.2)
		(layers "F.Cu" "B.Cu")
		(net 966)
	)
	(via
		(at 194.5 159.3)
		(size 0.45)
		(drill 0.2)
		(layers "F.Cu" "B.Cu")
		(net 966)
	)
	(segment
		(start 166.55 185.47)
		(end 166.55 185)
		(width 0.1)
		(layer "B.Cu")
		(net 966)
	)
	(segment
		(start 166.55 185)
		(end 166.6 184.95)
		(width 0.1)
		(layer "B.Cu")
		(net 966)
	)
	(segment
		(start 168.225 187.225)
		(end 166.6 185.6)
		(width 0.1)
		(layer "In3.Cu")
		(net 966)
	)
	(segment
		(start 189.8 181.54)
		(end 184.115 187.225)
		(width 0.1)
		(layer "In3.Cu")
		(net 966)
	)
	(segment
		(start 166.6 185.6)
		(end 166.6 184.95)
		(width 0.1)
		(layer "In3.Cu")
		(net 966)
	)
	(segment
		(start 189.8 169.875)
		(end 189.8 181.54)
		(width 0.1)
		(layer "In3.Cu")
		(net 966)
	)
	(segment
		(start 184.115 187.225)
		(end 168.225 187.225)
		(width 0.1)
		(layer "In3.Cu")
		(net 966)
	)
	(segment
		(start 195.6 160.95)
		(end 195.6 164.075)
		(width 0.1)
		(layer "In3.Cu")
		(net 966)
	)
	(segment
		(start 195.6 164.075)
		(end 189.8 169.875)
		(width 0.1)
		(layer "In3.Cu")
		(net 966)
	)
	(segment
		(start 194.5 159.85)
		(end 195.6 160.95)
		(width 0.1)
		(layer "In5.Cu")
		(net 966)
	)
	(segment
		(start 194.5 159.3)
		(end 194.5 159.85)
		(width 0.1)
		(layer "In5.Cu")
		(net 966)
	)
	(segment
		(start 167.547 185.29)
		(end 167.547 184.953)
		(width 0.182)
		(layer "F.Cu")
		(net 967)
	)
	(segment
		(start 167.547 185.29)
		(end 167.547 185.836)
		(width 0.182)
		(layer "F.Cu")
		(net 967)
	)
	(segment
		(start 167.547 184.953)
		(end 167.55 184.95)
		(width 0.182)
		(layer "F.Cu")
		(net 967)
	)
	(segment
		(start 156.025 170.5)
		(end 155.1125 170.5)
		(width 0.182)
		(layer "F.Cu")
		(net 967)
	)
	(via
		(at 167.55 184.95)
		(size 0.45)
		(drill 0.2)
		(layers "F.Cu" "B.Cu")
		(net 967)
	)
	(via
		(at 155.1125 170.5)
		(size 0.45)
		(drill 0.2)
		(layers "F.Cu" "B.Cu")
		(net 967)
	)
	(segment
		(start 156.1 180.6)
		(end 166.5 180.6)
		(width 0.1)
		(layer "B.Cu")
		(net 967)
	)
	(segment
		(start 154.1 178.6)
		(end 156.1 180.6)
		(width 0.1)
		(layer "B.Cu")
		(net 967)
	)
	(segment
		(start 154.6 170.5)
		(end 154.1 171)
		(width 0.1)
		(layer "B.Cu")
		(net 967)
	)
	(segment
		(start 167.5 181.6)
		(end 167.5 184.9)
		(width 0.1)
		(layer "B.Cu")
		(net 967)
	)
	(segment
		(start 154.1 171)
		(end 154.1 178.6)
		(width 0.1)
		(layer "B.Cu")
		(net 967)
	)
	(segment
		(start 167.55 185.47)
		(end 167.55 184.95)
		(width 0.1)
		(layer "B.Cu")
		(net 967)
	)
	(segment
		(start 167.5 184.9)
		(end 167.55 184.95)
		(width 0.1)
		(layer "B.Cu")
		(net 967)
	)
	(segment
		(start 166.5 180.6)
		(end 167.5 181.6)
		(width 0.1)
		(layer "B.Cu")
		(net 967)
	)
	(segment
		(start 155.1125 170.5)
		(end 154.6 170.5)
		(width 0.1)
		(layer "B.Cu")
		(net 967)
	)
	(segment
		(start 168.497 185.697)
		(end 168.497 185.29)
		(width 0.182)
		(layer "F.Cu")
		(net 968)
	)
	(segment
		(start 168.497 184.953)
		(end 168.5 184.95)
		(width 0.182)
		(layer "F.Cu")
		(net 968)
	)
	(segment
		(start 168.497 185.29)
		(end 168.497 185.836)
		(width 0.182)
		(layer "F.Cu")
		(net 968)
	)
	(segment
		(start 172 170.5)
		(end 172.975 170.5)
		(width 0.182)
		(layer "F.Cu")
		(net 968)
	)
	(segment
		(start 168.497 185.29)
		(end 168.497 184.953)
		(width 0.182)
		(layer "F.Cu")
		(net 968)
	)
	(segment
		(start 168.5 185.7)
		(end 168.497 185.697)
		(width 0.182)
		(layer "F.Cu")
		(net 968)
	)
	(via
		(at 172 170.5)
		(size 0.45)
		(drill 0.2)
		(layers "F.Cu" "B.Cu")
		(net 968)
	)
	(via
		(at 168.5 184.95)
		(size 0.45)
		(drill 0.2)
		(layers "F.Cu" "B.Cu")
		(net 968)
	)
	(segment
		(start 168.5 179.6)
		(end 170.025 178.075)
		(width 0.1)
		(layer "B.Cu")
		(net 968)
	)
	(segment
		(start 168.55 185)
		(end 168.5 184.95)
		(width 0.1)
		(layer "B.Cu")
		(net 968)
	)
	(segment
		(start 168.55 185.47)
		(end 168.55 185)
		(width 0.1)
		(layer "B.Cu")
		(net 968)
	)
	(segment
		(start 170.025 178.075)
		(end 170.025 172.475)
		(width 0.1)
		(layer "B.Cu")
		(net 968)
	)
	(segment
		(start 168.5 184.95)
		(end 168.5 179.6)
		(width 0.1)
		(layer "B.Cu")
		(net 968)
	)
	(segment
		(start 170.025 172.475)
		(end 172 170.5)
		(width 0.1)
		(layer "B.Cu")
		(net 968)
	)
	(segment
		(start 153.15 141)
		(end 152.63 141)
		(width 0.177)
		(layer "F.Cu")
		(net 969)
	)
	(segment
		(start 152.63 141)
		(end 152.58 140.95)
		(width 0.177)
		(layer "F.Cu")
		(net 969)
	)
	(via
		(at 152.58 140.95)
		(size 0.45)
		(drill 0.2)
		(layers "F.Cu" "B.Cu")
		(net 969)
	)
	(segment
		(start 194.100001 163.749999)
		(end 194.100001 164.615001)
		(width 0.177)
		(layer "F.Cu")
		(net 970)
	)
	(segment
		(start 194.100001 164.615001)
		(end 194.6 165.115)
		(width 0.177)
		(layer "F.Cu")
		(net 970)
	)
	(segment
		(start 221.4 136.375)
		(end 219.86 136.375)
		(width 0.184)
		(layer "F.Cu")
		(net 971)
	)
	(segment
		(start 219.86 136.375)
		(end 219.685 136.2)
		(width 0.184)
		(layer "F.Cu")
		(net 971)
	)
	(segment
		(start 221.4 137.025)
		(end 219.86 137.025)
		(width 0.184)
		(layer "F.Cu")
		(net 972)
	)
	(segment
		(start 219.86 137.025)
		(end 219.685 137.2)
		(width 0.184)
		(layer "F.Cu")
		(net 972)
	)
	(segment
		(start 221.4 141.575)
		(end 220.51 141.575)
		(width 0.184)
		(layer "F.Cu")
		(net 973)
	)
	(segment
		(start 220.51 141.575)
		(end 219.685 142.4)
		(width 0.184)
		(layer "F.Cu")
		(net 973)
	)
	(segment
		(start 261.3 187.1)
		(end 261.3 188.55)
		(width 0.1)
		(layer "F.Cu")
		(net 974)
	)
	(segment
		(start 157.4 186.2)
		(end 159 187.8)
		(width 0.1)
		(layer "F.Cu")
		(net 974)
	)
	(segment
		(start 159 188.45)
		(end 159 189.1)
		(width 0.1)
		(layer "F.Cu")
		(net 974)
	)
	(segment
		(start 158 183.515)
		(end 157.4 184.115)
		(width 0.1)
		(layer "F.Cu")
		(net 974)
	)
	(segment
		(start 261.45 187.25)
		(end 261.925 187.25)
		(width 0.1)
		(layer "F.Cu")
		(net 974)
	)
	(segment
		(start 159 189.1)
		(end 158.8 189.3)
		(width 0.1)
		(layer "F.Cu")
		(net 974)
	)
	(segment
		(start 159 187.8)
		(end 159 188.45)
		(width 0.1)
		(layer "F.Cu")
		(net 974)
	)
	(segment
		(start 157.4 184.115)
		(end 157.4 186.2)
		(width 0.1)
		(layer "F.Cu")
		(net 974)
	)
	(segment
		(start 261.3 184.45)
		(end 261.3 187.1)
		(width 0.1)
		(layer "F.Cu")
		(net 974)
	)
	(segment
		(start 261.3 187.1)
		(end 261.45 187.25)
		(width 0.1)
		(layer "F.Cu")
		(net 974)
	)
	(via
		(at 158.8 189.26)
		(size 0.45)
		(drill 0.2)
		(layers "F.Cu" "B.Cu")
		(net 974)
	)
	(via
		(at 261.925 187.25)
		(size 0.45)
		(drill 0.2)
		(layers "F.Cu" "B.Cu")
		(net 974)
	)
	(segment
		(start 187.4 185.2)
		(end 193.2 185.2)
		(width 0.1)
		(layer "In3.Cu")
		(net 974)
	)
	(segment
		(start 158.8 189.3)
		(end 158.8 188.6)
		(width 0.1)
		(layer "In3.Cu")
		(net 974)
	)
	(segment
		(start 196.225 188.225)
		(end 260.95 188.225)
		(width 0.1)
		(layer "In3.Cu")
		(net 974)
	)
	(segment
		(start 159.41 187.99)
		(end 184.61 187.99)
		(width 0.1)
		(layer "In3.Cu")
		(net 974)
	)
	(segment
		(start 260.95 188.225)
		(end 261.925 187.25)
		(width 0.1)
		(layer "In3.Cu")
		(net 974)
	)
	(segment
		(start 193.2 185.2)
		(end 196.225 188.225)
		(width 0.1)
		(layer "In3.Cu")
		(net 974)
	)
	(segment
		(start 184.61 187.99)
		(end 187.4 185.2)
		(width 0.1)
		(layer "In3.Cu")
		(net 974)
	)
	(segment
		(start 158.8 188.6)
		(end 159.41 187.99)
		(width 0.1)
		(layer "In3.Cu")
		(net 974)
	)
	(via
		(at 250.15 149.9)
		(size 0.45)
		(drill 0.2)
		(layers "F.Cu" "B.Cu")
		(net 975)
	)
	(segment
		(start 250.15 149.9)
		(end 250.15 149.5)
		(width 0.177)
		(layer "B.Cu")
		(net 975)
	)
	(segment
		(start 250.15 149.5)
		(end 250.1 149.45)
		(width 0.177)
		(layer "B.Cu")
		(net 975)
	)
	(segment
		(start 230.33 162.18)
		(end 231.565 162.18)
		(width 0.1)
		(layer "F.Cu")
		(net 983)
	)
	(segment
		(start 231.565 162.18)
		(end 231.6 162.215)
		(width 0.1)
		(layer "F.Cu")
		(net 983)
	)
	(segment
		(start 199.7 90.422851)
		(end 199.7 89.800627)
		(width 0.184)
		(layer "F.Cu")
		(net 993)
	)
	(segment
		(start 205.5 119.5)
		(end 205.960401 119.039599)
		(width 0.256)
		(layer "F.Cu")
		(net 993)
	)
	(segment
		(start 205.960401 119.039599)
		(end 206 119.039599)
		(width 0.256)
		(layer "F.Cu")
		(net 993)
	)
	(segment
		(start 199.7 89.800627)
		(end 199.649655 89.750282)
		(width 0.184)
		(layer "F.Cu")
		(net 993)
	)
	(via
		(at 206 119.039599)
		(size 0.45)
		(drill 0.2)
		(layers "F.Cu" "B.Cu")
		(net 993)
	)
	(via
		(at 199.649655 89.750282)
		(size 0.45)
		(drill 0.2)
		(layers "F.Cu" "B.Cu")
		(net 993)
	)
	(segment
		(start 202.625 102.085)
		(end 202.790325 102.085)
		(width 0.1)
		(layer "In7.Cu")
		(net 993)
	)
	(segment
		(start 202.625 101.385)
		(end 202.790325 101.385)
		(width 0.1)
		(layer "In7.Cu")
		(net 993)
	)
	(segment
		(start 202.45 100.82)
		(end 203.34 99.93)
		(width 0.1)
		(layer "In7.Cu")
		(net 993)
	)
	(segment
		(start 205.87 112.57)
		(end 203.32 110.02)
		(width 0.1)
		(layer "In7.Cu")
		(net 993)
	)
	(segment
		(start 205.87 118.909599)
		(end 205.87 112.57)
		(width 0.1)
		(layer "In7.Cu")
		(net 993)
	)
	(segment
		(start 202.790325 101.735)
		(end 202.625 101.735)
		(width 0.1)
		(layer "In7.Cu")
		(net 993)
	)
	(segment
		(start 202.625 103.485)
		(end 202.790325 103.485)
		(width 0.1)
		(layer "In7.Cu")
		(net 993)
	)
	(segment
		(start 203.34 99.93)
		(end 203.34 95.923748)
		(width 0.1)
		(layer "In7.Cu")
		(net 993)
	)
	(segment
		(start 202.790325 101.035)
		(end 202.625 101.035)
		(width 0.1)
		(layer "In7.Cu")
		(net 993)
	)
	(segment
		(start 203.32 108.87)
		(end 202.45 108)
		(width 0.1)
		(layer "In7.Cu")
		(net 993)
	)
	(segment
		(start 202.790325 103.835)
		(end 202.625 103.835)
		(width 0.1)
		(layer "In7.Cu")
		(net 993)
	)
	(segment
		(start 203.32 110.02)
		(end 203.32 108.87)
		(width 0.1)
		(layer "In7.Cu")
		(net 993)
	)
	(segment
		(start 203.34 95.923748)
		(end 199.649655 92.233403)
		(width 0.1)
		(layer "In7.Cu")
		(net 993)
	)
	(segment
		(start 202.45 100.86)
		(end 202.45 100.82)
		(width 0.1)
		(layer "In7.Cu")
		(net 993)
	)
	(segment
		(start 202.625 106.285)
		(end 202.790325 106.285)
		(width 0.1)
		(layer "In7.Cu")
		(net 993)
	)
	(segment
		(start 202.625 107.685)
		(end 202.790325 107.685)
		(width 0.1)
		(layer "In7.Cu")
		(net 993)
	)
	(segment
		(start 202.625 104.885)
		(end 202.790325 104.885)
		(width 0.1)
		(layer "In7.Cu")
		(net 993)
	)
	(segment
		(start 202.625 105.585)
		(end 202.790325 105.585)
		(width 0.1)
		(layer "In7.Cu")
		(net 993)
	)
	(segment
		(start 202.790325 106.635)
		(end 202.625 106.635)
		(width 0.1)
		(layer "In7.Cu")
		(net 993)
	)
	(segment
		(start 206 119.039599)
		(end 205.87 118.909599)
		(width 0.1)
		(layer "In7.Cu")
		(net 993)
	)
	(segment
		(start 202.790325 105.935)
		(end 202.625 105.935)
		(width 0.1)
		(layer "In7.Cu")
		(net 993)
	)
	(segment
		(start 202.45 108)
		(end 202.45 107.86)
		(width 0.1)
		(layer "In7.Cu")
		(net 993)
	)
	(segment
		(start 202.790325 104.535)
		(end 202.625 104.535)
		(width 0.1)
		(layer "In7.Cu")
		(net 993)
	)
	(segment
		(start 202.790325 103.135)
		(end 202.625 103.135)
		(width 0.1)
		(layer "In7.Cu")
		(net 993)
	)
	(segment
		(start 199.649655 92.233403)
		(end 199.649655 89.750282)
		(width 0.1)
		(layer "In7.Cu")
		(net 993)
	)
	(segment
		(start 202.790325 105.235)
		(end 202.625 105.235)
		(width 0.1)
		(layer "In7.Cu")
		(net 993)
	)
	(segment
		(start 202.790325 102.435)
		(end 202.625 102.435)
		(width 0.1)
		(layer "In7.Cu")
		(net 993)
	)
	(segment
		(start 202.625 102.785)
		(end 202.790325 102.785)
		(width 0.1)
		(layer "In7.Cu")
		(net 993)
	)
	(segment
		(start 202.790325 107.335)
		(end 202.625 107.335)
		(width 0.1)
		(layer "In7.Cu")
		(net 993)
	)
	(segment
		(start 202.625 104.185)
		(end 202.790325 104.185)
		(width 0.1)
		(layer "In7.Cu")
		(net 993)
	)
	(segment
		(start 202.625 106.985)
		(end 202.790325 106.985)
		(width 0.1)
		(layer "In7.Cu")
		(net 993)
	)
	(arc
		(start 202.965325 102.61)
		(mid 202.914069 102.486256)
		(end 202.790325 102.435)
		(width 0.1)
		(layer "In7.Cu")
		(net 993)
	)
	(arc
		(start 202.625 105.935)
		(mid 202.501256 105.883744)
		(end 202.45 105.76)
		(width 0.1)
		(layer "In7.Cu")
		(net 993)
	)
	(arc
		(start 202.790325 104.885)
		(mid 202.914069 104.833744)
		(end 202.965325 104.71)
		(width 0.1)
		(layer "In7.Cu")
		(net 993)
	)
	(arc
		(start 202.625 101.735)
		(mid 202.501256 101.683744)
		(end 202.45 101.56)
		(width 0.1)
		(layer "In7.Cu")
		(net 993)
	)
	(arc
		(start 202.625 101.035)
		(mid 202.501256 100.983744)
		(end 202.45 100.86)
		(width 0.1)
		(layer "In7.Cu")
		(net 993)
	)
	(arc
		(start 202.965325 106.81)
		(mid 202.914069 106.686256)
		(end 202.790325 106.635)
		(width 0.1)
		(layer "In7.Cu")
		(net 993)
	)
	(arc
		(start 202.625 102.435)
		(mid 202.501256 102.383744)
		(end 202.45 102.26)
		(width 0.1)
		(layer "In7.Cu")
		(net 993)
	)
	(arc
		(start 202.965325 101.91)
		(mid 202.914069 101.786256)
		(end 202.790325 101.735)
		(width 0.1)
		(layer "In7.Cu")
		(net 993)
	)
	(arc
		(start 202.965325 103.31)
		(mid 202.914069 103.186256)
		(end 202.790325 103.135)
		(width 0.1)
		(layer "In7.Cu")
		(net 993)
	)
	(arc
		(start 202.790325 104.185)
		(mid 202.914069 104.133744)
		(end 202.965325 104.01)
		(width 0.1)
		(layer "In7.Cu")
		(net 993)
	)
	(arc
		(start 202.625 106.635)
		(mid 202.501256 106.583744)
		(end 202.45 106.46)
		(width 0.1)
		(layer "In7.Cu")
		(net 993)
	)
	(arc
		(start 202.790325 103.485)
		(mid 202.914069 103.433744)
		(end 202.965325 103.31)
		(width 0.1)
		(layer "In7.Cu")
		(net 993)
	)
	(arc
		(start 202.45 107.16)
		(mid 202.501256 107.036256)
		(end 202.625 106.985)
		(width 0.1)
		(layer "In7.Cu")
		(net 993)
	)
	(arc
		(start 202.45 101.56)
		(mid 202.501256 101.436256)
		(end 202.625 101.385)
		(width 0.1)
		(layer "In7.Cu")
		(net 993)
	)
	(arc
		(start 202.965325 104.71)
		(mid 202.914069 104.586256)
		(end 202.790325 104.535)
		(width 0.1)
		(layer "In7.Cu")
		(net 993)
	)
	(arc
		(start 202.45 105.06)
		(mid 202.501256 104.936256)
		(end 202.625 104.885)
		(width 0.1)
		(layer "In7.Cu")
		(net 993)
	)
	(arc
		(start 202.45 105.76)
		(mid 202.501256 105.636256)
		(end 202.625 105.585)
		(width 0.1)
		(layer "In7.Cu")
		(net 993)
	)
	(arc
		(start 202.625 107.335)
		(mid 202.501256 107.283744)
		(end 202.45 107.16)
		(width 0.1)
		(layer "In7.Cu")
		(net 993)
	)
	(arc
		(start 202.45 102.96)
		(mid 202.501256 102.836256)
		(end 202.625 102.785)
		(width 0.1)
		(layer "In7.Cu")
		(net 993)
	)
	(arc
		(start 202.45 102.26)
		(mid 202.501256 102.136256)
		(end 202.625 102.085)
		(width 0.1)
		(layer "In7.Cu")
		(net 993)
	)
	(arc
		(start 202.45 107.86)
		(mid 202.501256 107.736256)
		(end 202.625 107.685)
		(width 0.1)
		(layer "In7.Cu")
		(net 993)
	)
	(arc
		(start 202.790325 105.585)
		(mid 202.914069 105.533744)
		(end 202.965325 105.41)
		(width 0.1)
		(layer "In7.Cu")
		(net 993)
	)
	(arc
		(start 202.790325 107.685)
		(mid 202.914069 107.633744)
		(end 202.965325 107.51)
		(width 0.1)
		(layer "In7.Cu")
		(net 993)
	)
	(arc
		(start 202.790325 101.385)
		(mid 202.914069 101.333744)
		(end 202.965325 101.21)
		(width 0.1)
		(layer "In7.Cu")
		(net 993)
	)
	(arc
		(start 202.965325 107.51)
		(mid 202.914069 107.386256)
		(end 202.790325 107.335)
		(width 0.1)
		(layer "In7.Cu")
		(net 993)
	)
	(arc
		(start 202.45 104.36)
		(mid 202.501256 104.236256)
		(end 202.625 104.185)
		(width 0.1)
		(layer "In7.Cu")
		(net 993)
	)
	(arc
		(start 202.965325 106.11)
		(mid 202.914069 105.986256)
		(end 202.790325 105.935)
		(width 0.1)
		(layer "In7.Cu")
		(net 993)
	)
	(arc
		(start 202.45 106.46)
		(mid 202.501256 106.336256)
		(end 202.625 106.285)
		(width 0.1)
		(layer "In7.Cu")
		(net 993)
	)
	(arc
		(start 202.790325 102.085)
		(mid 202.914069 102.033744)
		(end 202.965325 101.91)
		(width 0.1)
		(layer "In7.Cu")
		(net 993)
	)
	(arc
		(start 202.625 103.135)
		(mid 202.501256 103.083744)
		(end 202.45 102.96)
		(width 0.1)
		(layer "In7.Cu")
		(net 993)
	)
	(arc
		(start 202.965325 105.41)
		(mid 202.914069 105.286256)
		(end 202.790325 105.235)
		(width 0.1)
		(layer "In7.Cu")
		(net 993)
	)
	(arc
		(start 202.625 105.235)
		(mid 202.501256 105.183744)
		(end 202.45 105.06)
		(width 0.1)
		(layer "In7.Cu")
		(net 993)
	)
	(arc
		(start 202.790325 106.285)
		(mid 202.914069 106.233744)
		(end 202.965325 106.11)
		(width 0.1)
		(layer "In7.Cu")
		(net 993)
	)
	(arc
		(start 202.790325 102.785)
		(mid 202.914069 102.733744)
		(end 202.965325 102.61)
		(width 0.1)
		(layer "In7.Cu")
		(net 993)
	)
	(arc
		(start 202.965325 101.21)
		(mid 202.914069 101.086256)
		(end 202.790325 101.035)
		(width 0.1)
		(layer "In7.Cu")
		(net 993)
	)
	(arc
		(start 202.625 103.835)
		(mid 202.501256 103.783744)
		(end 202.45 103.66)
		(width 0.1)
		(layer "In7.Cu")
		(net 993)
	)
	(arc
		(start 202.625 104.535)
		(mid 202.501256 104.483744)
		(end 202.45 104.36)
		(width 0.1)
		(layer "In7.Cu")
		(net 993)
	)
	(arc
		(start 202.45 103.66)
		(mid 202.501256 103.536256)
		(end 202.625 103.485)
		(width 0.1)
		(layer "In7.Cu")
		(net 993)
	)
	(arc
		(start 202.965325 104.01)
		(mid 202.914069 103.886256)
		(end 202.790325 103.835)
		(width 0.1)
		(layer "In7.Cu")
		(net 993)
	)
	(arc
		(start 202.790325 106.985)
		(mid 202.914069 106.933744)
		(end 202.965325 106.81)
		(width 0.1)
		(layer "In7.Cu")
		(net 993)
	)
	(segment
		(start 251.75 140.325)
		(end 252.125 140.7)
		(width 0.1)
		(layer "F.Cu")
		(net 996)
	)
	(segment
		(start 262.3 132.99388)
		(end 262.2102 132.90408)
		(width 0.182)
		(layer "F.Cu")
		(net 996)
	)
	(segment
		(start 251.75 139.9375)
		(end 251.75 140.325)
		(width 0.1)
		(layer "F.Cu")
		(net 996)
	)
	(segment
		(start 251.65 139.8375)
		(end 251.75 139.9375)
		(width 0.1)
		(layer "F.Cu")
		(net 996)
	)
	(segment
		(start 262.3 133.6)
		(end 262.3 132.99388)
		(width 0.182)
		(layer "F.Cu")
		(net 996)
	)
	(via
		(at 262.2102 132.90408)
		(size 0.45)
		(drill 0.2)
		(layers "F.Cu" "B.Cu")
		(net 996)
	)
	(via
		(at 252.125 140.7)
		(size 0.45)
		(drill 0.2)
		(layers "F.Cu" "B.Cu")
		(net 996)
	)
	(segment
		(start 260.3 133.6)
		(end 260.99592 132.90408)
		(width 0.1)
		(layer "In3.Cu")
		(net 996)
	)
	(segment
		(start 260.99592 132.90408)
		(end 262.2102 132.90408)
		(width 0.1)
		(layer "In3.Cu")
		(net 996)
	)
	(segment
		(start 252.125 140.7)
		(end 252.225 140.8)
		(width 0.1)
		(layer "In3.Cu")
		(net 996)
	)
	(segment
		(start 259.1 140.8)
		(end 260.3 139.6)
		(width 0.1)
		(layer "In3.Cu")
		(net 996)
	)
	(segment
		(start 260.3 139.6)
		(end 260.3 133.6)
		(width 0.1)
		(layer "In3.Cu")
		(net 996)
	)
	(segment
		(start 252.225 140.8)
		(end 259.1 140.8)
		(width 0.1)
		(layer "In3.Cu")
		(net 996)
	)
	(segment
		(start 261.9 133.4)
		(end 261.9 133.6)
		(width 0.182)
		(layer "F.Cu")
		(net 997)
	)
	(segment
		(start 252.3375 139.84525)
		(end 252.3375 139.15)
		(width 0.182)
		(layer "F.Cu")
		(net 997)
	)
	(segment
		(start 261.7 132.5)
		(end 261.7 133.2)
		(width 0.182)
		(layer "F.Cu")
		(net 997)
	)
	(segment
		(start 261.7 133.2)
		(end 261.9 133.4)
		(width 0.182)
		(layer "F.Cu")
		(net 997)
	)
	(segment
		(start 252.1505 140.03225)
		(end 252.3375 139.84525)
		(width 0.182)
		(layer "F.Cu")
		(net 997)
	)
	(via
		(at 261.7 132.5)
		(size 0.45)
		(drill 0.2)
		(layers "F.Cu" "B.Cu")
		(net 997)
	)
	(via
		(at 252.1505 140.03225)
		(size 0.45)
		(drill 0.2)
		(layers "F.Cu" "B.Cu")
		(net 997)
	)
	(segment
		(start 261 132.5)
		(end 261.7 132.5)
		(width 0.1)
		(layer "In3.Cu")
		(net 997)
	)
	(segment
		(start 252.1505 140.0505)
		(end 252.6 140.5)
		(width 0.1)
		(layer "In3.Cu")
		(net 997)
	)
	(segment
		(start 260 139.4)
		(end 260 133.5)
		(width 0.1)
		(layer "In3.Cu")
		(net 997)
	)
	(segment
		(start 260 133.5)
		(end 261 132.5)
		(width 0.1)
		(layer "In3.Cu")
		(net 997)
	)
	(segment
		(start 252.1505 140.03225)
		(end 252.1505 140.0505)
		(width 0.1)
		(layer "In3.Cu")
		(net 997)
	)
	(segment
		(start 252.6 140.5)
		(end 258.9 140.5)
		(width 0.1)
		(layer "In3.Cu")
		(net 997)
	)
	(segment
		(start 258.9 140.5)
		(end 260 139.4)
		(width 0.1)
		(layer "In3.Cu")
		(net 997)
	)
	(segment
		(start 251.25 140.4)
		(end 251.25 139.9375)
		(width 0.1)
		(layer "F.Cu")
		(net 998)
	)
	(segment
		(start 251.9 141.225)
		(end 251.9 141.05)
		(width 0.1)
		(layer "F.Cu")
		(net 998)
	)
	(segment
		(start 251.25 139.9375)
		(end 251.15 139.8375)
		(width 0.1)
		(layer "F.Cu")
		(net 998)
	)
	(segment
		(start 251.9 141.05)
		(end 251.25 140.4)
		(width 0.1)
		(layer "F.Cu")
		(net 998)
	)
	(segment
		(start 260.920341 134.55)
		(end 260.778288 134.692053)
		(width 0.182)
		(layer "F.Cu")
		(net 998)
	)
	(segment
		(start 261.35 134.55)
		(end 260.920341 134.55)
		(width 0.182)
		(layer "F.Cu")
		(net 998)
	)
	(via
		(at 260.778288 134.692053)
		(size 0.45)
		(drill 0.2)
		(layers "F.Cu" "B.Cu")
		(net 998)
	)
	(via
		(at 251.9 141.225)
		(size 0.45)
		(drill 0.2)
		(layers "F.Cu" "B.Cu")
		(net 998)
	)
	(segment
		(start 260.6 134.870341)
		(end 260.778288 134.692053)
		(width 0.1)
		(layer "In3.Cu")
		(net 998)
	)
	(segment
		(start 259.3 141.1)
		(end 260.6 139.8)
		(width 0.1)
		(layer "In3.Cu")
		(net 998)
	)
	(segment
		(start 251.9 141.225)
		(end 252.025 141.1)
		(width 0.1)
		(layer "In3.Cu")
		(net 998)
	)
	(segment
		(start 260.6 139.8)
		(end 260.6 134.870341)
		(width 0.1)
		(layer "In3.Cu")
		(net 998)
	)
	(segment
		(start 252.025 141.1)
		(end 259.3 141.1)
		(width 0.1)
		(layer "In3.Cu")
		(net 998)
	)
	(segment
		(start 197.041252 96.6)
		(end 196.991252 96.65)
		(width 0.182)
		(layer "F.Cu")
		(net 1001)
	)
	(segment
		(start 198.022851 96.6)
		(end 197.041252 96.6)
		(width 0.182)
		(layer "F.Cu")
		(net 1001)
	)
	(segment
		(start 201.5 120.5)
		(end 202 120)
		(width 0.256)
		(layer "F.Cu")
		(net 1001)
	)
	(via
		(at 196.991252 96.65)
		(size 0.45)
		(drill 0.2)
		(layers "F.Cu" "B.Cu")
		(net 1001)
	)
	(via
		(at 202 120)
		(size 0.45)
		(drill 0.2)
		(layers "F.Cu" "B.Cu")
		(net 1001)
	)
	(segment
		(start 193.82 95.67)
		(end 193.82 95.97)
		(width 0.1)
		(layer "In7.Cu")
		(net 1001)
	)
	(segment
		(start 197.09 110.42)
		(end 201.29 114.62)
		(width 0.1)
		(layer "In7.Cu")
		(net 1001)
	)
	(segment
		(start 196.991252 96.65)
		(end 195.481252 95.14)
		(width 0.1)
		(layer "In7.Cu")
		(net 1001)
	)
	(segment
		(start 193.82 106.3)
		(end 197.09 109.57)
		(width 0.1)
		(layer "In7.Cu")
		(net 1001)
	)
	(segment
		(start 201.29 114.62)
		(end 201.29 117.407158)
		(width 0.1)
		(layer "In7.Cu")
		(net 1001)
	)
	(segment
		(start 194.02 96.17)
		(end 194.500951 96.17)
		(width 0.1)
		(layer "In7.Cu")
		(net 1001)
	)
	(segment
		(start 193.82 97.62)
		(end 193.82 106.3)
		(width 0.1)
		(layer "In7.Cu")
		(net 1001)
	)
	(segment
		(start 194.500951 97.37)
		(end 194.02 97.37)
		(width 0.1)
		(layer "In7.Cu")
		(net 1001)
	)
	(segment
		(start 194.500951 96.57)
		(end 194.02 96.57)
		(width 0.1)
		(layer "In7.Cu")
		(net 1001)
	)
	(segment
		(start 194.02 96.97)
		(end 194.500951 96.97)
		(width 0.1)
		(layer "In7.Cu")
		(net 1001)
	)
	(segment
		(start 201.29 117.407158)
		(end 201.575 117.692158)
		(width 0.1)
		(layer "In7.Cu")
		(net 1001)
	)
	(segment
		(start 201.575 119.575)
		(end 202 120)
		(width 0.1)
		(layer "In7.Cu")
		(net 1001)
	)
	(segment
		(start 194.35 95.14)
		(end 193.82 95.67)
		(width 0.1)
		(layer "In7.Cu")
		(net 1001)
	)
	(segment
		(start 201.575 117.692158)
		(end 201.575 119.575)
		(width 0.1)
		(layer "In7.Cu")
		(net 1001)
	)
	(segment
		(start 193.82 97.57)
		(end 193.82 97.62)
		(width 0.1)
		(layer "In7.Cu")
		(net 1001)
	)
	(segment
		(start 197.09 109.57)
		(end 197.09 110.42)
		(width 0.1)
		(layer "In7.Cu")
		(net 1001)
	)
	(segment
		(start 195.481252 95.14)
		(end 194.35 95.14)
		(width 0.1)
		(layer "In7.Cu")
		(net 1001)
	)
	(arc
		(start 193.82 96.77)
		(mid 193.878579 96.911421)
		(end 194.02 96.97)
		(width 0.1)
		(layer "In7.Cu")
		(net 1001)
	)
	(arc
		(start 194.02 96.57)
		(mid 193.878579 96.628579)
		(end 193.82 96.77)
		(width 0.1)
		(layer "In7.Cu")
		(net 1001)
	)
	(arc
		(start 194.02 97.37)
		(mid 193.878579 97.428579)
		(end 193.82 97.57)
		(width 0.1)
		(layer "In7.Cu")
		(net 1001)
	)
	(arc
		(start 193.82 95.97)
		(mid 193.878579 96.111421)
		(end 194.02 96.17)
		(width 0.1)
		(layer "In7.Cu")
		(net 1001)
	)
	(arc
		(start 194.700951 97.17)
		(mid 194.642372 97.311421)
		(end 194.500951 97.37)
		(width 0.1)
		(layer "In7.Cu")
		(net 1001)
	)
	(arc
		(start 194.500951 96.17)
		(mid 194.642372 96.228579)
		(end 194.700951 96.37)
		(width 0.1)
		(layer "In7.Cu")
		(net 1001)
	)
	(arc
		(start 194.700951 96.37)
		(mid 194.642372 96.511421)
		(end 194.500951 96.57)
		(width 0.1)
		(layer "In7.Cu")
		(net 1001)
	)
	(arc
		(start 194.500951 96.97)
		(mid 194.642372 97.028579)
		(end 194.700951 97.17)
		(width 0.1)
		(layer "In7.Cu")
		(net 1001)
	)
	(segment
		(start 200.2 90.422851)
		(end 200.2 89.483748)
		(width 0.184)
		(layer "F.Cu")
		(net 1002)
	)
	(segment
		(start 205.5 120.5)
		(end 206 120)
		(width 0.256)
		(layer "F.Cu")
		(net 1002)
	)
	(segment
		(start 200.2 89.483748)
		(end 200.141252 89.425)
		(width 0.184)
		(layer "F.Cu")
		(net 1002)
	)
	(via
		(at 200.141252 89.425)
		(size 0.45)
		(drill 0.2)
		(layers "F.Cu" "B.Cu")
		(net 1002)
	)
	(via
		(at 206 120)
		(size 0.45)
		(drill 0.2)
		(layers "F.Cu" "B.Cu")
		(net 1002)
	)
	(segment
		(start 203.566252 106.676252)
		(end 203.487342 106.676252)
		(width 0.1)
		(layer "In7.Cu")
		(net 1002)
	)
	(segment
		(start 203.741252 95.725)
		(end 203.741252 100.201252)
		(width 0.1)
		(layer "In7.Cu")
		(net 1002)
	)
	(segment
		(start 203.487342 107.026252)
		(end 203.566252 107.026252)
		(width 0.1)
		(layer "In7.Cu")
		(net 1002)
	)
	(segment
		(start 203.566252 103.176252)
		(end 203.487342 103.176252)
		(width 0.1)
		(layer "In7.Cu")
		(net 1002)
	)
	(segment
		(start 206.2 118.5)
		(end 206.375 118.675)
		(width 0.1)
		(layer "In7.Cu")
		(net 1002)
	)
	(segment
		(start 203.566252 101.076252)
		(end 203.487342 101.076252)
		(width 0.1)
		(layer "In7.Cu")
		(net 1002)
	)
	(segment
		(start 203.741252 109.941252)
		(end 206.2 112.4)
		(width 0.1)
		(layer "In7.Cu")
		(net 1002)
	)
	(segment
		(start 206.375 119.625)
		(end 206 120)
		(width 0.1)
		(layer "In7.Cu")
		(net 1002)
	)
	(segment
		(start 203.741252 108.601252)
		(end 203.741252 108.651252)
		(width 0.1)
		(layer "In7.Cu")
		(net 1002)
	)
	(segment
		(start 203.487342 103.526252)
		(end 203.566252 103.526252)
		(width 0.1)
		(layer "In7.Cu")
		(net 1002)
	)
	(segment
		(start 206.375 118.675)
		(end 206.375 119.625)
		(width 0.1)
		(layer "In7.Cu")
		(net 1002)
	)
	(segment
		(start 203.487342 101.426252)
		(end 203.566252 101.426252)
		(width 0.1)
		(layer "In7.Cu")
		(net 1002)
	)
	(segment
		(start 203.566252 108.076252)
		(end 203.487342 108.076252)
		(width 0.1)
		(layer "In7.Cu")
		(net 1002)
	)
	(segment
		(start 203.566252 105.276252)
		(end 203.487342 105.276252)
		(width 0.1)
		(layer "In7.Cu")
		(net 1002)
	)
	(segment
		(start 203.487342 102.826252)
		(end 203.566252 102.826252)
		(width 0.1)
		(layer "In7.Cu")
		(net 1002)
	)
	(segment
		(start 203.487342 104.226252)
		(end 203.566252 104.226252)
		(width 0.1)
		(layer "In7.Cu")
		(net 1002)
	)
	(segment
		(start 203.487342 107.726252)
		(end 203.566252 107.726252)
		(width 0.1)
		(layer "In7.Cu")
		(net 1002)
	)
	(segment
		(start 203.566252 105.976252)
		(end 203.487342 105.976252)
		(width 0.1)
		(layer "In7.Cu")
		(net 1002)
	)
	(segment
		(start 206.2 112.4)
		(end 206.2 118.5)
		(width 0.1)
		(layer "In7.Cu")
		(net 1002)
	)
	(segment
		(start 203.566252 102.476252)
		(end 203.487342 102.476252)
		(width 0.1)
		(layer "In7.Cu")
		(net 1002)
	)
	(segment
		(start 203.566252 103.876252)
		(end 203.487342 103.876252)
		(width 0.1)
		(layer "In7.Cu")
		(net 1002)
	)
	(segment
		(start 200.141252 92.125)
		(end 203.741252 95.725)
		(width 0.1)
		(layer "In7.Cu")
		(net 1002)
	)
	(segment
		(start 203.487342 100.726252)
		(end 203.566252 100.726252)
		(width 0.1)
		(layer "In7.Cu")
		(net 1002)
	)
	(segment
		(start 203.566252 104.576252)
		(end 203.487342 104.576252)
		(width 0.1)
		(layer "In7.Cu")
		(net 1002)
	)
	(segment
		(start 203.741252 108.651252)
		(end 203.741252 109.941252)
		(width 0.1)
		(layer "In7.Cu")
		(net 1002)
	)
	(segment
		(start 200.141252 89.425)
		(end 200.141252 92.125)
		(width 0.1)
		(layer "In7.Cu")
		(net 1002)
	)
	(segment
		(start 203.566252 107.376252)
		(end 203.487342 107.376252)
		(width 0.1)
		(layer "In7.Cu")
		(net 1002)
	)
	(segment
		(start 203.487342 104.926252)
		(end 203.566252 104.926252)
		(width 0.1)
		(layer "In7.Cu")
		(net 1002)
	)
	(segment
		(start 203.487342 105.626252)
		(end 203.566252 105.626252)
		(width 0.1)
		(layer "In7.Cu")
		(net 1002)
	)
	(segment
		(start 203.487342 102.126252)
		(end 203.566252 102.126252)
		(width 0.1)
		(layer "In7.Cu")
		(net 1002)
	)
	(segment
		(start 203.566252 100.376252)
		(end 203.487342 100.376252)
		(width 0.1)
		(layer "In7.Cu")
		(net 1002)
	)
	(segment
		(start 203.487342 106.326252)
		(end 203.566252 106.326252)
		(width 0.1)
		(layer "In7.Cu")
		(net 1002)
	)
	(segment
		(start 203.566252 101.776252)
		(end 203.487342 101.776252)
		(width 0.1)
		(layer "In7.Cu")
		(net 1002)
	)
	(segment
		(start 203.487342 108.426252)
		(end 203.566252 108.426252)
		(width 0.1)
		(layer "In7.Cu")
		(net 1002)
	)
	(arc
		(start 203.312342 105.451252)
		(mid 203.363598 105.574996)
		(end 203.487342 105.626252)
		(width 0.1)
		(layer "In7.Cu")
		(net 1002)
	)
	(arc
		(start 203.312342 102.651252)
		(mid 203.363598 102.774996)
		(end 203.487342 102.826252)
		(width 0.1)
		(layer "In7.Cu")
		(net 1002)
	)
	(arc
		(start 203.566252 104.226252)
		(mid 203.689996 104.277508)
		(end 203.741252 104.401252)
		(width 0.1)
		(layer "In7.Cu")
		(net 1002)
	)
	(arc
		(start 203.487342 103.176252)
		(mid 203.363598 103.227508)
		(end 203.312342 103.351252)
		(width 0.1)
		(layer "In7.Cu")
		(net 1002)
	)
	(arc
		(start 203.312342 104.051252)
		(mid 203.363598 104.174996)
		(end 203.487342 104.226252)
		(width 0.1)
		(layer "In7.Cu")
		(net 1002)
	)
	(arc
		(start 203.741252 101.601252)
		(mid 203.689996 101.724996)
		(end 203.566252 101.776252)
		(width 0.1)
		(layer "In7.Cu")
		(net 1002)
	)
	(arc
		(start 203.312342 107.551252)
		(mid 203.363598 107.674996)
		(end 203.487342 107.726252)
		(width 0.1)
		(layer "In7.Cu")
		(net 1002)
	)
	(arc
		(start 203.312342 106.151252)
		(mid 203.363598 106.274996)
		(end 203.487342 106.326252)
		(width 0.1)
		(layer "In7.Cu")
		(net 1002)
	)
	(arc
		(start 203.566252 107.726252)
		(mid 203.689996 107.777508)
		(end 203.741252 107.901252)
		(width 0.1)
		(layer "In7.Cu")
		(net 1002)
	)
	(arc
		(start 203.487342 103.876252)
		(mid 203.363598 103.927508)
		(end 203.312342 104.051252)
		(width 0.1)
		(layer "In7.Cu")
		(net 1002)
	)
	(arc
		(start 203.312342 100.551252)
		(mid 203.363598 100.674996)
		(end 203.487342 100.726252)
		(width 0.1)
		(layer "In7.Cu")
		(net 1002)
	)
	(arc
		(start 203.312342 101.951252)
		(mid 203.363598 102.074996)
		(end 203.487342 102.126252)
		(width 0.1)
		(layer "In7.Cu")
		(net 1002)
	)
	(arc
		(start 203.487342 108.076252)
		(mid 203.363598 108.127508)
		(end 203.312342 108.251252)
		(width 0.1)
		(layer "In7.Cu")
		(net 1002)
	)
	(arc
		(start 203.741252 102.301252)
		(mid 203.689996 102.424996)
		(end 203.566252 102.476252)
		(width 0.1)
		(layer "In7.Cu")
		(net 1002)
	)
	(arc
		(start 203.487342 100.376252)
		(mid 203.363598 100.427508)
		(end 203.312342 100.551252)
		(width 0.1)
		(layer "In7.Cu")
		(net 1002)
	)
	(arc
		(start 203.566252 104.926252)
		(mid 203.689996 104.977508)
		(end 203.741252 105.101252)
		(width 0.1)
		(layer "In7.Cu")
		(net 1002)
	)
	(arc
		(start 203.566252 106.326252)
		(mid 203.689996 106.377508)
		(end 203.741252 106.501252)
		(width 0.1)
		(layer "In7.Cu")
		(net 1002)
	)
	(arc
		(start 203.741252 104.401252)
		(mid 203.689996 104.524996)
		(end 203.566252 104.576252)
		(width 0.1)
		(layer "In7.Cu")
		(net 1002)
	)
	(arc
		(start 203.566252 103.526252)
		(mid 203.689996 103.577508)
		(end 203.741252 103.701252)
		(width 0.1)
		(layer "In7.Cu")
		(net 1002)
	)
	(arc
		(start 203.741252 100.901252)
		(mid 203.689996 101.024996)
		(end 203.566252 101.076252)
		(width 0.1)
		(layer "In7.Cu")
		(net 1002)
	)
	(arc
		(start 203.566252 102.126252)
		(mid 203.689996 102.177508)
		(end 203.741252 102.301252)
		(width 0.1)
		(layer "In7.Cu")
		(net 1002)
	)
	(arc
		(start 203.487342 105.276252)
		(mid 203.363598 105.327508)
		(end 203.312342 105.451252)
		(width 0.1)
		(layer "In7.Cu")
		(net 1002)
	)
	(arc
		(start 203.566252 101.426252)
		(mid 203.689996 101.477508)
		(end 203.741252 101.601252)
		(width 0.1)
		(layer "In7.Cu")
		(net 1002)
	)
	(arc
		(start 203.312342 103.351252)
		(mid 203.363598 103.474996)
		(end 203.487342 103.526252)
		(width 0.1)
		(layer "In7.Cu")
		(net 1002)
	)
	(arc
		(start 203.566252 105.626252)
		(mid 203.689996 105.677508)
		(end 203.741252 105.801252)
		(width 0.1)
		(layer "In7.Cu")
		(net 1002)
	)
	(arc
		(start 203.741252 106.501252)
		(mid 203.689996 106.624996)
		(end 203.566252 106.676252)
		(width 0.1)
		(layer "In7.Cu")
		(net 1002)
	)
	(arc
		(start 203.312342 108.251252)
		(mid 203.363598 108.374996)
		(end 203.487342 108.426252)
		(width 0.1)
		(layer "In7.Cu")
		(net 1002)
	)
	(arc
		(start 203.566252 100.726252)
		(mid 203.689996 100.777508)
		(end 203.741252 100.901252)
		(width 0.1)
		(layer "In7.Cu")
		(net 1002)
	)
	(arc
		(start 203.312342 104.751252)
		(mid 203.363598 104.874996)
		(end 203.487342 104.926252)
		(width 0.1)
		(layer "In7.Cu")
		(net 1002)
	)
	(arc
		(start 203.487342 105.976252)
		(mid 203.363598 106.027508)
		(end 203.312342 106.151252)
		(width 0.1)
		(layer "In7.Cu")
		(net 1002)
	)
	(arc
		(start 203.487342 106.676252)
		(mid 203.363598 106.727508)
		(end 203.312342 106.851252)
		(width 0.1)
		(layer "In7.Cu")
		(net 1002)
	)
	(arc
		(start 203.741252 105.101252)
		(mid 203.689996 105.224996)
		(end 203.566252 105.276252)
		(width 0.1)
		(layer "In7.Cu")
		(net 1002)
	)
	(arc
		(start 203.566252 102.826252)
		(mid 203.689996 102.877508)
		(end 203.741252 103.001252)
		(width 0.1)
		(layer "In7.Cu")
		(net 1002)
	)
	(arc
		(start 203.741252 107.201252)
		(mid 203.689996 107.324996)
		(end 203.566252 107.376252)
		(width 0.1)
		(layer "In7.Cu")
		(net 1002)
	)
	(arc
		(start 203.312342 101.251252)
		(mid 203.363598 101.374996)
		(end 203.487342 101.426252)
		(width 0.1)
		(layer "In7.Cu")
		(net 1002)
	)
	(arc
		(start 203.741252 103.701252)
		(mid 203.689996 103.824996)
		(end 203.566252 103.876252)
		(width 0.1)
		(layer "In7.Cu")
		(net 1002)
	)
	(arc
		(start 203.487342 102.476252)
		(mid 203.363598 102.527508)
		(end 203.312342 102.651252)
		(width 0.1)
		(layer "In7.Cu")
		(net 1002)
	)
	(arc
		(start 203.741252 105.801252)
		(mid 203.689996 105.924996)
		(end 203.566252 105.976252)
		(width 0.1)
		(layer "In7.Cu")
		(net 1002)
	)
	(arc
		(start 203.312342 106.851252)
		(mid 203.363598 106.974996)
		(end 203.487342 107.026252)
		(width 0.1)
		(layer "In7.Cu")
		(net 1002)
	)
	(arc
		(start 203.487342 101.776252)
		(mid 203.363598 101.827508)
		(end 203.312342 101.951252)
		(width 0.1)
		(layer "In7.Cu")
		(net 1002)
	)
	(arc
		(start 203.741252 107.901252)
		(mid 203.689996 108.024996)
		(end 203.566252 108.076252)
		(width 0.1)
		(layer "In7.Cu")
		(net 1002)
	)
	(arc
		(start 203.487342 107.376252)
		(mid 203.363598 107.427508)
		(end 203.312342 107.551252)
		(width 0.1)
		(layer "In7.Cu")
		(net 1002)
	)
	(arc
		(start 203.741252 100.201252)
		(mid 203.689996 100.324996)
		(end 203.566252 100.376252)
		(width 0.1)
		(layer "In7.Cu")
		(net 1002)
	)
	(arc
		(start 203.487342 104.576252)
		(mid 203.363598 104.627508)
		(end 203.312342 104.751252)
		(width 0.1)
		(layer "In7.Cu")
		(net 1002)
	)
	(arc
		(start 203.566252 107.026252)
		(mid 203.689996 107.077508)
		(end 203.741252 107.201252)
		(width 0.1)
		(layer "In7.Cu")
		(net 1002)
	)
	(arc
		(start 203.566252 108.426252)
		(mid 203.689996 108.477508)
		(end 203.741252 108.601252)
		(width 0.1)
		(layer "In7.Cu")
		(net 1002)
	)
	(arc
		(start 203.741252 103.001252)
		(mid 203.689996 103.124996)
		(end 203.566252 103.176252)
		(width 0.1)
		(layer "In7.Cu")
		(net 1002)
	)
	(arc
		(start 203.487342 101.076252)
		(mid 203.363598 101.127508)
		(end 203.312342 101.251252)
		(width 0.1)
		(layer "In7.Cu")
		(net 1002)
	)
	(segment
		(start 197.341252 91.1)
		(end 197.291252 91.05)
		(width 0.182)
		(layer "F.Cu")
		(net 1008)
	)
	(segment
		(start 204.97121 121.02879)
		(end 204.5 121.5)
		(width 0.256)
		(layer "F.Cu")
		(net 1008)
	)
	(segment
		(start 205.018429 121.02879)
		(end 204.97121 121.02879)
		(width 0.256)
		(layer "F.Cu")
		(net 1008)
	)
	(segment
		(start 198.022851 91.1)
		(end 197.341252 91.1)
		(width 0.182)
		(layer "F.Cu")
		(net 1008)
	)
	(via
		(at 205.018429 121.02879)
		(size 0.45)
		(drill 0.2)
		(layers "F.Cu" "B.Cu")
		(net 1008)
	)
	(via
		(at 197.291252 91.05)
		(size 0.45)
		(drill 0.2)
		(layers "F.Cu" "B.Cu")
		(net 1008)
	)
	(segment
		(start 200.382972 94.204401)
		(end 199.487626 95.099751)
		(width 0.1)
		(layer "In7.Cu")
		(net 1008)
	)
	(segment
		(start 202.53 97.07)
		(end 201.384864 95.924863)
		(width 0.1)
		(layer "In7.Cu")
		(net 1008)
	)
	(segment
		(start 205.01 115.77)
		(end 205.01 112.91)
		(width 0.1)
		(layer "In7.Cu")
		(net 1008)
	)
	(segment
		(start 199.888 93.709429)
		(end 198.992654 94.604779)
		(width 0.1)
		(layer "In7.Cu")
		(net 1008)
	)
	(segment
		(start 199.157488 93.450001)
		(end 199.157487 93.449999)
		(width 0.1)
		(layer "In7.Cu")
		(net 1008)
	)
	(segment
		(start 198.992654 94.604779)
		(end 198.992654 94.604778)
		(width 0.1)
		(layer "In7.Cu")
		(net 1008)
	)
	(segment
		(start 198.745167 94.604779)
		(end 198.745167 94.60478)
		(width 0.1)
		(layer "In7.Cu")
		(net 1008)
	)
	(segment
		(start 200.766148 95.306147)
		(end 201.125433 94.946862)
		(width 0.1)
		(layer "In7.Cu")
		(net 1008)
	)
	(segment
		(start 200.13549 93.709431)
		(end 200.135489 93.70943)
		(width 0.1)
		(layer "In7.Cu")
		(net 1008)
	)
	(segment
		(start 201.620405 95.441833)
		(end 201.620405 95.441834)
		(width 0.1)
		(layer "In7.Cu")
		(net 1008)
	)
	(segment
		(start 202.35 110.25)
		(end 202.35 108.88)
		(width 0.1)
		(layer "In7.Cu")
		(net 1008)
	)
	(segment
		(start 199.841177 95.24117)
		(end 200.271174 94.811174)
		(width 0.1)
		(layer "In7.Cu")
		(net 1008)
	)
	(segment
		(start 200.300794 95.771497)
		(end 200.766146 95.306146)
		(width 0.1)
		(layer "In7.Cu")
		(net 1008)
	)
	(segment
		(start 204.8 117.15)
		(end 204.8 115.98)
		(width 0.1)
		(layer "In7.Cu")
		(net 1008)
	)
	(segment
		(start 201.372916 95.194345)
		(end 200.548281 96.018985)
		(width 0.1)
		(layer "In7.Cu")
		(net 1008)
	)
	(segment
		(start 198.745167 94.357292)
		(end 199.640516 93.461944)
		(width 0.1)
		(layer "In7.Cu")
		(net 1008)
	)
	(segment
		(start 205.018429 121.02879)
		(end 205.375 120.672219)
		(width 0.1)
		(layer "In7.Cu")
		(net 1008)
	)
	(segment
		(start 200.300794 96.018985)
		(end 200.300793 96.018984)
		(width 0.1)
		(layer "In7.Cu")
		(net 1008)
	)
	(segment
		(start 198.76 93.3)
		(end 198.76 92.518748)
		(width 0.1)
		(layer "In7.Cu")
		(net 1008)
	)
	(segment
		(start 199.841177 95.488657)
		(end 199.841177 95.488658)
		(width 0.1)
		(layer "In7.Cu")
		(net 1008)
	)
	(segment
		(start 202.35 108.88)
		(end 200.954874 107.484874)
		(width 0.1)
		(layer "In7.Cu")
		(net 1008)
	)
	(segment
		(start 199.640517 93.214458)
		(end 199.640516 93.214458)
		(width 0.1)
		(layer "In7.Cu")
		(net 1008)
	)
	(segment
		(start 200.271176 94.811175)
		(end 200.630461 94.45189)
		(width 0.1)
		(layer "In7.Cu")
		(net 1008)
	)
	(segment
		(start 200.877944 94.699373)
		(end 200.088664 95.488657)
		(width 0.1)
		(layer "In7.Cu")
		(net 1008)
	)
	(segment
		(start 200.947157 107.484874)
		(end 200.81 107.347717)
		(width 0.1)
		(layer "In7.Cu")
		(net 1008)
	)
	(segment
		(start 201.620406 95.194347)
		(end 201.620405 95.194346)
		(width 0.1)
		(layer "In7.Cu")
		(net 1008)
	)
	(segment
		(start 200.088664 95.488657)
		(end 200.088664 95.488656)
		(width 0.1)
		(layer "In7.Cu")
		(net 1008)
	)
	(segment
		(start 201.384863 95.677376)
		(end 201.620405 95.441833)
		(width 0.1)
		(layer "In7.Cu")
		(net 1008)
	)
	(segment
		(start 205.01 112.91)
		(end 202.35 110.25)
		(width 0.1)
		(layer "In7.Cu")
		(net 1008)
	)
	(segment
		(start 199.776202 94.316202)
		(end 199.776204 94.316203)
		(width 0.1)
		(layer "In7.Cu")
		(net 1008)
	)
	(segment
		(start 200.548281 96.018985)
		(end 200.548281 96.018984)
		(width 0.1)
		(layer "In7.Cu")
		(net 1008)
	)
	(segment
		(start 200.630462 94.204403)
		(end 200.630461 94.204402)
		(width 0.1)
		(layer "In7.Cu")
		(net 1008)
	)
	(segment
		(start 198.91 93.45)
		(end 198.76 93.3)
		(width 0.1)
		(layer "In7.Cu")
		(net 1008)
	)
	(segment
		(start 200.271174 94.811174)
		(end 200.271176 94.811175)
		(width 0.1)
		(layer "In7.Cu")
		(net 1008)
	)
	(segment
		(start 200.81 101.48)
		(end 202.53 99.76)
		(width 0.1)
		(layer "In7.Cu")
		(net 1008)
	)
	(segment
		(start 202.53 99.76)
		(end 202.53 97.07)
		(width 0.1)
		(layer "In7.Cu")
		(net 1008)
	)
	(segment
		(start 199.393029 93.214457)
		(end 199.157488 93.450001)
		(width 0.1)
		(layer "In7.Cu")
		(net 1008)
	)
	(segment
		(start 199.776204 94.316203)
		(end 200.135489 93.956918)
		(width 0.1)
		(layer "In7.Cu")
		(net 1008)
	)
	(segment
		(start 205.375 117.725)
		(end 204.8 117.15)
		(width 0.1)
		(layer "In7.Cu")
		(net 1008)
	)
	(segment
		(start 200.81 107.347717)
		(end 200.81 101.48)
		(width 0.1)
		(layer "In7.Cu")
		(net 1008)
	)
	(segment
		(start 200.766146 95.306146)
		(end 200.766148 95.306147)
		(width 0.1)
		(layer "In7.Cu")
		(net 1008)
	)
	(segment
		(start 198.76 92.518748)
		(end 197.291252 91.05)
		(width 0.1)
		(layer "In7.Cu")
		(net 1008)
	)
	(segment
		(start 205.375 120.672219)
		(end 205.375 117.725)
		(width 0.1)
		(layer "In7.Cu")
		(net 1008)
	)
	(segment
		(start 199.240139 94.852264)
		(end 199.776202 94.316202)
		(width 0.1)
		(layer "In7.Cu")
		(net 1008)
	)
	(segment
		(start 199.487626 95.099751)
		(end 199.487626 95.09975)
		(width 0.1)
		(layer "In7.Cu")
		(net 1008)
	)
	(segment
		(start 199.640516 93.461944)
		(end 199.640516 93.461945)
		(width 0.1)
		(layer "In7.Cu")
		(net 1008)
	)
	(segment
		(start 204.8 115.98)
		(end 205.01 115.77)
		(width 0.1)
		(layer "In7.Cu")
		(net 1008)
	)
	(segment
		(start 199.240139 95.099751)
		(end 199.240139 95.099752)
		(width 0.1)
		(layer "In7.Cu")
		(net 1008)
	)
	(segment
		(start 201.125434 94.699375)
		(end 201.125433 94.699374)
		(width 0.1)
		(layer "In7.Cu")
		(net 1008)
	)
	(segment
		(start 200.954874 107.484874)
		(end 200.947157 107.484874)
		(width 0.1)
		(layer "In7.Cu")
		(net 1008)
	)
	(arc
		(start 199.240139 95.099752)
		(mid 199.188883 94.976008)
		(end 199.240139 94.852264)
		(width 0.1)
		(layer "In7.Cu")
		(net 1008)
	)
	(arc
		(start 199.487626 95.09975)
		(mid 199.363883 95.151007)
		(end 199.240139 95.099751)
		(width 0.1)
		(layer "In7.Cu")
		(net 1008)
	)
	(arc
		(start 200.630461 94.45189)
		(mid 200.681718 94.328147)
		(end 200.630462 94.204403)
		(width 0.1)
		(layer "In7.Cu")
		(net 1008)
	)
	(arc
		(start 198.992654 94.604778)
		(mid 198.868911 94.656035)
		(end 198.745167 94.604779)
		(width 0.1)
		(layer "In7.Cu")
		(net 1008)
	)
	(arc
		(start 200.630461 94.204402)
		(mid 200.506717 94.153146)
		(end 200.382972 94.204401)
		(width 0.1)
		(layer "In7.Cu")
		(net 1008)
	)
	(arc
		(start 201.620405 95.194346)
		(mid 201.496661 95.14309)
		(end 201.372916 95.194345)
		(width 0.1)
		(layer "In7.Cu")
		(net 1008)
	)
	(arc
		(start 200.088664 95.488656)
		(mid 199.964921 95.539913)
		(end 199.841177 95.488657)
		(width 0.1)
		(layer "In7.Cu")
		(net 1008)
	)
	(arc
		(start 199.640516 93.214458)
		(mid 199.516773 93.163201)
		(end 199.393029 93.214457)
		(width 0.1)
		(layer "In7.Cu")
		(net 1008)
	)
	(arc
		(start 201.384864 95.924863)
		(mid 201.333607 95.80112)
		(end 201.384863 95.677376)
		(width 0.1)
		(layer "In7.Cu")
		(net 1008)
	)
	(arc
		(start 201.125433 94.946862)
		(mid 201.17669 94.823119)
		(end 201.125434 94.699375)
		(width 0.1)
		(layer "In7.Cu")
		(net 1008)
	)
	(arc
		(start 198.745167 94.60478)
		(mid 198.693911 94.481036)
		(end 198.745167 94.357292)
		(width 0.1)
		(layer "In7.Cu")
		(net 1008)
	)
	(arc
		(start 199.157487 93.449999)
		(mid 199.033744 93.501256)
		(end 198.91 93.45)
		(width 0.1)
		(layer "In7.Cu")
		(net 1008)
	)
	(arc
		(start 199.841177 95.488658)
		(mid 199.789921 95.364914)
		(end 199.841177 95.24117)
		(width 0.1)
		(layer "In7.Cu")
		(net 1008)
	)
	(arc
		(start 200.548281 96.018984)
		(mid 200.424538 96.070241)
		(end 200.300794 96.018985)
		(width 0.1)
		(layer "In7.Cu")
		(net 1008)
	)
	(arc
		(start 201.125433 94.699374)
		(mid 201.001689 94.648118)
		(end 200.877944 94.699373)
		(width 0.1)
		(layer "In7.Cu")
		(net 1008)
	)
	(arc
		(start 200.135489 93.70943)
		(mid 200.011745 93.658174)
		(end 199.888 93.709429)
		(width 0.1)
		(layer "In7.Cu")
		(net 1008)
	)
	(arc
		(start 200.300793 96.018984)
		(mid 200.249537 95.89524)
		(end 200.300794 95.771497)
		(width 0.1)
		(layer "In7.Cu")
		(net 1008)
	)
	(arc
		(start 199.640516 93.461945)
		(mid 199.691773 93.338202)
		(end 199.640517 93.214458)
		(width 0.1)
		(layer "In7.Cu")
		(net 1008)
	)
	(arc
		(start 201.620405 95.441834)
		(mid 201.671662 95.318091)
		(end 201.620406 95.194347)
		(width 0.1)
		(layer "In7.Cu")
		(net 1008)
	)
	(arc
		(start 200.135489 93.956918)
		(mid 200.186746 93.833175)
		(end 200.13549 93.709431)
		(width 0.1)
		(layer "In7.Cu")
		(net 1008)
	)
	(segment
		(start 241.075 131.8)
		(end 240.55 131.8)
		(width 0.1)
		(layer "F.Cu")
		(net 1015)
	)
	(segment
		(start 241.9255 129.3)
		(end 252.7 129.3)
		(width 0.1)
		(layer "F.Cu")
		(net 1015)
	)
	(segment
		(start 252.7 129.3)
		(end 253.345 129.945)
		(width 0.1)
		(layer "F.Cu")
		(net 1015)
	)
	(segment
		(start 253.345 129.945)
		(end 253.345 133.435)
		(width 0.1)
		(layer "F.Cu")
		(net 1015)
	)
	(segment
		(start 253.13 133.65)
		(end 252.3375 133.65)
		(width 0.1)
		(layer "F.Cu")
		(net 1015)
	)
	(segment
		(start 241.3 129.9255)
		(end 241.9255 129.3)
		(width 0.1)
		(layer "F.Cu")
		(net 1015)
	)
	(segment
		(start 241.2 131.675)
		(end 241.075 131.8)
		(width 0.1)
		(layer "F.Cu")
		(net 1015)
	)
	(segment
		(start 253.345 133.435)
		(end 253.13 133.65)
		(width 0.1)
		(layer "F.Cu")
		(net 1015)
	)
	(via
		(at 241.2 131.675)
		(size 0.45)
		(drill 0.2)
		(layers "F.Cu" "B.Cu")
		(net 1015)
	)
	(via
		(at 241.3 129.9255)
		(size 0.45)
		(drill 0.2)
		(layers "F.Cu" "B.Cu")
		(net 1015)
	)
	(segment
		(start 241.2 131.675)
		(end 241.3 131.575)
		(width 0.1)
		(layer "B.Cu")
		(net 1015)
	)
	(segment
		(start 241.3 131.575)
		(end 241.3 129.9255)
		(width 0.1)
		(layer "B.Cu")
		(net 1015)
	)
	(segment
		(start 242.975 129.5)
		(end 241.975 130.5)
		(width 0.1)
		(layer "F.Cu")
		(net 1016)
	)
	(segment
		(start 252.95 133.15)
		(end 253.1 133)
		(width 0.1)
		(layer "F.Cu")
		(net 1016)
	)
	(segment
		(start 253.1 130.1)
		(end 252.5 129.5)
		(width 0.1)
		(layer "F.Cu")
		(net 1016)
	)
	(segment
		(start 241.4 130.5)
		(end 241.1 130.8)
		(width 0.1)
		(layer "F.Cu")
		(net 1016)
	)
	(segment
		(start 241.1 130.8)
		(end 240.55 130.8)
		(width 0.1)
		(layer "F.Cu")
		(net 1016)
	)
	(segment
		(start 252.5 129.5)
		(end 242.975 129.5)
		(width 0.1)
		(layer "F.Cu")
		(net 1016)
	)
	(segment
		(start 252.3375 133.15)
		(end 252.95 133.15)
		(width 0.1)
		(layer "F.Cu")
		(net 1016)
	)
	(segment
		(start 241.975 130.5)
		(end 241.4 130.5)
		(width 0.1)
		(layer "F.Cu")
		(net 1016)
	)
	(segment
		(start 253.1 133)
		(end 253.1 130.1)
		(width 0.1)
		(layer "F.Cu")
		(net 1016)
	)
	(segment
		(start 241.62538 130.3)
		(end 240.55 130.3)
		(width 0.1)
		(layer "F.Cu")
		(net 1017)
	)
	(segment
		(start 241.818814 130.106566)
		(end 241.62538 130.3)
		(width 0.1)
		(layer "F.Cu")
		(net 1017)
	)
	(segment
		(start 252.45 132.65)
		(end 252.3375 132.65)
		(width 0.1)
		(layer "F.Cu")
		(net 1017)
	)
	(segment
		(start 252.5 132.6)
		(end 252.45 132.65)
		(width 0.1)
		(layer "F.Cu")
		(net 1017)
	)
	(segment
		(start 252.3375 132.65)
		(end 252.3875 132.6)
		(width 0.1)
		(layer "F.Cu")
		(net 1017)
	)
	(segment
		(start 252.5 130.2)
		(end 252.5 132.6)
		(width 0.1)
		(layer "F.Cu")
		(net 1017)
	)
	(segment
		(start 243.075 129.7)
		(end 252 129.7)
		(width 0.1)
		(layer "F.Cu")
		(net 1017)
	)
	(segment
		(start 252 129.7)
		(end 252.5 130.2)
		(width 0.1)
		(layer "F.Cu")
		(net 1017)
	)
	(segment
		(start 241.7 130.875)
		(end 241.9 130.875)
		(width 0.1)
		(layer "F.Cu")
		(net 1017)
	)
	(segment
		(start 241.9 130.875)
		(end 243.075 129.7)
		(width 0.1)
		(layer "F.Cu")
		(net 1017)
	)
	(via
		(at 241.818814 130.106566)
		(size 0.45)
		(drill 0.2)
		(layers "F.Cu" "B.Cu")
		(net 1017)
	)
	(via
		(at 241.7 130.875)
		(size 0.45)
		(drill 0.2)
		(layers "F.Cu" "B.Cu")
		(net 1017)
	)
	(segment
		(start 241.7 130.22538)
		(end 241.818814 130.106566)
		(width 0.1)
		(layer "B.Cu")
		(net 1017)
	)
	(segment
		(start 241.7 130.875)
		(end 241.7 130.22538)
		(width 0.1)
		(layer "B.Cu")
		(net 1017)
	)
	(segment
		(start 241.85 131.3)
		(end 242.2 130.95)
		(width 0.1)
		(layer "F.Cu")
		(net 1018)
	)
	(segment
		(start 251.65 130.54)
		(end 251.65 131.9625)
		(width 0.1)
		(layer "F.Cu")
		(net 1018)
	)
	(segment
		(start 242.2 130.9)
		(end 243.2 129.9)
		(width 0.1)
		(layer "F.Cu")
		(net 1018)
	)
	(segment
		(start 243.2 129.9)
		(end 251.01 129.9)
		(width 0.1)
		(layer "F.Cu")
		(net 1018)
	)
	(segment
		(start 251.01 129.9)
		(end 251.65 130.54)
		(width 0.1)
		(layer "F.Cu")
		(net 1018)
	)
	(segment
		(start 242.2 130.95)
		(end 242.2 130.9)
		(width 0.1)
		(layer "F.Cu")
		(net 1018)
	)
	(segment
		(start 240.55 131.3)
		(end 241.85 131.3)
		(width 0.1)
		(layer "F.Cu")
		(net 1018)
	)
	(segment
		(start 198.7 89.79353)
		(end 198.64484 89.73837)
		(width 0.184)
		(layer "F.Cu")
		(net 1019)
	)
	(segment
		(start 204.5 122.5)
		(end 205 122)
		(width 0.256)
		(layer "F.Cu")
		(net 1019)
	)
	(segment
		(start 198.7 90.422851)
		(end 198.7 89.79353)
		(width 0.184)
		(layer "F.Cu")
		(net 1019)
	)
	(via
		(at 198.64484 89.73837)
		(size 0.45)
		(drill 0.2)
		(layers "F.Cu" "B.Cu")
		(net 1019)
	)
	(via
		(at 205 122)
		(size 0.45)
		(drill 0.2)
		(layers "F.Cu" "B.Cu")
		(net 1019)
	)
	(segment
		(start 202.85 108.86)
		(end 202.85 110.15)
		(width 0.1)
		(layer "In7.Cu")
		(net 1019)
	)
	(segment
		(start 201.917913 104.59)
		(end 201.4 104.59)
		(width 0.1)
		(layer "In7.Cu")
		(net 1019)
	)
	(segment
		(start 201.4 104.19)
		(end 201.917913 104.19)
		(width 0.1)
		(layer "In7.Cu")
		(net 1019)
	)
	(segment
		(start 201.4 101.79)
		(end 201.917913 101.79)
		(width 0.1)
		(layer "In7.Cu")
		(net 1019)
	)
	(segment
		(start 198.64484 89.73837)
		(end 198.64484 91.828588)
		(width 0.1)
		(layer "In7.Cu")
		(net 1019)
	)
	(segment
		(start 201.917913 105.39)
		(end 201.4 105.39)
		(width 0.1)
		(layer "In7.Cu")
		(net 1019)
	)
	(segment
		(start 202.92 99.87)
		(end 201.2 101.59)
		(width 0.1)
		(layer "In7.Cu")
		(net 1019)
	)
	(segment
		(start 201.2 107.19)
		(end 201.2 107.21)
		(width 0.1)
		(layer "In7.Cu")
		(net 1019)
	)
	(segment
		(start 205.4 112.7)
		(end 205.4 115.98)
		(width 0.1)
		(layer "In7.Cu")
		(net 1019)
	)
	(segment
		(start 201.917913 106.19)
		(end 201.4 106.19)
		(width 0.1)
		(layer "In7.Cu")
		(net 1019)
	)
	(segment
		(start 205.02 116.36)
		(end 205.02 116.95)
		(width 0.1)
		(layer "In7.Cu")
		(net 1019)
	)
	(segment
		(start 205.62 121.38)
		(end 205 122)
		(width 0.1)
		(layer "In7.Cu")
		(net 1019)
	)
	(segment
		(start 202.92 96.103748)
		(end 202.92 99.87)
		(width 0.1)
		(layer "In7.Cu")
		(net 1019)
	)
	(segment
		(start 198.64484 91.828588)
		(end 202.92 96.103748)
		(width 0.1)
		(layer "In7.Cu")
		(net 1019)
	)
	(segment
		(start 201.917913 103.79)
		(end 201.4 103.79)
		(width 0.1)
		(layer "In7.Cu")
		(net 1019)
	)
	(segment
		(start 205.02 116.95)
		(end 205.62 117.55)
		(width 0.1)
		(layer "In7.Cu")
		(net 1019)
	)
	(segment
		(start 205.62 117.55)
		(end 205.62 121.38)
		(width 0.1)
		(layer "In7.Cu")
		(net 1019)
	)
	(segment
		(start 201.4 104.99)
		(end 201.917913 104.99)
		(width 0.1)
		(layer "In7.Cu")
		(net 1019)
	)
	(segment
		(start 201.917913 106.99)
		(end 201.4 106.99)
		(width 0.1)
		(layer "In7.Cu")
		(net 1019)
	)
	(segment
		(start 201.4 106.59)
		(end 201.917913 106.59)
		(width 0.1)
		(layer "In7.Cu")
		(net 1019)
	)
	(segment
		(start 205.4 115.98)
		(end 205.02 116.36)
		(width 0.1)
		(layer "In7.Cu")
		(net 1019)
	)
	(segment
		(start 201.4 105.79)
		(end 201.917913 105.79)
		(width 0.1)
		(layer "In7.Cu")
		(net 1019)
	)
	(segment
		(start 201.4 102.59)
		(end 201.917913 102.59)
		(width 0.1)
		(layer "In7.Cu")
		(net 1019)
	)
	(segment
		(start 202.85 110.15)
		(end 205.4 112.7)
		(width 0.1)
		(layer "In7.Cu")
		(net 1019)
	)
	(segment
		(start 201.4 103.39)
		(end 201.917913 103.39)
		(width 0.1)
		(layer "In7.Cu")
		(net 1019)
	)
	(segment
		(start 201.917913 102.19)
		(end 201.4 102.19)
		(width 0.1)
		(layer "In7.Cu")
		(net 1019)
	)
	(segment
		(start 201.917913 102.99)
		(end 201.4 102.99)
		(width 0.1)
		(layer "In7.Cu")
		(net 1019)
	)
	(segment
		(start 201.2 107.21)
		(end 202.85 108.86)
		(width 0.1)
		(layer "In7.Cu")
		(net 1019)
	)
	(arc
		(start 201.917913 102.59)
		(mid 202.059334 102.648579)
		(end 202.117913 102.79)
		(width 0.1)
		(layer "In7.Cu")
		(net 1019)
	)
	(arc
		(start 201.917913 104.19)
		(mid 202.059334 104.248579)
		(end 202.117913 104.39)
		(width 0.1)
		(layer "In7.Cu")
		(net 1019)
	)
	(arc
		(start 202.117913 101.99)
		(mid 202.059334 102.131421)
		(end 201.917913 102.19)
		(width 0.1)
		(layer "In7.Cu")
		(net 1019)
	)
	(arc
		(start 201.917913 101.79)
		(mid 202.059334 101.848579)
		(end 202.117913 101.99)
		(width 0.1)
		(layer "In7.Cu")
		(net 1019)
	)
	(arc
		(start 201.4 105.39)
		(mid 201.258579 105.448579)
		(end 201.2 105.59)
		(width 0.1)
		(layer "In7.Cu")
		(net 1019)
	)
	(arc
		(start 202.117913 103.59)
		(mid 202.059334 103.731421)
		(end 201.917913 103.79)
		(width 0.1)
		(layer "In7.Cu")
		(net 1019)
	)
	(arc
		(start 202.117913 105.99)
		(mid 202.059334 106.131421)
		(end 201.917913 106.19)
		(width 0.1)
		(layer "In7.Cu")
		(net 1019)
	)
	(arc
		(start 201.4 106.99)
		(mid 201.258579 107.048579)
		(end 201.2 107.19)
		(width 0.1)
		(layer "In7.Cu")
		(net 1019)
	)
	(arc
		(start 202.117913 104.39)
		(mid 202.059334 104.531421)
		(end 201.917913 104.59)
		(width 0.1)
		(layer "In7.Cu")
		(net 1019)
	)
	(arc
		(start 202.117913 106.79)
		(mid 202.059334 106.931421)
		(end 201.917913 106.99)
		(width 0.1)
		(layer "In7.Cu")
		(net 1019)
	)
	(arc
		(start 201.4 104.59)
		(mid 201.258579 104.648579)
		(end 201.2 104.79)
		(width 0.1)
		(layer "In7.Cu")
		(net 1019)
	)
	(arc
		(start 201.917913 104.99)
		(mid 202.059334 105.048579)
		(end 202.117913 105.19)
		(width 0.1)
		(layer "In7.Cu")
		(net 1019)
	)
	(arc
		(start 201.917913 106.59)
		(mid 202.059334 106.648579)
		(end 202.117913 106.79)
		(width 0.1)
		(layer "In7.Cu")
		(net 1019)
	)
	(arc
		(start 201.917913 103.39)
		(mid 202.059334 103.448579)
		(end 202.117913 103.59)
		(width 0.1)
		(layer "In7.Cu")
		(net 1019)
	)
	(arc
		(start 201.2 103.99)
		(mid 201.258579 104.131421)
		(end 201.4 104.19)
		(width 0.1)
		(layer "In7.Cu")
		(net 1019)
	)
	(arc
		(start 202.117913 105.19)
		(mid 202.059334 105.331421)
		(end 201.917913 105.39)
		(width 0.1)
		(layer "In7.Cu")
		(net 1019)
	)
	(arc
		(start 201.2 103.19)
		(mid 201.258579 103.331421)
		(end 201.4 103.39)
		(width 0.1)
		(layer "In7.Cu")
		(net 1019)
	)
	(arc
		(start 201.2 105.59)
		(mid 201.258579 105.731421)
		(end 201.4 105.79)
		(width 0.1)
		(layer "In7.Cu")
		(net 1019)
	)
	(arc
		(start 201.2 102.39)
		(mid 201.258579 102.531421)
		(end 201.4 102.59)
		(width 0.1)
		(layer "In7.Cu")
		(net 1019)
	)
	(arc
		(start 201.2 104.79)
		(mid 201.258579 104.931421)
		(end 201.4 104.99)
		(width 0.1)
		(layer "In7.Cu")
		(net 1019)
	)
	(arc
		(start 201.4 106.19)
		(mid 201.258579 106.248579)
		(end 201.2 106.39)
		(width 0.1)
		(layer "In7.Cu")
		(net 1019)
	)
	(arc
		(start 201.4 102.19)
		(mid 201.258579 102.248579)
		(end 201.2 102.39)
		(width 0.1)
		(layer "In7.Cu")
		(net 1019)
	)
	(arc
		(start 201.4 102.99)
		(mid 201.258579 103.048579)
		(end 201.2 103.19)
		(width 0.1)
		(layer "In7.Cu")
		(net 1019)
	)
	(arc
		(start 201.2 101.59)
		(mid 201.258579 101.731421)
		(end 201.4 101.79)
		(width 0.1)
		(layer "In7.Cu")
		(net 1019)
	)
	(arc
		(start 201.2 106.39)
		(mid 201.258579 106.531421)
		(end 201.4 106.59)
		(width 0.1)
		(layer "In7.Cu")
		(net 1019)
	)
	(arc
		(start 201.917913 105.79)
		(mid 202.059334 105.848579)
		(end 202.117913 105.99)
		(width 0.1)
		(layer "In7.Cu")
		(net 1019)
	)
	(arc
		(start 201.4 103.79)
		(mid 201.258579 103.848579)
		(end 201.2 103.99)
		(width 0.1)
		(layer "In7.Cu")
		(net 1019)
	)
	(arc
		(start 202.117913 102.79)
		(mid 202.059334 102.931421)
		(end 201.917913 102.99)
		(width 0.1)
		(layer "In7.Cu")
		(net 1019)
	)
	(segment
		(start 250.15 131.9625)
		(end 250.15 132.2)
		(width 0.1)
		(layer "F.Cu")
		(net 1020)
	)
	(via
		(at 257.55 124.3)
		(size 0.45)
		(drill 0.2)
		(layers "F.Cu" "B.Cu")
		(net 1020)
	)
	(via
		(at 250.15 132.2)
		(size 0.45)
		(drill 0.2)
		(layers "F.Cu" "B.Cu")
		(net 1020)
	)
	(segment
		(start 258.25 123.4875)
		(end 258.25 123.51)
		(width 0.1)
		(layer "B.Cu")
		(net 1020)
	)
	(segment
		(start 257.55 124.21)
		(end 257.55 124.3)
		(width 0.1)
		(layer "B.Cu")
		(net 1020)
	)
	(segment
		(start 258.25 123.51)
		(end 257.55 124.21)
		(width 0.1)
		(layer "B.Cu")
		(net 1020)
	)
	(segment
		(start 248.6 127.75)
		(end 248.5 127.85)
		(width 0.1)
		(layer "In3.Cu")
		(net 1020)
	)
	(segment
		(start 251.4 124.3)
		(end 248.6 127.1)
		(width 0.1)
		(layer "In3.Cu")
		(net 1020)
	)
	(segment
		(start 247.15 128.2)
		(end 247.15 130.95)
		(width 0.1)
		(layer "In3.Cu")
		(net 1020)
	)
	(segment
		(start 248.4 132.2)
		(end 250.15 132.2)
		(width 0.1)
		(layer "In3.Cu")
		(net 1020)
	)
	(segment
		(start 248.5 127.85)
		(end 247.5 127.85)
		(width 0.1)
		(layer "In3.Cu")
		(net 1020)
	)
	(segment
		(start 247.15 130.95)
		(end 248.4 132.2)
		(width 0.1)
		(layer "In3.Cu")
		(net 1020)
	)
	(segment
		(start 247.5 127.85)
		(end 247.15 128.2)
		(width 0.1)
		(layer "In3.Cu")
		(net 1020)
	)
	(segment
		(start 248.6 127.1)
		(end 248.6 127.75)
		(width 0.1)
		(layer "In3.Cu")
		(net 1020)
	)
	(segment
		(start 257.55 124.3)
		(end 251.4 124.3)
		(width 0.1)
		(layer "In3.Cu")
		(net 1020)
	)
	(segment
		(start 205.5 122.5)
		(end 206 122)
		(width 0.256)
		(layer "F.Cu")
		(net 1021)
	)
	(segment
		(start 200.7 90.422851)
		(end 200.7 89.783748)
		(width 0.184)
		(layer "F.Cu")
		(net 1021)
	)
	(segment
		(start 200.7 89.783748)
		(end 200.641252 89.725)
		(width 0.184)
		(layer "F.Cu")
		(net 1021)
	)
	(via
		(at 200.641252 89.725)
		(size 0.45)
		(drill 0.2)
		(layers "F.Cu" "B.Cu")
		(net 1021)
	)
	(via
		(at 206 122)
		(size 0.45)
		(drill 0.2)
		(layers "F.Cu" "B.Cu")
		(net 1021)
	)
	(segment
		(start 204.295 106.585)
		(end 204.895 106.585)
		(width 0.1)
		(layer "In7.Cu")
		(net 1021)
	)
	(segment
		(start 204.895 108.335)
		(end 204.295 108.335)
		(width 0.1)
		(layer "In7.Cu")
		(net 1021)
	)
	(segment
		(start 206.575 112.175)
		(end 204.12 109.72)
		(width 0.1)
		(layer "In7.Cu")
		(net 1021)
	)
	(segment
		(start 206.75 120.91)
		(end 206.942404 120.91)
		(width 0.1)
		(layer "In7.Cu")
		(net 1021)
	)
	(segment
		(start 204.295 107.285)
		(end 204.895 107.285)
		(width 0.1)
		(layer "In7.Cu")
		(net 1021)
	)
	(segment
		(start 204.895 105.535)
		(end 204.295 105.535)
		(width 0.1)
		(layer "In7.Cu")
		(net 1021)
	)
	(segment
		(start 204.295 105.885)
		(end 204.895 105.885)
		(width 0.1)
		(layer "In7.Cu")
		(net 1021)
	)
	(segment
		(start 204.12 105.31)
		(end 204.12 95.503748)
		(width 0.1)
		(layer "In7.Cu")
		(net 1021)
	)
	(segment
		(start 204.295 109.385)
		(end 204.895 109.385)
		(width 0.1)
		(layer "In7.Cu")
		(net 1021)
	)
	(segment
		(start 206.575 119.759007)
		(end 206.575 112.175)
		(width 0.1)
		(layer "In7.Cu")
		(net 1021)
	)
	(segment
		(start 204.12 95.503748)
		(end 200.641252 92.025)
		(width 0.1)
		(layer "In7.Cu")
		(net 1021)
	)
	(segment
		(start 204.295 108.685)
		(end 204.895 108.685)
		(width 0.1)
		(layer "In7.Cu")
		(net 1021)
	)
	(segment
		(start 204.895 106.235)
		(end 204.295 106.235)
		(width 0.1)
		(layer "In7.Cu")
		(net 1021)
	)
	(segment
		(start 206.942404 120.56)
		(end 206.75 120.56)
		(width 0.1)
		(layer "In7.Cu")
		(net 1021)
	)
	(segment
		(start 204.895 109.035)
		(end 204.295 109.035)
		(width 0.1)
		(layer "In7.Cu")
		(net 1021)
	)
	(segment
		(start 204.895 107.635)
		(end 204.295 107.635)
		(width 0.1)
		(layer "In7.Cu")
		(net 1021)
	)
	(segment
		(start 204.295 107.985)
		(end 204.895 107.985)
		(width 0.1)
		(layer "In7.Cu")
		(net 1021)
	)
	(segment
		(start 206.575 120.385)
		(end 206.575 119.759007)
		(width 0.1)
		(layer "In7.Cu")
		(net 1021)
	)
	(segment
		(start 204.12 109.72)
		(end 204.12 109.56)
		(width 0.1)
		(layer "In7.Cu")
		(net 1021)
	)
	(segment
		(start 206 122)
		(end 206.575 121.425)
		(width 0.1)
		(layer "In7.Cu")
		(net 1021)
	)
	(segment
		(start 204.12 105.36)
		(end 204.12 105.31)
		(width 0.1)
		(layer "In7.Cu")
		(net 1021)
	)
	(segment
		(start 200.641252 92.025)
		(end 200.641252 89.725)
		(width 0.1)
		(layer "In7.Cu")
		(net 1021)
	)
	(segment
		(start 206.575 121.425)
		(end 206.575 121.085)
		(width 0.1)
		(layer "In7.Cu")
		(net 1021)
	)
	(segment
		(start 204.895 106.935)
		(end 204.295 106.935)
		(width 0.1)
		(layer "In7.Cu")
		(net 1021)
	)
	(arc
		(start 205.07 106.41)
		(mid 205.018744 106.286256)
		(end 204.895 106.235)
		(width 0.1)
		(layer "In7.Cu")
		(net 1021)
	)
	(arc
		(start 205.07 105.71)
		(mid 205.018744 105.586256)
		(end 204.895 105.535)
		(width 0.1)
		(layer "In7.Cu")
		(net 1021)
	)
	(arc
		(start 204.895 108.685)
		(mid 205.018744 108.633744)
		(end 205.07 108.51)
		(width 0.1)
		(layer "In7.Cu")
		(net 1021)
	)
	(arc
		(start 207.117404 120.735)
		(mid 207.066148 120.611256)
		(end 206.942404 120.56)
		(width 0.1)
		(layer "In7.Cu")
		(net 1021)
	)
	(arc
		(start 204.295 105.535)
		(mid 204.171256 105.483744)
		(end 204.12 105.36)
		(width 0.1)
		(layer "In7.Cu")
		(net 1021)
	)
	(arc
		(start 206.75 120.56)
		(mid 206.626256 120.508744)
		(end 206.575 120.385)
		(width 0.1)
		(layer "In7.Cu")
		(net 1021)
	)
	(arc
		(start 204.295 109.035)
		(mid 204.171256 108.983744)
		(end 204.12 108.86)
		(width 0.1)
		(layer "In7.Cu")
		(net 1021)
	)
	(arc
		(start 204.295 107.635)
		(mid 204.171256 107.583744)
		(end 204.12 107.46)
		(width 0.1)
		(layer "In7.Cu")
		(net 1021)
	)
	(arc
		(start 204.12 108.16)
		(mid 204.171256 108.036256)
		(end 204.295 107.985)
		(width 0.1)
		(layer "In7.Cu")
		(net 1021)
	)
	(arc
		(start 206.575 121.085)
		(mid 206.626256 120.961256)
		(end 206.75 120.91)
		(width 0.1)
		(layer "In7.Cu")
		(net 1021)
	)
	(arc
		(start 204.12 106.06)
		(mid 204.171256 105.936256)
		(end 204.295 105.885)
		(width 0.1)
		(layer "In7.Cu")
		(net 1021)
	)
	(arc
		(start 204.295 106.935)
		(mid 204.171256 106.883744)
		(end 204.12 106.76)
		(width 0.1)
		(layer "In7.Cu")
		(net 1021)
	)
	(arc
		(start 204.12 106.76)
		(mid 204.171256 106.636256)
		(end 204.295 106.585)
		(width 0.1)
		(layer "In7.Cu")
		(net 1021)
	)
	(arc
		(start 204.12 107.46)
		(mid 204.171256 107.336256)
		(end 204.295 107.285)
		(width 0.1)
		(layer "In7.Cu")
		(net 1021)
	)
	(arc
		(start 205.07 107.81)
		(mid 205.018744 107.686256)
		(end 204.895 107.635)
		(width 0.1)
		(layer "In7.Cu")
		(net 1021)
	)
	(arc
		(start 204.895 109.385)
		(mid 205.018744 109.333744)
		(end 205.07 109.21)
		(width 0.1)
		(layer "In7.Cu")
		(net 1021)
	)
	(arc
		(start 205.07 109.21)
		(mid 205.018744 109.086256)
		(end 204.895 109.035)
		(width 0.1)
		(layer "In7.Cu")
		(net 1021)
	)
	(arc
		(start 204.895 106.585)
		(mid 205.018744 106.533744)
		(end 205.07 106.41)
		(width 0.1)
		(layer "In7.Cu")
		(net 1021)
	)
	(arc
		(start 205.07 107.11)
		(mid 205.018744 106.986256)
		(end 204.895 106.935)
		(width 0.1)
		(layer "In7.Cu")
		(net 1021)
	)
	(arc
		(start 204.295 108.335)
		(mid 204.171256 108.283744)
		(end 204.12 108.16)
		(width 0.1)
		(layer "In7.Cu")
		(net 1021)
	)
	(arc
		(start 204.12 108.86)
		(mid 204.171256 108.736256)
		(end 204.295 108.685)
		(width 0.1)
		(layer "In7.Cu")
		(net 1021)
	)
	(arc
		(start 204.12 109.56)
		(mid 204.171256 109.436256)
		(end 204.295 109.385)
		(width 0.1)
		(layer "In7.Cu")
		(net 1021)
	)
	(arc
		(start 206.942404 120.91)
		(mid 207.066148 120.858744)
		(end 207.117404 120.735)
		(width 0.1)
		(layer "In7.Cu")
		(net 1021)
	)
	(arc
		(start 205.07 108.51)
		(mid 205.018744 108.386256)
		(end 204.895 108.335)
		(width 0.1)
		(layer "In7.Cu")
		(net 1021)
	)
	(arc
		(start 204.895 107.285)
		(mid 205.018744 107.233744)
		(end 205.07 107.11)
		(width 0.1)
		(layer "In7.Cu")
		(net 1021)
	)
	(arc
		(start 204.895 107.985)
		(mid 205.018744 107.933744)
		(end 205.07 107.81)
		(width 0.1)
		(layer "In7.Cu")
		(net 1021)
	)
	(arc
		(start 204.895 105.885)
		(mid 205.018744 105.833744)
		(end 205.07 105.71)
		(width 0.1)
		(layer "In7.Cu")
		(net 1021)
	)
	(arc
		(start 204.295 106.235)
		(mid 204.171256 106.183744)
		(end 204.12 106.06)
		(width 0.1)
		(layer "In7.Cu")
		(net 1021)
	)
	(segment
		(start 241.5 136.1)
		(end 241.475 136.075)
		(width 0.1)
		(layer "F.Cu")
		(net 1023)
	)
	(segment
		(start 248.15 130.45)
		(end 248.15 131.9625)
		(width 0.1)
		(layer "F.Cu")
		(net 1023)
	)
	(segment
		(start 241.475 131.975)
		(end 243.325 130.125)
		(width 0.1)
		(layer "F.Cu")
		(net 1023)
	)
	(segment
		(start 247.825 130.125)
		(end 248.15 130.45)
		(width 0.1)
		(layer "F.Cu")
		(net 1023)
	)
	(segment
		(start 241.25 138.7)
		(end 240.85 138.7)
		(width 0.1)
		(layer "F.Cu")
		(net 1023)
	)
	(segment
		(start 241.6 138.35)
		(end 241.25 138.7)
		(width 0.1)
		(layer "F.Cu")
		(net 1023)
	)
	(segment
		(start 241.475 136.075)
		(end 241.475 131.975)
		(width 0.1)
		(layer "F.Cu")
		(net 1023)
	)
	(segment
		(start 243.325 130.125)
		(end 247.825 130.125)
		(width 0.1)
		(layer "F.Cu")
		(net 1023)
	)
	(segment
		(start 242.9 144.54)
		(end 242.9 138.4)
		(width 0.1)
		(layer "F.Cu")
		(net 1023)
	)
	(segment
		(start 242.17 145.27)
		(end 241.74 145.7)
		(width 0.1)
		(layer "F.Cu")
		(net 1023)
	)
	(segment
		(start 241.74 145.7)
		(end 240.5 145.7)
		(width 0.1)
		(layer "F.Cu")
		(net 1023)
	)
	(segment
		(start 242.9 138.4)
		(end 243 138.3)
		(width 0.1)
		(layer "F.Cu")
		(net 1023)
	)
	(segment
		(start 242.17 145.27)
		(end 242.9 144.54)
		(width 0.1)
		(layer "F.Cu")
		(net 1023)
	)
	(via
		(at 240.95 151.12)
		(size 0.45)
		(drill 0.2)
		(layers "F.Cu" "B.Cu")
		(net 1023)
	)
	(via
		(at 242.17 145.27)
		(size 0.45)
		(drill 0.2)
		(layers "F.Cu" "B.Cu")
		(net 1023)
	)
	(via
		(at 241.6 138.35)
		(size 0.45)
		(drill 0.2)
		(layers "F.Cu" "B.Cu")
		(net 1023)
	)
	(via
		(at 243 138.3)
		(size 0.45)
		(drill 0.2)
		(layers "F.Cu" "B.Cu")
		(net 1023)
	)
	(via
		(at 178.77 182.74)
		(size 0.45)
		(drill 0.2)
		(layers "F.Cu" "B.Cu")
		(net 1023)
	)
	(via
		(at 241.5 136.1)
		(size 0.45)
		(drill 0.2)
		(layers "F.Cu" "B.Cu")
		(net 1023)
	)
	(segment
		(start 241.6 138.3)
		(end 241.6 138.35)
		(width 0.1)
		(layer "B.Cu")
		(net 1023)
	)
	(segment
		(start 241.2 138.1)
		(end 241.2 136.4)
		(width 0.1)
		(layer "B.Cu")
		(net 1023)
	)
	(segment
		(start 241.2 136.4)
		(end 241.5 136.1)
		(width 0.1)
		(layer "B.Cu")
		(net 1023)
	)
	(segment
		(start 241.6 138.35)
		(end 241.45 138.35)
		(width 0.1)
		(layer "B.Cu")
		(net 1023)
	)
	(segment
		(start 241.65 138.3)
		(end 241.6 138.35)
		(width 0.1)
		(layer "B.Cu")
		(net 1023)
	)
	(segment
		(start 241.65 138.3)
		(end 243 138.3)
		(width 0.1)
		(layer "B.Cu")
		(net 1023)
	)
	(segment
		(start 241.45 138.35)
		(end 241.2 138.1)
		(width 0.1)
		(layer "B.Cu")
		(net 1023)
	)
	(segment
		(start 178.77 182.74)
		(end 176.98 182.74)
		(width 0.1)
		(layer "In5.Cu")
		(net 1023)
	)
	(segment
		(start 237.25 151.23)
		(end 238.36 152.34)
		(width 0.1)
		(layer "In5.Cu")
		(net 1023)
	)
	(segment
		(start 227.877052 163.3)
		(end 230.570002 163.3)
		(width 0.1)
		(layer "In5.Cu")
		(net 1023)
	)
	(segment
		(start 223.587052 167.59)
		(end 227.877052 163.3)
		(width 0.1)
		(layer "In5.Cu")
		(net 1023)
	)
	(segment
		(start 176.25 187.52)
		(end 179.31 187.52)
		(width 0.1)
		(layer "In5.Cu")
		(net 1023)
	)
	(segment
		(start 239.35 152.34)
		(end 240.57 151.12)
		(width 0.1)
		(layer "In5.Cu")
		(net 1023)
	)
	(segment
		(start 232.43 161.44)
		(end 232.43 153.917052)
		(width 0.1)
		(layer "In5.Cu")
		(net 1023)
	)
	(segment
		(start 198.625684 167.59)
		(end 223.587052 167.59)
		(width 0.1)
		(layer "In5.Cu")
		(net 1023)
	)
	(segment
		(start 189.668526 169.8)
		(end 196.415685 169.8)
		(width 0.1)
		(layer "In5.Cu")
		(net 1023)
	)
	(segment
		(start 174.92 184.8)
		(end 174.92 186.19)
		(width 0.1)
		(layer "In5.Cu")
		(net 1023)
	)
	(segment
		(start 240.57 151.12)
		(end 240.95 151.12)
		(width 0.1)
		(layer "In5.Cu")
		(net 1023)
	)
	(segment
		(start 196.415685 169.8)
		(end 198.625684 167.59)
		(width 0.1)
		(layer "In5.Cu")
		(net 1023)
	)
	(segment
		(start 183.09 183.74)
		(end 183.09 176.378526)
		(width 0.1)
		(layer "In5.Cu")
		(net 1023)
	)
	(segment
		(start 176.98 182.74)
		(end 174.92 184.8)
		(width 0.1)
		(layer "In5.Cu")
		(net 1023)
	)
	(segment
		(start 235.117052 151.23)
		(end 237.25 151.23)
		(width 0.1)
		(layer "In5.Cu")
		(net 1023)
	)
	(segment
		(start 179.31 187.52)
		(end 183.09 183.74)
		(width 0.1)
		(layer "In5.Cu")
		(net 1023)
	)
	(segment
		(start 230.570002 163.3)
		(end 230.69716 163.172843)
		(width 0.1)
		(layer "In5.Cu")
		(net 1023)
	)
	(segment
		(start 183.09 176.378526)
		(end 189.668526 169.8)
		(width 0.1)
		(layer "In5.Cu")
		(net 1023)
	)
	(segment
		(start 238.36 152.34)
		(end 239.35 152.34)
		(width 0.1)
		(layer "In5.Cu")
		(net 1023)
	)
	(segment
		(start 232.43 153.917052)
		(end 235.117052 151.23)
		(width 0.1)
		(layer "In5.Cu")
		(net 1023)
	)
	(segment
		(start 230.69716 163.17284)
		(end 232.43 161.44)
		(width 0.1)
		(layer "In5.Cu")
		(net 1023)
	)
	(segment
		(start 174.92 186.19)
		(end 176.25 187.52)
		(width 0.1)
		(layer "In5.Cu")
		(net 1023)
	)
	(segment
		(start 230.69716 163.172843)
		(end 230.69716 163.17284)
		(width 0.1)
		(layer "In5.Cu")
		(net 1023)
	)
	(segment
		(start 242.17 145.27)
		(end 242.024999 145.415001)
		(width 0.1)
		(layer "In7.Cu")
		(net 1023)
	)
	(segment
		(start 242.024999 150.045001)
		(end 240.95 151.12)
		(width 0.1)
		(layer "In7.Cu")
		(net 1023)
	)
	(segment
		(start 242.024999 145.415001)
		(end 242.024999 149.585001)
		(width 0.1)
		(layer "In7.Cu")
		(net 1023)
	)
	(segment
		(start 242.024999 149.585001)
		(end 242.024999 150.045001)
		(width 0.1)
		(layer "In7.Cu")
		(net 1023)
	)
	(segment
		(start 241.9 135.275)
		(end 241.675 135.05)
		(width 0.1)
		(layer "F.Cu")
		(net 1024)
	)
	(segment
		(start 177.77 184.46)
		(end 177.77 182.74)
		(width 0.1)
		(layer "F.Cu")
		(net 1024)
	)
	(segment
		(start 240.5 145.2)
		(end 241.37 145.2)
		(width 0.1)
		(layer "F.Cu")
		(net 1024)
	)
	(segment
		(start 243.45 130.325)
		(end 247.325 130.325)
		(width 0.1)
		(layer "F.Cu")
		(net 1024)
	)
	(segment
		(start 247.775 130.775)
		(end 247.775 131.8375)
		(width 0.1)
		(layer "F.Cu")
		(net 1024)
	)
	(segment
		(start 247.325 130.325)
		(end 247.775 130.775)
		(width 0.1)
		(layer "F.Cu")
		(net 1024)
	)
	(segment
		(start 242.6 144.175)
		(end 241.585 145.19)
		(width 0.1)
		(layer "F.Cu")
		(net 1024)
	)
	(segment
		(start 247.775 131.8375)
		(end 247.65 131.9625)
		(width 0.1)
		(layer "F.Cu")
		(net 1024)
	)
	(segment
		(start 241.9 136.6)
		(end 241.9 135.275)
		(width 0.1)
		(layer "F.Cu")
		(net 1024)
	)
	(segment
		(start 242.6 137.9)
		(end 242.6 144.175)
		(width 0.1)
		(layer "F.Cu")
		(net 1024)
	)
	(segment
		(start 241.37 145.2)
		(end 241.38 145.19)
		(width 0.1)
		(layer "F.Cu")
		(net 1024)
	)
	(segment
		(start 242.8 137.7)
		(end 242.6 137.9)
		(width 0.1)
		(layer "F.Cu")
		(net 1024)
	)
	(segment
		(start 240.85 137.7)
		(end 241.6 137.7)
		(width 0.1)
		(layer "F.Cu")
		(net 1024)
	)
	(segment
		(start 241.675 132.1)
		(end 243.45 130.325)
		(width 0.1)
		(layer "F.Cu")
		(net 1024)
	)
	(segment
		(start 241.585 145.19)
		(end 240.51 145.19)
		(width 0.1)
		(layer "F.Cu")
		(net 1024)
	)
	(segment
		(start 241.675 135.05)
		(end 241.675 132.1)
		(width 0.1)
		(layer "F.Cu")
		(net 1024)
	)
	(segment
		(start 240.51 145.19)
		(end 240.5 145.2)
		(width 0.1)
		(layer "F.Cu")
		(net 1024)
	)
	(segment
		(start 177.76 184.47)
		(end 177.77 184.46)
		(width 0.1)
		(layer "F.Cu")
		(net 1024)
	)
	(via
		(at 177.76 184.47)
		(size 0.45)
		(drill 0.2)
		(layers "F.Cu" "B.Cu")
		(net 1024)
	)
	(via
		(at 240.57 149.91)
		(size 0.45)
		(drill 0.2)
		(layers "F.Cu" "B.Cu")
		(net 1024)
	)
	(via
		(at 241.9 136.6)
		(size 0.45)
		(drill 0.2)
		(layers "F.Cu" "B.Cu")
		(net 1024)
	)
	(via
		(at 241.38 145.19)
		(size 0.45)
		(drill 0.2)
		(layers "F.Cu" "B.Cu")
		(net 1024)
	)
	(via
		(at 241.6 137.7)
		(size 0.45)
		(drill 0.2)
		(layers "F.Cu" "B.Cu")
		(net 1024)
	)
	(via
		(at 242.8 137.7)
		(size 0.45)
		(drill 0.2)
		(layers "F.Cu" "B.Cu")
		(net 1024)
	)
	(segment
		(start 241.6 136.9)
		(end 241.6 137.7)
		(width 0.1)
		(layer "B.Cu")
		(net 1024)
	)
	(segment
		(start 241.9 136.6)
		(end 241.6 136.9)
		(width 0.1)
		(layer "B.Cu")
		(net 1024)
	)
	(segment
		(start 242.8 137.7)
		(end 241.6 137.7)
		(width 0.1)
		(layer "B.Cu")
		(net 1024)
	)
	(segment
		(start 239.17 151.9)
		(end 238.62 151.9)
		(width 0.1)
		(layer "In5.Cu")
		(net 1024)
	)
	(segment
		(start 182.69 176.212842)
		(end 182.69 183.46)
		(width 0.1)
		(layer "In5.Cu")
		(net 1024)
	)
	(segment
		(start 240.57 149.91)
		(end 240.24 149.91)
		(width 0.1)
		(layer "In5.Cu")
		(net 1024)
	)
	(segment
		(start 177.08 185.15)
		(end 177.76 184.47)
		(width 0.1)
		(layer "In5.Cu")
		(net 1024)
	)
	(segment
		(start 182.69 183.46)
		(end 179.06 187.09)
		(width 0.1)
		(layer "In5.Cu")
		(net 1024)
	)
	(segment
		(start 176.42 187.09)
		(end 175.32 185.99)
		(width 0.1)
		(layer "In5.Cu")
		(net 1024)
	)
	(segment
		(start 239.68 150.47)
		(end 239.68 151.39)
		(width 0.1)
		(layer "In5.Cu")
		(net 1024)
	)
	(segment
		(start 232.03 161.274316)
		(end 230.404317 162.9)
		(width 0.1)
		(layer "In5.Cu")
		(net 1024)
	)
	(segment
		(start 179.06 187.09)
		(end 176.42 187.09)
		(width 0.1)
		(layer "In5.Cu")
		(net 1024)
	)
	(segment
		(start 226.756368 163.855)
		(end 219.694999 163.855)
		(width 0.1)
		(layer "In5.Cu")
		(net 1024)
	)
	(segment
		(start 237.52 150.8)
		(end 234.981368 150.8)
		(width 0.1)
		(layer "In5.Cu")
		(net 1024)
	)
	(segment
		(start 219.694999 163.855)
		(end 216.36 167.19)
		(width 0.1)
		(layer "In5.Cu")
		(net 1024)
	)
	(segment
		(start 240.24 149.91)
		(end 239.68 150.47)
		(width 0.1)
		(layer "In5.Cu")
		(net 1024)
	)
	(segment
		(start 196.25 169.4)
		(end 189.502841 169.4)
		(width 0.1)
		(layer "In5.Cu")
		(net 1024)
	)
	(segment
		(start 227.711368 162.9)
		(end 226.756368 163.855)
		(width 0.1)
		(layer "In5.Cu")
		(net 1024)
	)
	(segment
		(start 234.981368 150.8)
		(end 232.03 153.751368)
		(width 0.1)
		(layer "In5.Cu")
		(net 1024)
	)
	(segment
		(start 239.68 151.39)
		(end 239.17 151.9)
		(width 0.1)
		(layer "In5.Cu")
		(net 1024)
	)
	(segment
		(start 230.404317 162.9)
		(end 227.711368 162.9)
		(width 0.1)
		(layer "In5.Cu")
		(net 1024)
	)
	(segment
		(start 198.459999 167.19)
		(end 196.25 169.4)
		(width 0.1)
		(layer "In5.Cu")
		(net 1024)
	)
	(segment
		(start 232.03 153.751368)
		(end 232.03 161.274316)
		(width 0.1)
		(layer "In5.Cu")
		(net 1024)
	)
	(segment
		(start 175.32 185.99)
		(end 175.32 185.37)
		(width 0.1)
		(layer "In5.Cu")
		(net 1024)
	)
	(segment
		(start 238.62 151.9)
		(end 237.52 150.8)
		(width 0.1)
		(layer "In5.Cu")
		(net 1024)
	)
	(segment
		(start 189.502841 169.4)
		(end 182.69 176.212842)
		(width 0.1)
		(layer "In5.Cu")
		(net 1024)
	)
	(segment
		(start 175.32 185.37)
		(end 175.54 185.15)
		(width 0.1)
		(layer "In5.Cu")
		(net 1024)
	)
	(segment
		(start 216.36 167.19)
		(end 198.459999 167.19)
		(width 0.1)
		(layer "In5.Cu")
		(net 1024)
	)
	(segment
		(start 175.54 185.15)
		(end 177.08 185.15)
		(width 0.1)
		(layer "In5.Cu")
		(net 1024)
	)
	(segment
		(start 241.48 149.11)
		(end 241.03 149.56)
		(width 0.1)
		(layer "In7.Cu")
		(net 1024)
	)
	(segment
		(start 241.48 145.29)
		(end 241.48 149.11)
		(width 0.1)
		(layer "In7.Cu")
		(net 1024)
	)
	(segment
		(start 241.38 145.19)
		(end 241.48 145.29)
		(width 0.1)
		(layer "In7.Cu")
		(net 1024)
	)
	(segment
		(start 241.03 149.56)
		(end 240.68 149.91)
		(width 0.1)
		(layer "In7.Cu")
		(net 1024)
	)
	(segment
		(start 240.68 149.91)
		(end 240.57 149.91)
		(width 0.1)
		(layer "In7.Cu")
		(net 1024)
	)
	(segment
		(start 242.3 136.9)
		(end 242.3 136.325)
		(width 0.1)
		(layer "F.Cu")
		(net 1025)
	)
	(segment
		(start 241 144.2)
		(end 241.275 143.925)
		(width 0.1)
		(layer "F.Cu")
		(net 1025)
	)
	(segment
		(start 240.5 144.2)
		(end 241 144.2)
		(width 0.1)
		(layer "F.Cu")
		(net 1025)
	)
	(segment
		(start 242.15 136.175)
		(end 242.15 135.2)
		(width 0.1)
		(layer "F.Cu")
		(net 1025)
	)
	(segment
		(start 240.85 137.2)
		(end 241.9 137.2)
		(width 0.1)
		(layer "F.Cu")
		(net 1025)
	)
	(segment
		(start 242.3 136.325)
		(end 242.15 136.175)
		(width 0.1)
		(layer "F.Cu")
		(net 1025)
	)
	(segment
		(start 247 130.7)
		(end 247 131.8125)
		(width 0.1)
		(layer "F.Cu")
		(net 1025)
	)
	(segment
		(start 242 143.2)
		(end 242 137.4)
		(width 0.1)
		(layer "F.Cu")
		(net 1025)
	)
	(segment
		(start 241.875 132.2)
		(end 243.55 130.525)
		(width 0.1)
		(layer "F.Cu")
		(net 1025)
	)
	(segment
		(start 242 137.3)
		(end 242 137.4)
		(width 0.1)
		(layer "F.Cu")
		(net 1025)
	)
	(segment
		(start 241.9 137.2)
		(end 242 137.2)
		(width 0.1)
		(layer "F.Cu")
		(net 1025)
	)
	(segment
		(start 241.275 143.925)
		(end 242 143.2)
		(width 0.1)
		(layer "F.Cu")
		(net 1025)
	)
	(segment
		(start 242 137.3)
		(end 241.9 137.2)
		(width 0.1)
		(layer "F.Cu")
		(net 1025)
	)
	(segment
		(start 243.55 130.525)
		(end 246.825 130.525)
		(width 0.1)
		(layer "F.Cu")
		(net 1025)
	)
	(segment
		(start 242 137.4)
		(end 242 137.2)
		(width 0.1)
		(layer "F.Cu")
		(net 1025)
	)
	(segment
		(start 176.73 182.78)
		(end 176.77 182.74)
		(width 0.1)
		(layer "F.Cu")
		(net 1025)
	)
	(segment
		(start 242.15 135.2)
		(end 241.875 134.925)
		(width 0.1)
		(layer "F.Cu")
		(net 1025)
	)
	(segment
		(start 176.73 183.71)
		(end 176.73 182.78)
		(width 0.1)
		(layer "F.Cu")
		(net 1025)
	)
	(segment
		(start 241.875 134.925)
		(end 241.875 132.2)
		(width 0.1)
		(layer "F.Cu")
		(net 1025)
	)
	(segment
		(start 246.825 130.525)
		(end 247 130.7)
		(width 0.1)
		(layer "F.Cu")
		(net 1025)
	)
	(segment
		(start 242 137.2)
		(end 242.3 136.9)
		(width 0.1)
		(layer "F.Cu")
		(net 1025)
	)
	(segment
		(start 247 131.8125)
		(end 247.15 131.9625)
		(width 0.1)
		(layer "F.Cu")
		(net 1025)
	)
	(via
		(at 176.73 183.71)
		(size 0.45)
		(drill 0.2)
		(layers "F.Cu" "B.Cu")
		(net 1025)
	)
	(via
		(at 240.59 150.56)
		(size 0.45)
		(drill 0.2)
		(layers "F.Cu" "B.Cu")
		(net 1025)
	)
	(via
		(at 241.275 143.925)
		(size 0.45)
		(drill 0.2)
		(layers "F.Cu" "B.Cu")
		(net 1025)
	)
	(segment
		(start 176.69 183.71)
		(end 175.12 185.28)
		(width 0.1)
		(layer "In5.Cu")
		(net 1025)
	)
	(segment
		(start 230.48716 163.1)
		(end 232.23 161.357158)
		(width 0.1)
		(layer "In5.Cu")
		(net 1025)
	)
	(segment
		(start 216.442843 167.39)
		(end 219.777842 164.055)
		(width 0.1)
		(layer "In5.Cu")
		(net 1025)
	)
	(segment
		(start 239.25 152.12)
		(end 240.59 150.78)
		(width 0.1)
		(layer "In5.Cu")
		(net 1025)
	)
	(segment
		(start 219.777842 164.055)
		(end 226.839211 164.055)
		(width 0.1)
		(layer "In5.Cu")
		(net 1025)
	)
	(segment
		(start 232.23 153.83421)
		(end 235.03421 151.03)
		(width 0.1)
		(layer "In5.Cu")
		(net 1025)
	)
	(segment
		(start 227.79421 163.1)
		(end 230.48716 163.1)
		(width 0.1)
		(layer "In5.Cu")
		(net 1025)
	)
	(segment
		(start 237.41 151.03)
		(end 238.5 152.12)
		(width 0.1)
		(layer "In5.Cu")
		(net 1025)
	)
	(segment
		(start 198.542842 167.39)
		(end 216.442843 167.39)
		(width 0.1)
		(layer "In5.Cu")
		(net 1025)
	)
	(segment
		(start 182.89 176.295684)
		(end 189.585684 169.6)
		(width 0.1)
		(layer "In5.Cu")
		(net 1025)
	)
	(segment
		(start 179.21 187.32)
		(end 182.89 183.64)
		(width 0.1)
		(layer "In5.Cu")
		(net 1025)
	)
	(segment
		(start 175.12 185.28)
		(end 175.12 186.1)
		(width 0.1)
		(layer "In5.Cu")
		(net 1025)
	)
	(segment
		(start 240.59 150.78)
		(end 240.59 150.56)
		(width 0.1)
		(layer "In5.Cu")
		(net 1025)
	)
	(segment
		(start 189.585684 169.6)
		(end 196.332843 169.6)
		(width 0.1)
		(layer "In5.Cu")
		(net 1025)
	)
	(segment
		(start 175.12 186.1)
		(end 176.34 187.32)
		(width 0.1)
		(layer "In5.Cu")
		(net 1025)
	)
	(segment
		(start 196.332843 169.6)
		(end 198.542842 167.39)
		(width 0.1)
		(layer "In5.Cu")
		(net 1025)
	)
	(segment
		(start 226.839211 164.055)
		(end 227.79421 163.1)
		(width 0.1)
		(layer "In5.Cu")
		(net 1025)
	)
	(segment
		(start 176.34 187.32)
		(end 179.21 187.32)
		(width 0.1)
		(layer "In5.Cu")
		(net 1025)
	)
	(segment
		(start 176.73 183.71)
		(end 176.69 183.71)
		(width 0.1)
		(layer "In5.Cu")
		(net 1025)
	)
	(segment
		(start 182.89 183.64)
		(end 182.89 176.295684)
		(width 0.1)
		(layer "In5.Cu")
		(net 1025)
	)
	(segment
		(start 238.5 152.12)
		(end 239.25 152.12)
		(width 0.1)
		(layer "In5.Cu")
		(net 1025)
	)
	(segment
		(start 232.23 161.357158)
		(end 232.23 153.83421)
		(width 0.1)
		(layer "In5.Cu")
		(net 1025)
	)
	(segment
		(start 235.03421 151.03)
		(end 237.41 151.03)
		(width 0.1)
		(layer "In5.Cu")
		(net 1025)
	)
	(segment
		(start 241.275 144.485)
		(end 241.76 144.97)
		(width 0.1)
		(layer "In7.Cu")
		(net 1025)
	)
	(segment
		(start 241.76 149.25)
		(end 241.76 149.39)
		(width 0.1)
		(layer "In7.Cu")
		(net 1025)
	)
	(segment
		(start 241.76 149.39)
		(end 240.59 150.56)
		(width 0.1)
		(layer "In7.Cu")
		(net 1025)
	)
	(segment
		(start 241.76 144.97)
		(end 241.76 149.25)
		(width 0.1)
		(layer "In7.Cu")
		(net 1025)
	)
	(segment
		(start 241.275 143.925)
		(end 241.275 144.485)
		(width 0.1)
		(layer "In7.Cu")
		(net 1025)
	)
	(segment
		(start 238.35 137.7)
		(end 237.25 137.7)
		(width 0.177)
		(layer "F.Cu")
		(net 1047)
	)
	(segment
		(start 238.8 137.7)
		(end 238.35 137.7)
		(width 0.1)
		(layer "F.Cu")
		(net 1047)
	)
	(segment
		(start 237.8 139.13)
		(end 238.79 139.13)
		(width 0.1)
		(layer "F.Cu")
		(net 1047)
	)
	(segment
		(start 177.77 185.36)
		(end 177.77 188.64)
		(width 0.1)
		(layer "F.Cu")
		(net 1047)
	)
	(segment
		(start 238.93 138.99)
		(end 238.93 137.83)
		(width 0.1)
		(layer "F.Cu")
		(net 1047)
	)
	(segment
		(start 238.79 139.13)
		(end 238.93 138.99)
		(width 0.1)
		(layer "F.Cu")
		(net 1047)
	)
	(segment
		(start 238.93 137.83)
		(end 238.8 137.7)
		(width 0.1)
		(layer "F.Cu")
		(net 1047)
	)
	(via
		(at 237.8 139.13)
		(size 0.45)
		(drill 0.2)
		(layers "F.Cu" "B.Cu")
		(net 1047)
	)
	(via
		(at 177.77 185.36)
		(size 0.45)
		(drill 0.2)
		(layers "F.Cu" "B.Cu")
		(net 1047)
	)
	(via
		(at 238.93 149.95)
		(size 0.45)
		(drill 0.2)
		(layers "F.Cu" "B.Cu")
		(net 1047)
	)
	(segment
		(start 216.028632 166.39)
		(end 219.363631 163.055)
		(width 0.1)
		(layer "In5.Cu")
		(net 1047)
	)
	(segment
		(start 181.89 175.859999)
		(end 189.15 168.6)
		(width 0.1)
		(layer "In5.Cu")
		(net 1047)
	)
	(segment
		(start 227.38 162.1)
		(end 230.072948 162.1)
		(width 0.1)
		(layer "In5.Cu")
		(net 1047)
	)
	(segment
		(start 219.363631 163.055)
		(end 226.425 163.055)
		(width 0.1)
		(layer "In5.Cu")
		(net 1047)
	)
	(segment
		(start 195.85 168.6)
		(end 198.06 166.39)
		(width 0.1)
		(layer "In5.Cu")
		(net 1047)
	)
	(segment
		(start 179.62 185.36)
		(end 181.89 183.09)
		(width 0.1)
		(layer "In5.Cu")
		(net 1047)
	)
	(segment
		(start 238.88 150)
		(end 238.93 149.95)
		(width 0.1)
		(layer "In5.Cu")
		(net 1047)
	)
	(segment
		(start 226.425 163.055)
		(end 227.38 162.1)
		(width 0.1)
		(layer "In5.Cu")
		(net 1047)
	)
	(segment
		(start 231.21 160.962948)
		(end 231.21 153.439997)
		(width 0.1)
		(layer "In5.Cu")
		(net 1047)
	)
	(segment
		(start 181.89 183.09)
		(end 181.89 175.859999)
		(width 0.1)
		(layer "In5.Cu")
		(net 1047)
	)
	(segment
		(start 234.649998 150)
		(end 238.88 150)
		(width 0.1)
		(layer "In5.Cu")
		(net 1047)
	)
	(segment
		(start 230.072948 162.1)
		(end 231.21 160.962948)
		(width 0.1)
		(layer "In5.Cu")
		(net 1047)
	)
	(segment
		(start 177.77 185.36)
		(end 179.62 185.36)
		(width 0.1)
		(layer "In5.Cu")
		(net 1047)
	)
	(segment
		(start 198.06 166.39)
		(end 216.028632 166.39)
		(width 0.1)
		(layer "In5.Cu")
		(net 1047)
	)
	(segment
		(start 231.21 153.439997)
		(end 234.649998 150)
		(width 0.1)
		(layer "In5.Cu")
		(net 1047)
	)
	(segment
		(start 189.15 168.6)
		(end 195.85 168.6)
		(width 0.1)
		(layer "In5.Cu")
		(net 1047)
	)
	(segment
		(start 237.68 148.7)
		(end 238.93 149.95)
		(width 0.1)
		(layer "In7.Cu")
		(net 1047)
	)
	(segment
		(start 237.8 139.13)
		(end 237.68 139.25)
		(width 0.1)
		(layer "In7.Cu")
		(net 1047)
	)
	(segment
		(start 237.68 147.81)
		(end 237.68 148.7)
		(width 0.1)
		(layer "In7.Cu")
		(net 1047)
	)
	(segment
		(start 237.68 139.25)
		(end 237.68 147.81)
		(width 0.1)
		(layer "In7.Cu")
		(net 1047)
	)
	(segment
		(start 176.45 167.05)
		(end 176.4375 167.0625)
		(width 0.4)
		(layer "F.Cu")
		(net 1052)
	)
	(segment
		(start 176.4375 167.0625)
		(end 176.4375 167.6875)
		(width 0.4)
		(layer "F.Cu")
		(net 1052)
	)
	(via
		(at 176.45 167.05)
		(size 0.45)
		(drill 0.2)
		(layers "F.Cu" "B.Cu")
		(net 1052)
	)
	(segment
		(start 176.45 167.05)
		(end 176.585 167.185)
		(width 0.4)
		(layer "B.Cu")
		(net 1052)
	)
	(segment
		(start 176.585 167.185)
		(end 176.585 167.8)
		(width 0.4)
		(layer "B.Cu")
		(net 1052)
	)
	(segment
		(start 215.95 145.96)
		(end 215.08 146.83)
		(width 0.1)
		(layer "F.Cu")
		(net 1053)
	)
	(segment
		(start 169.7 176.5)
		(end 169.7 176.78)
		(width 0.1)
		(layer "F.Cu")
		(net 1053)
	)
	(segment
		(start 169.7 176.78)
		(end 169.46 177.02)
		(width 0.1)
		(layer "F.Cu")
		(net 1053)
	)
	(segment
		(start 215.95 140.58)
		(end 215.95 145.96)
		(width 0.1)
		(layer "F.Cu")
		(net 1053)
	)
	(segment
		(start 216.79 138.99)
		(end 216.28 139.5)
		(width 0.1)
		(layer "F.Cu")
		(net 1053)
	)
	(segment
		(start 216.28 139.5)
		(end 216.28 140.25)
		(width 0.1)
		(layer "F.Cu")
		(net 1053)
	)
	(segment
		(start 216.28 140.25)
		(end 215.95 140.58)
		(width 0.1)
		(layer "F.Cu")
		(net 1053)
	)
	(segment
		(start 213.5 134.5)
		(end 213.986054 134.986054)
		(width 0.256)
		(layer "F.Cu")
		(net 1053)
	)
	(segment
		(start 213.986054 134.986054)
		(end 213.986054 135.001766)
		(width 0.256)
		(layer "F.Cu")
		(net 1053)
	)
	(via
		(at 169.46 177.02)
		(size 0.45)
		(drill 0.2)
		(layers "F.Cu" "B.Cu")
		(net 1053)
	)
	(via
		(at 216.8 136.08)
		(size 0.45)
		(drill 0.2)
		(layers "F.Cu" "B.Cu")
		(net 1053)
	)
	(via
		(at 216.79 138.99)
		(size 0.45)
		(drill 0.2)
		(layers "F.Cu" "B.Cu")
		(net 1053)
	)
	(via
		(at 213.986054 135.001766)
		(size 0.45)
		(drill 0.2)
		(layers "F.Cu" "B.Cu")
		(net 1053)
	)
	(via
		(at 215.08 146.83)
		(size 0.45)
		(drill 0.2)
		(layers "F.Cu" "B.Cu")
		(net 1053)
	)
	(segment
		(start 216.8 138.98)
		(end 216.79 138.99)
		(width 0.1)
		(layer "B.Cu")
		(net 1053)
	)
	(segment
		(start 216.8 136.08)
		(end 216.8 138.98)
		(width 0.1)
		(layer "B.Cu")
		(net 1053)
	)
	(segment
		(start 214.47 152.02)
		(end 215.08 151.41)
		(width 0.1)
		(layer "In3.Cu")
		(net 1053)
	)
	(segment
		(start 183.76 174.14)
		(end 183.76 173.7)
		(width 0.1)
		(layer "In3.Cu")
		(net 1053)
	)
	(segment
		(start 210.32 154.24)
		(end 212.54 152.02)
		(width 0.1)
		(layer "In3.Cu")
		(net 1053)
	)
	(segment
		(start 186.05 163.97)
		(end 186.05 159.55)
		(width 0.1)
		(layer "In3.Cu")
		(net 1053)
	)
	(segment
		(start 193.02 155.34)
		(end 204.54 155.34)
		(width 0.1)
		(layer "In3.Cu")
		(net 1053)
	)
	(segment
		(start 183.69 178.53)
		(end 183.76 178.46)
		(width 0.1)
		(layer "In3.Cu")
		(net 1053)
	)
	(segment
		(start 187.31 158.29)
		(end 189.77 158.29)
		(width 0.1)
		(layer "In3.Cu")
		(net 1053)
	)
	(segment
		(start 170.49 179.87)
		(end 181.01 179.87)
		(width 0.1)
		(layer "In3.Cu")
		(net 1053)
	)
	(segment
		(start 204.55 155.35)
		(end 209.21 155.35)
		(width 0.1)
		(layer "In3.Cu")
		(net 1053)
	)
	(segment
		(start 186.05 159.55)
		(end 186.92 158.68)
		(width 0.1)
		(layer "In3.Cu")
		(net 1053)
	)
	(segment
		(start 183.76 178.46)
		(end 183.76 174.14)
		(width 0.1)
		(layer "In3.Cu")
		(net 1053)
	)
	(segment
		(start 189.77 158.29)
		(end 190.07 158.29)
		(width 0.1)
		(layer "In3.Cu")
		(net 1053)
	)
	(segment
		(start 215.08 151.41)
		(end 215.08 146.83)
		(width 0.1)
		(layer "In3.Cu")
		(net 1053)
	)
	(segment
		(start 183.76 173.7)
		(end 181.56 171.5)
		(width 0.1)
		(layer "In3.Cu")
		(net 1053)
	)
	(segment
		(start 181.56 171.5)
		(end 181.56 168.46)
		(width 0.1)
		(layer "In3.Cu")
		(net 1053)
	)
	(segment
		(start 209.21 155.35)
		(end 210.32 154.24)
		(width 0.1)
		(layer "In3.Cu")
		(net 1053)
	)
	(segment
		(start 186.92 158.68)
		(end 187.31 158.29)
		(width 0.1)
		(layer "In3.Cu")
		(net 1053)
	)
	(segment
		(start 169.46 178.84)
		(end 170.2 179.58)
		(width 0.1)
		(layer "In3.Cu")
		(net 1053)
	)
	(segment
		(start 181.56 168.46)
		(end 183.36 166.66)
		(width 0.1)
		(layer "In3.Cu")
		(net 1053)
	)
	(segment
		(start 182.35 179.87)
		(end 183.69 178.53)
		(width 0.1)
		(layer "In3.Cu")
		(net 1053)
	)
	(segment
		(start 181.01 179.87)
		(end 182.35 179.87)
		(width 0.1)
		(layer "In3.Cu")
		(net 1053)
	)
	(segment
		(start 169.46 177.02)
		(end 169.46 178.84)
		(width 0.1)
		(layer "In3.Cu")
		(net 1053)
	)
	(segment
		(start 204.54 155.34)
		(end 204.55 155.35)
		(width 0.1)
		(layer "In3.Cu")
		(net 1053)
	)
	(segment
		(start 213.99 152.02)
		(end 214.47 152.02)
		(width 0.1)
		(layer "In3.Cu")
		(net 1053)
	)
	(segment
		(start 190.07 158.29)
		(end 193.02 155.34)
		(width 0.1)
		(layer "In3.Cu")
		(net 1053)
	)
	(segment
		(start 183.36 166.66)
		(end 186.05 163.97)
		(width 0.1)
		(layer "In3.Cu")
		(net 1053)
	)
	(segment
		(start 212.54 152.02)
		(end 213.99 152.02)
		(width 0.1)
		(layer "In3.Cu")
		(net 1053)
	)
	(segment
		(start 170.2 179.58)
		(end 170.49 179.87)
		(width 0.1)
		(layer "In3.Cu")
		(net 1053)
	)
	(segment
		(start 214.384288 135.4)
		(end 216.12 135.4)
		(width 0.1)
		(layer "In7.Cu")
		(net 1053)
	)
	(segment
		(start 216.12 135.4)
		(end 216.8 136.08)
		(width 0.1)
		(layer "In7.Cu")
		(net 1053)
	)
	(segment
		(start 213.986054 135.001766)
		(end 214.384288 135.4)
		(width 0.1)
		(layer "In7.Cu")
		(net 1053)
	)
	(via
		(at 249.65 150.25)
		(size 0.45)
		(drill 0.2)
		(layers "F.Cu" "B.Cu")
		(net 1054)
	)
	(segment
		(start 249.65 149.5)
		(end 249.7 149.45)
		(width 0.177)
		(layer "B.Cu")
		(net 1054)
	)
	(segment
		(start 249.65 150.25)
		(end 249.65 149.5)
		(width 0.177)
		(layer "B.Cu")
		(net 1054)
	)
	(segment
		(start 153.75 155.2)
		(end 153.175 155.2)
		(width 0.182)
		(layer "F.Cu")
		(net 1055)
	)
	(segment
		(start 153.125 155.25)
		(end 153.175 155.2)
		(width 0.256)
		(layer "F.Cu")
		(net 1055)
	)
	(segment
		(start 152.46 155.25)
		(end 153.125 155.25)
		(width 0.256)
		(layer "F.Cu")
		(net 1055)
	)
	(via
		(at 248.65 150.25)
		(size 0.45)
		(drill 0.2)
		(layers "F.Cu" "B.Cu")
		(net 1060)
	)
	(segment
		(start 248.65 149.6)
		(end 248.5 149.45)
		(width 0.177)
		(layer "B.Cu")
		(net 1060)
	)
	(segment
		(start 248.65 150.25)
		(end 248.65 149.6)
		(width 0.177)
		(layer "B.Cu")
		(net 1060)
	)
	(via
		(at 247.65 128.6)
		(size 0.45)
		(drill 0.2)
		(layers "F.Cu" "B.Cu")
		(net 1061)
	)
	(segment
		(start 247.65 128.6)
		(end 247.65 128.25)
		(width 0.177)
		(layer "B.Cu")
		(net 1061)
	)
	(segment
		(start 247.65 128.25)
		(end 247.7 128.2)
		(width 0.177)
		(layer "B.Cu")
		(net 1061)
	)
	(segment
		(start 249.15 128.9)
		(end 249.15 127.775)
		(width 0.1)
		(layer "F.Cu")
		(net 1062)
	)
	(segment
		(start 249.17 128.92)
		(end 249.15 128.9)
		(width 0.1)
		(layer "F.Cu")
		(net 1062)
	)
	(via
		(at 249.17 128.92)
		(size 0.45)
		(drill 0.2)
		(layers "F.Cu" "B.Cu")
		(net 1062)
	)
	(segment
		(start 249.17 128.33)
		(end 249.3 128.2)
		(width 0.177)
		(layer "B.Cu")
		(net 1062)
	)
	(segment
		(start 249.17 128.92)
		(end 249.17 128.33)
		(width 0.177)
		(layer "B.Cu")
		(net 1062)
	)
	(via
		(at 252.65 128.6)
		(size 0.45)
		(drill 0.2)
		(layers "F.Cu" "B.Cu")
		(net 1063)
	)
	(segment
		(start 252.65 128.35)
		(end 252.5 128.2)
		(width 0.177)
		(layer "B.Cu")
		(net 1063)
	)
	(segment
		(start 252.65 128.6)
		(end 252.65 128.35)
		(width 0.177)
		(layer "B.Cu")
		(net 1063)
	)
	(via
		(at 253.65 128.6)
		(size 0.45)
		(drill 0.2)
		(layers "F.Cu" "B.Cu")
		(net 1064)
	)
	(segment
		(start 253.65 128.25)
		(end 253.7 128.2)
		(width 0.177)
		(layer "B.Cu")
		(net 1064)
	)
	(segment
		(start 253.65 128.6)
		(end 253.65 128.25)
		(width 0.177)
		(layer "B.Cu")
		(net 1064)
	)
	(via
		(at 254.65 128.6)
		(size 0.45)
		(drill 0.2)
		(layers "F.Cu" "B.Cu")
		(net 1065)
	)
	(segment
		(start 254.65 128.6)
		(end 254.65 128.35)
		(width 0.177)
		(layer "B.Cu")
		(net 1065)
	)
	(segment
		(start 254.65 128.35)
		(end 254.5 128.2)
		(width 0.177)
		(layer "B.Cu")
		(net 1065)
	)
	(segment
		(start 253.164171 128.856755)
		(end 253.164171 127.789171)
		(width 0.1)
		(layer "F.Cu")
		(net 1066)
	)
	(segment
		(start 253.164171 127.789171)
		(end 253.15 127.775)
		(width 0.1)
		(layer "F.Cu")
		(net 1066)
	)
	(via
		(at 253.164171 128.856755)
		(size 0.45)
		(drill 0.2)
		(layers "F.Cu" "B.Cu")
		(net 1066)
	)
	(segment
		(start 253.164171 128.856755)
		(end 253.164171 128.335829)
		(width 0.177)
		(layer "B.Cu")
		(net 1066)
	)
	(segment
		(start 253.164171 128.335829)
		(end 253.3 128.2)
		(width 0.177)
		(layer "B.Cu")
		(net 1066)
	)
	(segment
		(start 246.15 122.45)
		(end 246 122.3)
		(width 0.177)
		(layer "F.Cu")
		(net 1067)
	)
	(segment
		(start 246.15 123.825)
		(end 246.15 122.45)
		(width 0.177)
		(layer "F.Cu")
		(net 1067)
	)
	(via
		(at 249.65 128.6)
		(size 0.45)
		(drill 0.2)
		(layers "F.Cu" "B.Cu")
		(net 1068)
	)
	(segment
		(start 249.65 128.6)
		(end 249.65 128.25)
		(width 0.177)
		(layer "B.Cu")
		(net 1068)
	)
	(segment
		(start 249.65 128.25)
		(end 249.7 128.2)
		(width 0.177)
		(layer "B.Cu")
		(net 1068)
	)
	(via
		(at 252.15 149.9)
		(size 0.45)
		(drill 0.2)
		(layers "F.Cu" "B.Cu")
		(net 1069)
	)
	(segment
		(start 252.15 149.9)
		(end 252.15 149.5)
		(width 0.177)
		(layer "B.Cu")
		(net 1069)
	)
	(segment
		(start 252.15 149.5)
		(end 252.1 149.45)
		(width 0.177)
		(layer "B.Cu")
		(net 1069)
	)
	(segment
		(start 254.15 146.125)
		(end 254.15 144.65)
		(width 0.177)
		(layer "F.Cu")
		(net 1070)
	)
	(segment
		(start 254.15 144.65)
		(end 254.1 144.6)
		(width 0.177)
		(layer "F.Cu")
		(net 1070)
	)
	(segment
		(start 250.15 123.825)
		(end 250.15 122.45)
		(width 0.177)
		(layer "F.Cu")
		(net 1071)
	)
	(segment
		(start 250.15 122.45)
		(end 250 122.3)
		(width 0.177)
		(layer "F.Cu")
		(net 1071)
	)
	(segment
		(start 249.65 122.35)
		(end 249.6 122.3)
		(width 0.177)
		(layer "F.Cu")
		(net 1072)
	)
	(segment
		(start 249.65 123.825)
		(end 249.65 122.35)
		(width 0.177)
		(layer "F.Cu")
		(net 1072)
	)
	(segment
		(start 249.15 122.35)
		(end 249.2 122.3)
		(width 0.177)
		(layer "F.Cu")
		(net 1073)
	)
	(segment
		(start 249.15 123.825)
		(end 249.15 122.35)
		(width 0.177)
		(layer "F.Cu")
		(net 1073)
	)
	(via
		(at 248.65 128.6)
		(size 0.45)
		(drill 0.2)
		(layers "F.Cu" "B.Cu")
		(net 1074)
	)
	(segment
		(start 248.65 128.6)
		(end 248.65 128.35)
		(width 0.177)
		(layer "B.Cu")
		(net 1074)
	)
	(segment
		(start 248.65 128.35)
		(end 248.5 128.2)
		(width 0.177)
		(layer "B.Cu")
		(net 1074)
	)
	(segment
		(start 247.65 122.35)
		(end 247.6 122.3)
		(width 0.177)
		(layer "F.Cu")
		(net 1075)
	)
	(segment
		(start 247.65 123.825)
		(end 247.65 122.35)
		(width 0.177)
		(layer "F.Cu")
		(net 1075)
	)
	(segment
		(start 245.15 122.35)
		(end 245.2 122.3)
		(width 0.177)
		(layer "F.Cu")
		(net 1076)
	)
	(segment
		(start 245.15 123.825)
		(end 245.15 122.35)
		(width 0.177)
		(layer "F.Cu")
		(net 1076)
	)
	(segment
		(start 250.15 128.8605)
		(end 250.15 127.775)
		(width 0.1)
		(layer "F.Cu")
		(net 1077)
	)
	(via
		(at 250.15 128.8605)
		(size 0.45)
		(drill 0.2)
		(layers "F.Cu" "B.Cu")
		(net 1077)
	)
	(segment
		(start 250.15 128.8605)
		(end 250.15 128.25)
		(width 0.177)
		(layer "B.Cu")
		(net 1077)
	)
	(segment
		(start 250.15 128.25)
		(end 250.1 128.2)
		(width 0.177)
		(layer "B.Cu")
		(net 1077)
	)
	(segment
		(start 245.65 122.35)
		(end 245.6 122.3)
		(width 0.177)
		(layer "F.Cu")
		(net 1078)
	)
	(segment
		(start 245.65 123.825)
		(end 245.65 122.35)
		(width 0.177)
		(layer "F.Cu")
		(net 1078)
	)
	(via
		(at 250.65 128.6)
		(size 0.45)
		(drill 0.2)
		(layers "F.Cu" "B.Cu")
		(net 1079)
	)
	(segment
		(start 250.65 128.35)
		(end 250.5 128.2)
		(width 0.177)
		(layer "B.Cu")
		(net 1079)
	)
	(segment
		(start 250.65 128.6)
		(end 250.65 128.35)
		(width 0.177)
		(layer "B.Cu")
		(net 1079)
	)
	(segment
		(start 247.15 122.35)
		(end 247.2 122.3)
		(width 0.177)
		(layer "F.Cu")
		(net 1080)
	)
	(segment
		(start 247.15 123.825)
		(end 247.15 122.35)
		(width 0.177)
		(layer "F.Cu")
		(net 1080)
	)
	(segment
		(start 251.15 123.825)
		(end 251.15 122.35)
		(width 0.177)
		(layer "F.Cu")
		(net 1081)
	)
	(segment
		(start 251.15 122.35)
		(end 251.2 122.3)
		(width 0.177)
		(layer "F.Cu")
		(net 1081)
	)
	(segment
		(start 250.65 122.45)
		(end 250.8 122.3)
		(width 0.177)
		(layer "F.Cu")
		(net 1082)
	)
	(segment
		(start 250.65 123.825)
		(end 250.65 122.45)
		(width 0.177)
		(layer "F.Cu")
		(net 1082)
	)
	(segment
		(start 248.150001 128.827929)
		(end 248.15 127.775)
		(width 0.1)
		(layer "F.Cu")
		(net 1083)
	)
	(via
		(at 248.150001 128.827929)
		(size 0.45)
		(drill 0.2)
		(layers "F.Cu" "B.Cu")
		(net 1083)
	)
	(segment
		(start 248.150001 128.827929)
		(end 248.150001 128.250001)
		(width 0.177)
		(layer "B.Cu")
		(net 1083)
	)
	(segment
		(start 248.150001 128.250001)
		(end 248.1 128.2)
		(width 0.177)
		(layer "B.Cu")
		(net 1083)
	)
	(segment
		(start 251.65 122.35)
		(end 251.6 122.3)
		(width 0.177)
		(layer "F.Cu")
		(net 1084)
	)
	(segment
		(start 251.65 123.825)
		(end 251.65 122.35)
		(width 0.177)
		(layer "F.Cu")
		(net 1084)
	)
	(segment
		(start 251.15 144.75)
		(end 251.3 144.6)
		(width 0.177)
		(layer "F.Cu")
		(net 1085)
	)
	(segment
		(start 251.15 146.125)
		(end 251.15 144.75)
		(width 0.177)
		(layer "F.Cu")
		(net 1085)
	)
	(segment
		(start 253.65 146.125)
		(end 253.65 144.65)
		(width 0.177)
		(layer "F.Cu")
		(net 1086)
	)
	(segment
		(start 253.65 144.65)
		(end 253.7 144.6)
		(width 0.177)
		(layer "F.Cu")
		(net 1086)
	)
	(segment
		(start 252.15 123.825)
		(end 252.15 122.45)
		(width 0.177)
		(layer "F.Cu")
		(net 1087)
	)
	(segment
		(start 252.15 122.45)
		(end 252 122.3)
		(width 0.177)
		(layer "F.Cu")
		(net 1087)
	)
	(via
		(at 251.15 149.9)
		(size 0.45)
		(drill 0.2)
		(layers "F.Cu" "B.Cu")
		(net 1088)
	)
	(segment
		(start 251.15 149.6)
		(end 251.3 149.45)
		(width 0.177)
		(layer "B.Cu")
		(net 1088)
	)
	(segment
		(start 251.15 149.9)
		(end 251.15 149.6)
		(width 0.177)
		(layer "B.Cu")
		(net 1088)
	)
	(via
		(at 254.15 149.9)
		(size 0.45)
		(drill 0.2)
		(layers "F.Cu" "B.Cu")
		(net 1089)
	)
	(segment
		(start 254.15 149.9)
		(end 254.15 149.5)
		(width 0.177)
		(layer "B.Cu")
		(net 1089)
	)
	(segment
		(start 254.15 149.5)
		(end 254.1 149.45)
		(width 0.177)
		(layer "B.Cu")
		(net 1089)
	)
	(via
		(at 252.65 150.25)
		(size 0.45)
		(drill 0.2)
		(layers "F.Cu" "B.Cu")
		(net 1090)
	)
	(segment
		(start 252.65 149.6)
		(end 252.5 149.45)
		(width 0.177)
		(layer "B.Cu")
		(net 1090)
	)
	(segment
		(start 252.65 150.25)
		(end 252.65 149.6)
		(width 0.177)
		(layer "B.Cu")
		(net 1090)
	)
	(via
		(at 253.15 149.9)
		(size 0.45)
		(drill 0.2)
		(layers "F.Cu" "B.Cu")
		(net 1091)
	)
	(segment
		(start 253.15 149.6)
		(end 253.3 149.45)
		(width 0.177)
		(layer "B.Cu")
		(net 1091)
	)
	(segment
		(start 253.15 149.9)
		(end 253.15 149.6)
		(width 0.177)
		(layer "B.Cu")
		(net 1091)
	)
	(segment
		(start 250.15 146.125)
		(end 250.15 144.65)
		(width 0.177)
		(layer "F.Cu")
		(net 1092)
	)
	(segment
		(start 250.15 144.65)
		(end 250.1 144.6)
		(width 0.177)
		(layer "F.Cu")
		(net 1092)
	)
	(segment
		(start 253.15 146.125)
		(end 253.15 144.75)
		(width 0.177)
		(layer "F.Cu")
		(net 1093)
	)
	(segment
		(start 253.15 144.75)
		(end 253.3 144.6)
		(width 0.177)
		(layer "F.Cu")
		(net 1093)
	)
	(segment
		(start 254.65 146.125)
		(end 254.65 144.75)
		(width 0.177)
		(layer "F.Cu")
		(net 1094)
	)
	(segment
		(start 254.65 144.75)
		(end 254.5 144.6)
		(width 0.177)
		(layer "F.Cu")
		(net 1094)
	)
	(via
		(at 248.15 149.9)
		(size 0.45)
		(drill 0.2)
		(layers "F.Cu" "B.Cu")
		(net 1095)
	)
	(segment
		(start 248.15 149.5)
		(end 248.1 149.45)
		(width 0.177)
		(layer "B.Cu")
		(net 1095)
	)
	(segment
		(start 248.15 149.9)
		(end 248.15 149.5)
		(width 0.177)
		(layer "B.Cu")
		(net 1095)
	)
	(via
		(at 253.65 150.25)
		(size 0.45)
		(drill 0.2)
		(layers "F.Cu" "B.Cu")
		(net 1096)
	)
	(segment
		(start 253.65 150.25)
		(end 253.65 149.5)
		(width 0.177)
		(layer "B.Cu")
		(net 1096)
	)
	(segment
		(start 253.65 149.5)
		(end 253.7 149.45)
		(width 0.177)
		(layer "B.Cu")
		(net 1096)
	)
	(via
		(at 254.65 150.25)
		(size 0.45)
		(drill 0.2)
		(layers "F.Cu" "B.Cu")
		(net 1097)
	)
	(segment
		(start 254.65 150.25)
		(end 254.65 149.6)
		(width 0.177)
		(layer "B.Cu")
		(net 1097)
	)
	(segment
		(start 254.65 149.6)
		(end 254.5 149.45)
		(width 0.177)
		(layer "B.Cu")
		(net 1097)
	)
	(segment
		(start 245.15 144.75)
		(end 245.3 144.6)
		(width 0.177)
		(layer "F.Cu")
		(net 1098)
	)
	(segment
		(start 245.15 146.125)
		(end 245.15 144.75)
		(width 0.177)
		(layer "F.Cu")
		(net 1098)
	)
	(via
		(at 246.15 149.9)
		(size 0.45)
		(drill 0.2)
		(layers "F.Cu" "B.Cu")
		(net 1099)
	)
	(segment
		(start 246.15 149.5)
		(end 246.1 149.45)
		(width 0.177)
		(layer "B.Cu")
		(net 1099)
	)
	(segment
		(start 246.15 149.9)
		(end 246.15 149.5)
		(width 0.177)
		(layer "B.Cu")
		(net 1099)
	)
	(segment
		(start 252.65 146.125)
		(end 252.65 144.75)
		(width 0.177)
		(layer "F.Cu")
		(net 1100)
	)
	(segment
		(start 252.65 144.75)
		(end 252.5 144.6)
		(width 0.177)
		(layer "F.Cu")
		(net 1100)
	)
	(segment
		(start 254.137677 128.856151)
		(end 254.137677 127.787323)
		(width 0.1)
		(layer "F.Cu")
		(net 1101)
	)
	(segment
		(start 254.137677 127.787323)
		(end 254.15 127.775)
		(width 0.1)
		(layer "F.Cu")
		(net 1101)
	)
	(via
		(at 254.137677 128.856151)
		(size 0.45)
		(drill 0.2)
		(layers "F.Cu" "B.Cu")
		(net 1101)
	)
	(segment
		(start 254.137677 128.237677)
		(end 254.1 128.2)
		(width 0.177)
		(layer "B.Cu")
		(net 1101)
	)
	(segment
		(start 254.137677 128.856151)
		(end 254.137677 128.237677)
		(width 0.177)
		(layer "B.Cu")
		(net 1101)
	)
	(segment
		(start 246.65 146.125)
		(end 246.65 144.75)
		(width 0.177)
		(layer "F.Cu")
		(net 1102)
	)
	(segment
		(start 246.65 144.75)
		(end 246.5 144.6)
		(width 0.177)
		(layer "F.Cu")
		(net 1102)
	)
	(segment
		(start 247.65 144.65)
		(end 247.7 144.6)
		(width 0.177)
		(layer "F.Cu")
		(net 1103)
	)
	(segment
		(start 247.65 146.125)
		(end 247.65 144.65)
		(width 0.177)
		(layer "F.Cu")
		(net 1103)
	)
	(segment
		(start 249.15 144.75)
		(end 249.3 144.6)
		(width 0.177)
		(layer "F.Cu")
		(net 1104)
	)
	(segment
		(start 249.15 146.125)
		(end 249.15 144.75)
		(width 0.177)
		(layer "F.Cu")
		(net 1104)
	)
	(via
		(at 251.65 150.25)
		(size 0.45)
		(drill 0.2)
		(layers "F.Cu" "B.Cu")
		(net 1105)
	)
	(segment
		(start 251.65 149.5)
		(end 251.7 149.45)
		(width 0.177)
		(layer "B.Cu")
		(net 1105)
	)
	(segment
		(start 251.65 150.25)
		(end 251.65 149.5)
		(width 0.177)
		(layer "B.Cu")
		(net 1105)
	)
	(segment
		(start 247.15 144.75)
		(end 247.3 144.6)
		(width 0.177)
		(layer "F.Cu")
		(net 1106)
	)
	(segment
		(start 247.15 146.125)
		(end 247.15 144.75)
		(width 0.177)
		(layer "F.Cu")
		(net 1106)
	)
	(segment
		(start 251.65 144.65)
		(end 251.7 144.6)
		(width 0.177)
		(layer "F.Cu")
		(net 1107)
	)
	(segment
		(start 251.65 146.125)
		(end 251.65 144.65)
		(width 0.177)
		(layer "F.Cu")
		(net 1107)
	)
	(segment
		(start 252.146554 128.846554)
		(end 252.146554 127.778446)
		(width 0.1)
		(layer "F.Cu")
		(net 1108)
	)
	(segment
		(start 252.146554 127.778446)
		(end 252.15 127.775)
		(width 0.1)
		(layer "F.Cu")
		(net 1108)
	)
	(via
		(at 252.146554 128.846554)
		(size 0.45)
		(drill 0.2)
		(layers "F.Cu" "B.Cu")
		(net 1108)
	)
	(segment
		(start 252.146554 128.246554)
		(end 252.1 128.2)
		(width 0.177)
		(layer "B.Cu")
		(net 1108)
	)
	(segment
		(start 252.146554 128.846554)
		(end 252.146554 128.246554)
		(width 0.177)
		(layer "B.Cu")
		(net 1108)
	)
	(via
		(at 246.65 150.25)
		(size 0.45)
		(drill 0.2)
		(layers "F.Cu" "B.Cu")
		(net 1109)
	)
	(segment
		(start 246.65 149.6)
		(end 246.5 149.45)
		(width 0.177)
		(layer "B.Cu")
		(net 1109)
	)
	(segment
		(start 246.65 150.25)
		(end 246.65 149.6)
		(width 0.177)
		(layer "B.Cu")
		(net 1109)
	)
	(segment
		(start 245.65 144.65)
		(end 245.7 144.6)
		(width 0.177)
		(layer "F.Cu")
		(net 1110)
	)
	(segment
		(start 245.65 146.125)
		(end 245.65 144.65)
		(width 0.177)
		(layer "F.Cu")
		(net 1110)
	)
	(segment
		(start 246.15 144.65)
		(end 246.1 144.6)
		(width 0.177)
		(layer "F.Cu")
		(net 1111)
	)
	(segment
		(start 246.15 146.125)
		(end 246.15 144.65)
		(width 0.177)
		(layer "F.Cu")
		(net 1111)
	)
	(via
		(at 247.15 149.9)
		(size 0.45)
		(drill 0.2)
		(layers "F.Cu" "B.Cu")
		(net 1112)
	)
	(segment
		(start 247.15 149.6)
		(end 247.3 149.45)
		(width 0.177)
		(layer "B.Cu")
		(net 1112)
	)
	(segment
		(start 247.15 149.9)
		(end 247.15 149.6)
		(width 0.177)
		(layer "B.Cu")
		(net 1112)
	)
	(via
		(at 247.65 150.25)
		(size 0.45)
		(drill 0.2)
		(layers "F.Cu" "B.Cu")
		(net 1113)
	)
	(segment
		(start 247.65 149.5)
		(end 247.7 149.45)
		(width 0.177)
		(layer "B.Cu")
		(net 1113)
	)
	(segment
		(start 247.65 150.25)
		(end 247.65 149.5)
		(width 0.177)
		(layer "B.Cu")
		(net 1113)
	)
	(via
		(at 250.65 150.25)
		(size 0.45)
		(drill 0.2)
		(layers "F.Cu" "B.Cu")
		(net 1114)
	)
	(segment
		(start 250.65 150.25)
		(end 250.65 149.6)
		(width 0.177)
		(layer "B.Cu")
		(net 1114)
	)
	(segment
		(start 250.65 149.6)
		(end 250.5 149.45)
		(width 0.177)
		(layer "B.Cu")
		(net 1114)
	)
	(segment
		(start 248.65 144.75)
		(end 248.5 144.6)
		(width 0.177)
		(layer "F.Cu")
		(net 1115)
	)
	(segment
		(start 248.65 146.125)
		(end 248.65 144.75)
		(width 0.177)
		(layer "F.Cu")
		(net 1115)
	)
	(segment
		(start 248.15 144.65)
		(end 248.1 144.6)
		(width 0.177)
		(layer "F.Cu")
		(net 1116)
	)
	(segment
		(start 248.15 146.125)
		(end 248.15 144.65)
		(width 0.177)
		(layer "F.Cu")
		(net 1116)
	)
	(segment
		(start 250.65 146.125)
		(end 250.65 144.75)
		(width 0.177)
		(layer "F.Cu")
		(net 1117)
	)
	(segment
		(start 250.65 144.75)
		(end 250.5 144.6)
		(width 0.177)
		(layer "F.Cu")
		(net 1117)
	)
	(segment
		(start 248.15 122.45)
		(end 248 122.3)
		(width 0.177)
		(layer "F.Cu")
		(net 1118)
	)
	(segment
		(start 248.15 123.825)
		(end 248.15 122.45)
		(width 0.177)
		(layer "F.Cu")
		(net 1118)
	)
	(segment
		(start 175.8 167.05)
		(end 175.7875 167.0625)
		(width 0.4)
		(layer "F.Cu")
		(net 1143)
	)
	(segment
		(start 175.7875 167.0625)
		(end 175.7875 167.6875)
		(width 0.4)
		(layer "F.Cu")
		(net 1143)
	)
	(via
		(at 175.8 167.05)
		(size 0.45)
		(drill 0.2)
		(layers "F.Cu" "B.Cu")
		(net 1143)
	)
	(segment
		(start 175.8 167.05)
		(end 175.615 167.235)
		(width 0.4)
		(layer "B.Cu")
		(net 1143)
	)
	(segment
		(start 175.615 167.235)
		(end 175.615 167.8)
		(width 0.4)
		(layer "B.Cu")
		(net 1143)
	)
	(segment
		(start 260.485 100.25)
		(end 259.715 100.25)
		(width 0.182)
		(layer "F.Cu")
		(net 1144)
	)
	(via
		(at 193.1 79.3)
		(size 0.45)
		(drill 0.2)
		(layers "F.Cu" "B.Cu")
		(net 1145)
	)
	(segment
		(start 152.2 152.1)
		(end 152.8 151.5)
		(width 0.1)
		(layer "F.Cu")
		(net 1191)
	)
	(segment
		(start 153.75 154.2)
		(end 152.7 154.2)
		(width 0.1)
		(layer "F.Cu")
		(net 1191)
	)
	(segment
		(start 152.2 153.7)
		(end 152.2 152.1)
		(width 0.1)
		(layer "F.Cu")
		(net 1191)
	)
	(segment
		(start 155.5 151.5)
		(end 156.1 150.9)
		(width 0.1)
		(layer "F.Cu")
		(net 1191)
	)
	(segment
		(start 152.8 151.5)
		(end 155.5 151.5)
		(width 0.1)
		(layer "F.Cu")
		(net 1191)
	)
	(segment
		(start 152.7 154.2)
		(end 152.2 153.7)
		(width 0.1)
		(layer "F.Cu")
		(net 1191)
	)
	(segment
		(start 156.1 150.9)
		(end 156.1 150.2375)
		(width 0.1)
		(layer "F.Cu")
		(net 1191)
	)
	(segment
		(start 236.485 135.4)
		(end 237.1 135.4)
		(width 0.177)
		(layer "F.Cu")
		(net 1205)
	)
	(segment
		(start 236.485 140)
		(end 237.1 140)
		(width 0.177)
		(layer "F.Cu")
		(net 1205)
	)
	(via
		(at 237.1 140)
		(size 0.45)
		(drill 0.2)
		(layers "F.Cu" "B.Cu")
		(net 1205)
	)
	(via
		(at 237.1 135.4)
		(size 0.45)
		(drill 0.2)
		(layers "F.Cu" "B.Cu")
		(net 1205)
	)
	(segment
		(start 236.525 139.8)
		(end 236.525 137.7)
		(width 0.177)
		(layer "B.Cu")
		(net 1205)
	)
	(segment
		(start 236.525 137.7)
		(end 236.53 137.7)
		(width 0.177)
		(layer "B.Cu")
		(net 1205)
	)
	(segment
		(start 237.1 140)
		(end 236.725 140)
		(width 0.177)
		(layer "B.Cu")
		(net 1205)
	)
	(segment
		(start 236.725 140)
		(end 236.525 139.8)
		(width 0.177)
		(layer "B.Cu")
		(net 1205)
	)
	(segment
		(start 236.53 137.7)
		(end 236.942429 137.287571)
		(width 0.177)
		(layer "B.Cu")
		(net 1205)
	)
	(segment
		(start 236.942429 135.557571)
		(end 237.1 135.4)
		(width 0.177)
		(layer "B.Cu")
		(net 1205)
	)
	(segment
		(start 236.942429 137.287571)
		(end 236.942429 135.557571)
		(width 0.177)
		(layer "B.Cu")
		(net 1205)
	)
	(segment
		(start 258.34 120.187)
		(end 258.34 120.55911)
		(width 0.1)
		(layer "F.Cu")
		(net 1213)
	)
	(segment
		(start 258.34 120.55911)
		(end 258.515 120.73411)
		(width 0.1)
		(layer "F.Cu")
		(net 1213)
	)
	(segment
		(start 258.36 120.167)
		(end 258.34 120.187)
		(width 0.1)
		(layer "F.Cu")
		(net 1213)
	)
	(via
		(at 258.515 120.73411)
		(size 0.45)
		(drill 0.2)
		(layers "F.Cu" "B.Cu")
		(net 1213)
	)
	(via
		(at 229.565545 167.994455)
		(size 0.45)
		(drill 0.2)
		(layers "F.Cu" "B.Cu")
		(net 1213)
	)
	(segment
		(start 180.258578 179.18)
		(end 179.45 178.371422)
		(width 0.1)
		(layer "B.Cu")
		(net 1213)
	)
	(segment
		(start 190.811422 170)
		(end 189.83 170.981422)
		(width 0.1)
		(layer "B.Cu")
		(net 1213)
	)
	(segment
		(start 199.591422 167.55)
		(end 197.141422 170)
		(width 0.1)
		(layer "B.Cu")
		(net 1213)
	)
	(segment
		(start 229.368578 167.55)
		(end 199.591422 167.55)
		(width 0.1)
		(layer "B.Cu")
		(net 1213)
	)
	(segment
		(start 179.45 176.1475)
		(end 179.05 175.7475)
		(width 0.1)
		(layer "B.Cu")
		(net 1213)
	)
	(segment
		(start 186.781422 179.18)
		(end 180.258578 179.18)
		(width 0.1)
		(layer "B.Cu")
		(net 1213)
	)
	(segment
		(start 229.565545 167.746967)
		(end 229.368578 167.55)
		(width 0.1)
		(layer "B.Cu")
		(net 1213)
	)
	(segment
		(start 197.141422 170)
		(end 190.811422 170)
		(width 0.1)
		(layer "B.Cu")
		(net 1213)
	)
	(segment
		(start 229.565545 167.994455)
		(end 229.565545 167.746967)
		(width 0.1)
		(layer "B.Cu")
		(net 1213)
	)
	(segment
		(start 179.45 178.371422)
		(end 179.45 176.1475)
		(width 0.1)
		(layer "B.Cu")
		(net 1213)
	)
	(segment
		(start 189.83 170.981422)
		(end 189.83 176.131422)
		(width 0.1)
		(layer "B.Cu")
		(net 1213)
	)
	(segment
		(start 189.83 176.131422)
		(end 186.781422 179.18)
		(width 0.1)
		(layer "B.Cu")
		(net 1213)
	)
	(segment
		(start 248.551422 166.89)
		(end 252.611422 166.89)
		(width 0.1)
		(layer "In7.Cu")
		(net 1213)
	)
	(segment
		(start 230.418578 168.6)
		(end 231.741422 168.6)
		(width 0.1)
		(layer "In7.Cu")
		(net 1213)
	)
	(segment
		(start 264.041422 126.19)
		(end 262.871422 125.02)
		(width 0.1)
		(layer "In7.Cu")
		(net 1213)
	)
	(segment
		(start 252.611422 166.89)
		(end 253.291422 166.21)
		(width 0.1)
		(layer "In7.Cu")
		(net 1213)
	)
	(segment
		(start 229.565545 167.994455)
		(end 229.813033 167.994455)
		(width 0.1)
		(layer "In7.Cu")
		(net 1213)
	)
	(segment
		(start 266.78 127.618578)
		(end 265.351422 126.19)
		(width 0.1)
		(layer "In7.Cu")
		(net 1213)
	)
	(segment
		(start 259.051422 166.21)
		(end 268.33 156.931422)
		(width 0.1)
		(layer "In7.Cu")
		(net 1213)
	)
	(segment
		(start 268.33 152.228578)
		(end 266.78 150.678578)
		(width 0.1)
		(layer "In7.Cu")
		(net 1213)
	)
	(segment
		(start 265.351422 126.19)
		(end 264.041422 126.19)
		(width 0.1)
		(layer "In7.Cu")
		(net 1213)
	)
	(segment
		(start 232.531422 167.81)
		(end 247.631422 167.81)
		(width 0.1)
		(layer "In7.Cu")
		(net 1213)
	)
	(segment
		(start 253.291422 166.21)
		(end 259.051422 166.21)
		(width 0.1)
		(layer "In7.Cu")
		(net 1213)
	)
	(segment
		(start 262.871422 125.02)
		(end 260.341422 125.02)
		(width 0.1)
		(layer "In7.Cu")
		(net 1213)
	)
	(segment
		(start 247.631422 167.81)
		(end 248.551422 166.89)
		(width 0.1)
		(layer "In7.Cu")
		(net 1213)
	)
	(segment
		(start 258.34 123.018578)
		(end 260.341422 125.02)
		(width 0.1)
		(layer "In7.Cu")
		(net 1213)
	)
	(segment
		(start 266.78 150.678578)
		(end 266.78 127.618578)
		(width 0.1)
		(layer "In7.Cu")
		(net 1213)
	)
	(segment
		(start 258.34 120.90911)
		(end 258.34 123.018578)
		(width 0.1)
		(layer "In7.Cu")
		(net 1213)
	)
	(segment
		(start 258.515 120.73411)
		(end 258.34 120.90911)
		(width 0.1)
		(layer "In7.Cu")
		(net 1213)
	)
	(segment
		(start 231.741422 168.6)
		(end 232.531422 167.81)
		(width 0.1)
		(layer "In7.Cu")
		(net 1213)
	)
	(segment
		(start 268.33 156.931422)
		(end 268.33 152.228578)
		(width 0.1)
		(layer "In7.Cu")
		(net 1213)
	)
	(segment
		(start 229.813033 167.994455)
		(end 230.418578 168.6)
		(width 0.1)
		(layer "In7.Cu")
		(net 1213)
	)
	(segment
		(start 258.14 120.55911)
		(end 257.965 120.73411)
		(width 0.1)
		(layer "F.Cu")
		(net 1214)
	)
	(segment
		(start 258.12 120.167)
		(end 258.14 120.187)
		(width 0.1)
		(layer "F.Cu")
		(net 1214)
	)
	(segment
		(start 258.14 120.187)
		(end 258.14 120.55911)
		(width 0.1)
		(layer "F.Cu")
		(net 1214)
	)
	(via
		(at 229.954455 167.605545)
		(size 0.45)
		(drill 0.2)
		(layers "F.Cu" "B.Cu")
		(net 1214)
	)
	(via
		(at 257.965 120.73411)
		(size 0.45)
		(drill 0.2)
		(layers "F.Cu" "B.Cu")
		(net 1214)
	)
	(segment
		(start 190.728578 169.8)
		(end 189.63 170.898578)
		(width 0.1)
		(layer "B.Cu")
		(net 1214)
	)
	(segment
		(start 179.65 178.288578)
		(end 179.65 176.1475)
		(width 0.1)
		(layer "B.Cu")
		(net 1214)
	)
	(segment
		(start 229.954455 167.605545)
		(end 229.706967 167.605545)
		(width 0.1)
		(layer "B.Cu")
		(net 1214)
	)
	(segment
		(start 186.698578 178.98)
		(end 180.341422 178.98)
		(width 0.1)
		(layer "B.Cu")
		(net 1214)
	)
	(segment
		(start 179.65 176.1475)
		(end 180.05 175.7475)
		(width 0.1)
		(layer "B.Cu")
		(net 1214)
	)
	(segment
		(start 189.63 170.898578)
		(end 189.63 176.048578)
		(width 0.1)
		(layer "B.Cu")
		(net 1214)
	)
	(segment
		(start 189.63 176.048578)
		(end 186.698578 178.98)
		(width 0.1)
		(layer "B.Cu")
		(net 1214)
	)
	(segment
		(start 229.706967 167.605545)
		(end 229.451422 167.35)
		(width 0.1)
		(layer "B.Cu")
		(net 1214)
	)
	(segment
		(start 197.058578 169.8)
		(end 190.728578 169.8)
		(width 0.1)
		(layer "B.Cu")
		(net 1214)
	)
	(segment
		(start 180.341422 178.98)
		(end 179.65 178.288578)
		(width 0.1)
		(layer "B.Cu")
		(net 1214)
	)
	(segment
		(start 199.508578 167.35)
		(end 197.058578 169.8)
		(width 0.1)
		(layer "B.Cu")
		(net 1214)
	)
	(segment
		(start 229.451422 167.35)
		(end 199.508578 167.35)
		(width 0.1)
		(layer "B.Cu")
		(net 1214)
	)
	(segment
		(start 247.548578 167.61)
		(end 248.468578 166.69)
		(width 0.1)
		(layer "In7.Cu")
		(net 1214)
	)
	(segment
		(start 248.468578 166.69)
		(end 252.528578 166.69)
		(width 0.1)
		(layer "In7.Cu")
		(net 1214)
	)
	(segment
		(start 252.528578 166.69)
		(end 253.208578 166.01)
		(width 0.1)
		(layer "In7.Cu")
		(net 1214)
	)
	(segment
		(start 258.968578 166.01)
		(end 268.13 156.848578)
		(width 0.1)
		(layer "In7.Cu")
		(net 1214)
	)
	(segment
		(start 231.658578 168.4)
		(end 232.448578 167.61)
		(width 0.1)
		(layer "In7.Cu")
		(net 1214)
	)
	(segment
		(start 263.958578 126.39)
		(end 262.788578 125.22)
		(width 0.1)
		(layer "In7.Cu")
		(net 1214)
	)
	(segment
		(start 266.58 127.701422)
		(end 265.268578 126.39)
		(width 0.1)
		(layer "In7.Cu")
		(net 1214)
	)
	(segment
		(start 229.954455 167.853033)
		(end 230.501422 168.4)
		(width 0.1)
		(layer "In7.Cu")
		(net 1214)
	)
	(segment
		(start 265.268578 126.39)
		(end 263.958578 126.39)
		(width 0.1)
		(layer "In7.Cu")
		(net 1214)
	)
	(segment
		(start 268.13 156.848578)
		(end 268.13 152.311422)
		(width 0.1)
		(layer "In7.Cu")
		(net 1214)
	)
	(segment
		(start 253.208578 166.01)
		(end 258.968578 166.01)
		(width 0.1)
		(layer "In7.Cu")
		(net 1214)
	)
	(segment
		(start 232.448578 167.61)
		(end 247.548578 167.61)
		(width 0.1)
		(layer "In7.Cu")
		(net 1214)
	)
	(segment
		(start 266.58 150.761422)
		(end 266.58 127.701422)
		(width 0.1)
		(layer "In7.Cu")
		(net 1214)
	)
	(segment
		(start 258.14 120.90911)
		(end 258.14 123.101422)
		(width 0.1)
		(layer "In7.Cu")
		(net 1214)
	)
	(segment
		(start 268.13 152.311422)
		(end 266.58 150.761422)
		(width 0.1)
		(layer "In7.Cu")
		(net 1214)
	)
	(segment
		(start 257.965 120.73411)
		(end 258.14 120.90911)
		(width 0.1)
		(layer "In7.Cu")
		(net 1214)
	)
	(segment
		(start 258.14 123.101422)
		(end 260.258578 125.22)
		(width 0.1)
		(layer "In7.Cu")
		(net 1214)
	)
	(segment
		(start 262.788578 125.22)
		(end 260.258578 125.22)
		(width 0.1)
		(layer "In7.Cu")
		(net 1214)
	)
	(segment
		(start 229.954455 167.605545)
		(end 229.954455 167.853033)
		(width 0.1)
		(layer "In7.Cu")
		(net 1214)
	)
	(segment
		(start 230.501422 168.4)
		(end 231.658578 168.4)
		(width 0.1)
		(layer "In7.Cu")
		(net 1214)
	)
	(segment
		(start 188.973 146.59)
		(end 188.953 146.57)
		(width 0.1)
		(layer "F.Cu")
		(net 1215)
	)
	(segment
		(start 185.11 148.991422)
		(end 185.11 159.105)
		(width 0.1)
		(layer "F.Cu")
		(net 1215)
	)
	(segment
		(start 188.953 146.57)
		(end 187.531422 146.57)
		(width 0.1)
		(layer "F.Cu")
		(net 1215)
	)
	(segment
		(start 187.531422 146.57)
		(end 185.11 148.991422)
		(width 0.1)
		(layer "F.Cu")
		(net 1215)
	)
	(segment
		(start 185.11 159.105)
		(end 185.285 159.28)
		(width 0.1)
		(layer "F.Cu")
		(net 1215)
	)
	(via
		(at 170.685 177.7)
		(size 0.45)
		(drill 0.2)
		(layers "F.Cu" "B.Cu")
		(net 1215)
	)
	(via
		(at 185.285 159.28)
		(size 0.45)
		(drill 0.2)
		(layers "F.Cu" "B.Cu")
		(net 1215)
	)
	(segment
		(start 170.86 177.525)
		(end 170.685 177.7)
		(width 0.1)
		(layer "B.Cu")
		(net 1215)
	)
	(segment
		(start 171.261078 176.1375)
		(end 170.86 176.538578)
		(width 0.1)
		(layer "B.Cu")
		(net 1215)
	)
	(segment
		(start 171.84 176.1375)
		(end 171.261078 176.1375)
		(width 0.1)
		(layer "B.Cu")
		(net 1215)
	)
	(segment
		(start 170.86 176.538578)
		(end 170.86 177.525)
		(width 0.1)
		(layer "B.Cu")
		(net 1215)
	)
	(segment
		(start 172.265 175.7125)
		(end 171.84 176.1375)
		(width 0.1)
		(layer "B.Cu")
		(net 1215)
	)
	(segment
		(start 185.11 158.698578)
		(end 184.681422 158.27)
		(width 0.1)
		(layer "In3.Cu")
		(net 1215)
	)
	(segment
		(start 175.138578 158.27)
		(end 170.86 162.548578)
		(width 0.1)
		(layer "In3.Cu")
		(net 1215)
	)
	(segment
		(start 185.11 159.105)
		(end 185.11 158.698578)
		(width 0.1)
		(layer "In3.Cu")
		(net 1215)
	)
	(segment
		(start 170.86 177.525)
		(end 170.685 177.7)
		(width 0.1)
		(layer "In3.Cu")
		(net 1215)
	)
	(segment
		(start 184.681422 158.27)
		(end 175.138578 158.27)
		(width 0.1)
		(layer "In3.Cu")
		(net 1215)
	)
	(segment
		(start 185.285 159.28)
		(end 185.11 159.105)
		(width 0.1)
		(layer "In3.Cu")
		(net 1215)
	)
	(segment
		(start 170.86 162.548578)
		(end 170.86 177.525)
		(width 0.1)
		(layer "In3.Cu")
		(net 1215)
	)
	(segment
		(start 188.952999 146.37)
		(end 187.448578 146.37)
		(width 0.1)
		(layer "F.Cu")
		(net 1216)
	)
	(segment
		(start 184.91 148.908578)
		(end 184.91 159.105)
		(width 0.1)
		(layer "F.Cu")
		(net 1216)
	)
	(segment
		(start 187.448578 146.37)
		(end 184.91 148.908578)
		(width 0.1)
		(layer "F.Cu")
		(net 1216)
	)
	(segment
		(start 184.91 159.105)
		(end 184.735 159.28)
		(width 0.1)
		(layer "F.Cu")
		(net 1216)
	)
	(segment
		(start 188.973 146.349999)
		(end 188.952999 146.37)
		(width 0.1)
		(layer "F.Cu")
		(net 1216)
	)
	(via
		(at 184.735 159.28)
		(size 0.45)
		(drill 0.2)
		(layers "F.Cu" "B.Cu")
		(net 1216)
	)
	(via
		(at 171.235 177.7)
		(size 0.45)
		(drill 0.2)
		(layers "F.Cu" "B.Cu")
		(net 1216)
	)
	(segment
		(start 171.343922 176.3375)
		(end 171.06 176.621422)
		(width 0.1)
		(layer "B.Cu")
		(net 1216)
	)
	(segment
		(start 171.06 176.621422)
		(end 171.06 177.525)
		(width 0.1)
		(layer "B.Cu")
		(net 1216)
	)
	(segment
		(start 171.84 176.3375)
		(end 171.343922 176.3375)
		(width 0.1)
		(layer "B.Cu")
		(net 1216)
	)
	(segment
		(start 172.265 176.7625)
		(end 171.84 176.3375)
		(width 0.1)
		(layer "B.Cu")
		(net 1216)
	)
	(segment
		(start 171.06 177.525)
		(end 171.235 177.7)
		(width 0.1)
		(layer "B.Cu")
		(net 1216)
	)
	(segment
		(start 171.06 162.631422)
		(end 171.06 177.525)
		(width 0.1)
		(layer "In3.Cu")
		(net 1216)
	)
	(segment
		(start 184.91 159.105)
		(end 184.91 158.781422)
		(width 0.1)
		(layer "In3.Cu")
		(net 1216)
	)
	(segment
		(start 175.221422 158.47)
		(end 171.06 162.631422)
		(width 0.1)
		(layer "In3.Cu")
		(net 1216)
	)
	(segment
		(start 184.735 159.28)
		(end 184.91 159.105)
		(width 0.1)
		(layer "In3.Cu")
		(net 1216)
	)
	(segment
		(start 184.91 158.781422)
		(end 184.598578 158.47)
		(width 0.1)
		(layer "In3.Cu")
		(net 1216)
	)
	(segment
		(start 184.598578 158.47)
		(end 175.221422 158.47)
		(width 0.1)
		(layer "In3.Cu")
		(net 1216)
	)
	(segment
		(start 171.06 177.525)
		(end 171.235 177.7)
		(width 0.1)
		(layer "In3.Cu")
		(net 1216)
	)
	(segment
		(start 198.448578 165.51)
		(end 185.721422 165.51)
		(width 0.1)
		(layer "B.Cu")
		(net 1217)
	)
	(segment
		(start 207.880001 149.678577)
		(end 207.6 149.958578)
		(width 0.1)
		(layer "B.Cu")
		(net 1217)
	)
	(segment
		(start 207.860001 147.384)
		(end 207.880001 147.404)
		(width 0.1)
		(layer "B.Cu")
		(net 1217)
	)
	(segment
		(start 185.13 164.918578)
		(end 185.13 162.058578)
		(width 0.1)
		(layer "B.Cu")
		(net 1217)
	)
	(segment
		(start 207.6 149.958578)
		(end 207.6 156.358578)
		(width 0.1)
		(layer "B.Cu")
		(net 1217)
	)
	(segment
		(start 169.78 162.108578)
		(end 169.78 167.191422)
		(width 0.1)
		(layer "B.Cu")
		(net 1217)
	)
	(segment
		(start 170.65 168.4275)
		(end 170.25 168.8275)
		(width 0.1)
		(layer "B.Cu")
		(net 1217)
	)
	(segment
		(start 169.78 167.191422)
		(end 170.65 168.061422)
		(width 0.1)
		(layer "B.Cu")
		(net 1217)
	)
	(segment
		(start 207.6 156.358578)
		(end 198.448578 165.51)
		(width 0.1)
		(layer "B.Cu")
		(net 1217)
	)
	(segment
		(start 184.601422 161.53)
		(end 170.358578 161.53)
		(width 0.1)
		(layer "B.Cu")
		(net 1217)
	)
	(segment
		(start 170.65 168.061422)
		(end 170.65 168.4275)
		(width 0.1)
		(layer "B.Cu")
		(net 1217)
	)
	(segment
		(start 207.880001 147.404)
		(end 207.880001 149.678577)
		(width 0.1)
		(layer "B.Cu")
		(net 1217)
	)
	(segment
		(start 170.358578 161.53)
		(end 169.78 162.108578)
		(width 0.1)
		(layer "B.Cu")
		(net 1217)
	)
	(segment
		(start 185.721422 165.51)
		(end 185.13 164.918578)
		(width 0.1)
		(layer "B.Cu")
		(net 1217)
	)
	(segment
		(start 185.13 162.058578)
		(end 184.601422 161.53)
		(width 0.1)
		(layer "B.Cu")
		(net 1217)
	)
	(segment
		(start 181.675 167.8025)
		(end 181.675 166.786422)
		(width 0.1)
		(layer "B.Cu")
		(net 1218)
	)
	(segment
		(start 194.528578 167.94)
		(end 197.681422 167.94)
		(width 0.1)
		(layer "B.Cu")
		(net 1218)
	)
	(segment
		(start 208.84 156.781422)
		(end 208.84 147.404001)
		(width 0.1)
		(layer "B.Cu")
		(net 1218)
	)
	(segment
		(start 208.84 147.404001)
		(end 208.860001 147.384)
		(width 0.1)
		(layer "B.Cu")
		(net 1218)
	)
	(segment
		(start 184.788578 166.17)
		(end 185.868578 167.25)
		(width 0.1)
		(layer "B.Cu")
		(net 1218)
	)
	(segment
		(start 181.675 166.786422)
		(end 182.291422 166.17)
		(width 0.1)
		(layer "B.Cu")
		(net 1218)
	)
	(segment
		(start 197.681422 167.94)
		(end 208.84 156.781422)
		(width 0.1)
		(layer "B.Cu")
		(net 1218)
	)
	(segment
		(start 182.291422 166.17)
		(end 184.788578 166.17)
		(width 0.1)
		(layer "B.Cu")
		(net 1218)
	)
	(segment
		(start 193.838578 167.25)
		(end 194.528578 167.94)
		(width 0.1)
		(layer "B.Cu")
		(net 1218)
	)
	(segment
		(start 182.1 168.2275)
		(end 181.675 167.8025)
		(width 0.1)
		(layer "B.Cu")
		(net 1218)
	)
	(segment
		(start 185.868578 167.25)
		(end 193.838578 167.25)
		(width 0.1)
		(layer "B.Cu")
		(net 1218)
	)
	(segment
		(start 198.531422 165.71)
		(end 185.638578 165.71)
		(width 0.1)
		(layer "B.Cu")
		(net 1219)
	)
	(segment
		(start 170.85 168.4275)
		(end 171.25 168.8275)
		(width 0.1)
		(layer "B.Cu")
		(net 1219)
	)
	(segment
		(start 169.98 162.191422)
		(end 169.98 167.108578)
		(width 0.1)
		(layer "B.Cu")
		(net 1219)
	)
	(segment
		(start 208.080001 147.404)
		(end 208.080001 149.761421)
		(width 0.1)
		(layer "B.Cu")
		(net 1219)
	)
	(segment
		(start 208.100001 147.384)
		(end 208.080001 147.404)
		(width 0.1)
		(layer "B.Cu")
		(net 1219)
	)
	(segment
		(start 169.98 167.108578)
		(end 170.85 167.978578)
		(width 0.1)
		(layer "B.Cu")
		(net 1219)
	)
	(segment
		(start 170.441422 161.73)
		(end 169.98 162.191422)
		(width 0.1)
		(layer "B.Cu")
		(net 1219)
	)
	(segment
		(start 208.080001 149.761421)
		(end 207.8 150.041422)
		(width 0.1)
		(layer "B.Cu")
		(net 1219)
	)
	(segment
		(start 207.8 150.041422)
		(end 207.8 156.441422)
		(width 0.1)
		(layer "B.Cu")
		(net 1219)
	)
	(segment
		(start 207.8 156.441422)
		(end 198.531422 165.71)
		(width 0.1)
		(layer "B.Cu")
		(net 1219)
	)
	(segment
		(start 184.93 165.001422)
		(end 184.93 162.141422)
		(width 0.1)
		(layer "B.Cu")
		(net 1219)
	)
	(segment
		(start 185.638578 165.71)
		(end 184.93 165.001422)
		(width 0.1)
		(layer "B.Cu")
		(net 1219)
	)
	(segment
		(start 184.93 162.141422)
		(end 184.518578 161.73)
		(width 0.1)
		(layer "B.Cu")
		(net 1219)
	)
	(segment
		(start 170.85 167.978578)
		(end 170.85 168.4275)
		(width 0.1)
		(layer "B.Cu")
		(net 1219)
	)
	(segment
		(start 184.518578 161.73)
		(end 170.441422 161.73)
		(width 0.1)
		(layer "B.Cu")
		(net 1219)
	)
	(segment
		(start 193.921422 167.05)
		(end 194.611422 167.74)
		(width 0.1)
		(layer "B.Cu")
		(net 1220)
	)
	(segment
		(start 181.475 167.8025)
		(end 181.475 166.703578)
		(width 0.1)
		(layer "B.Cu")
		(net 1220)
	)
	(segment
		(start 182.208578 165.97)
		(end 184.871422 165.97)
		(width 0.1)
		(layer "B.Cu")
		(net 1220)
	)
	(segment
		(start 194.611422 167.74)
		(end 197.598578 167.74)
		(width 0.1)
		(layer "B.Cu")
		(net 1220)
	)
	(segment
		(start 197.598578 167.74)
		(end 208.64 156.698578)
		(width 0.1)
		(layer "B.Cu")
		(net 1220)
	)
	(segment
		(start 181.05 168.2275)
		(end 181.475 167.8025)
		(width 0.1)
		(layer "B.Cu")
		(net 1220)
	)
	(segment
		(start 185.951422 167.05)
		(end 193.921422 167.05)
		(width 0.1)
		(layer "B.Cu")
		(net 1220)
	)
	(segment
		(start 208.64 147.404001)
		(end 208.62 147.384001)
		(width 0.1)
		(layer "B.Cu")
		(net 1220)
	)
	(segment
		(start 181.475 166.703578)
		(end 182.208578 165.97)
		(width 0.1)
		(layer "B.Cu")
		(net 1220)
	)
	(segment
		(start 184.871422 165.97)
		(end 185.951422 167.05)
		(width 0.1)
		(layer "B.Cu")
		(net 1220)
	)
	(segment
		(start 208.64 156.698578)
		(end 208.64 147.404001)
		(width 0.1)
		(layer "B.Cu")
		(net 1220)
	)
	(via
		(at 188.405545 113.625545)
		(size 0.45)
		(drill 0.2)
		(layers "F.Cu" "B.Cu")
		(net 1221)
	)
	(via
		(at 152.835545 164.634455)
		(size 0.45)
		(drill 0.2)
		(layers "F.Cu" "B.Cu")
		(net 1221)
	)
	(via
		(at 183.685 128.49)
		(size 0.45)
		(drill 0.2)
		(layers "F.Cu" "B.Cu")
		(net 1221)
	)
	(segment
		(start 189.943 112.66)
		(end 189.618578 112.66)
		(width 0.1)
		(layer "B.Cu")
		(net 1221)
	)
	(segment
		(start 153.6625 165.213922)
		(end 153.083033 164.634455)
		(width 0.1)
		(layer "B.Cu")
		(net 1221)
	)
	(segment
		(start 189.963 112.64)
		(end 189.943 112.66)
		(width 0.1)
		(layer "B.Cu")
		(net 1221)
	)
	(segment
		(start 189.618578 112.66)
		(end 188.653033 113.625545)
		(width 0.1)
		(layer "B.Cu")
		(net 1221)
	)
	(segment
		(start 153.2125 168.715)
		(end 153.6625 168.265)
		(width 0.1)
		(layer "B.Cu")
		(net 1221)
	)
	(segment
		(start 153.6625 168.265)
		(end 153.6625 165.213922)
		(width 0.1)
		(layer "B.Cu")
		(net 1221)
	)
	(segment
		(start 153.083033 164.634455)
		(end 152.835545 164.634455)
		(width 0.1)
		(layer "B.Cu")
		(net 1221)
	)
	(segment
		(start 188.653033 113.625545)
		(end 188.405545 113.625545)
		(width 0.1)
		(layer "B.Cu")
		(net 1221)
	)
	(segment
		(start 188.405545 113.625545)
		(end 188.405545 113.873033)
		(width 0.1)
		(layer "In3.Cu")
		(net 1221)
	)
	(segment
		(start 188.405545 113.873033)
		(end 187.938578 114.34)
		(width 0.1)
		(layer "In3.Cu")
		(net 1221)
	)
	(segment
		(start 183.39 115.878578)
		(end 183.39 127.741422)
		(width 0.1)
		(layer "In3.Cu")
		(net 1221)
	)
	(segment
		(start 183.39 127.741422)
		(end 183.86 128.211422)
		(width 0.1)
		(layer "In3.Cu")
		(net 1221)
	)
	(segment
		(start 187.938578 114.34)
		(end 184.928578 114.34)
		(width 0.1)
		(layer "In3.Cu")
		(net 1221)
	)
	(segment
		(start 183.86 128.315)
		(end 183.685 128.49)
		(width 0.1)
		(layer "In3.Cu")
		(net 1221)
	)
	(segment
		(start 184.928578 114.34)
		(end 183.39 115.878578)
		(width 0.1)
		(layer "In3.Cu")
		(net 1221)
	)
	(segment
		(start 183.86 128.211422)
		(end 183.86 128.315)
		(width 0.1)
		(layer "In3.Cu")
		(net 1221)
	)
	(segment
		(start 183.86 129.098578)
		(end 183.718578 129.24)
		(width 0.1)
		(layer "In7.Cu")
		(net 1221)
	)
	(segment
		(start 152.28 163.831422)
		(end 152.835545 164.386967)
		(width 0.1)
		(layer "In7.Cu")
		(net 1221)
	)
	(segment
		(start 183.86 128.665)
		(end 183.86 129.098578)
		(width 0.1)
		(layer "In7.Cu")
		(net 1221)
	)
	(segment
		(start 183.718578 129.24)
		(end 154.058578 129.24)
		(width 0.1)
		(layer "In7.Cu")
		(net 1221)
	)
	(segment
		(start 183.685 128.49)
		(end 183.86 128.665)
		(width 0.1)
		(layer "In7.Cu")
		(net 1221)
	)
	(segment
		(start 152.28 151.748578)
		(end 152.28 163.831422)
		(width 0.1)
		(layer "In7.Cu")
		(net 1221)
	)
	(segment
		(start 153.02 146.231422)
		(end 153.02 151.008578)
		(width 0.1)
		(layer "In7.Cu")
		(net 1221)
	)
	(segment
		(start 151.68 131.618578)
		(end 151.68 144.891422)
		(width 0.1)
		(layer "In7.Cu")
		(net 1221)
	)
	(segment
		(start 152.835545 164.386967)
		(end 152.835545 164.634455)
		(width 0.1)
		(layer "In7.Cu")
		(net 1221)
	)
	(segment
		(start 153.02 151.008578)
		(end 152.28 151.748578)
		(width 0.1)
		(layer "In7.Cu")
		(net 1221)
	)
	(segment
		(start 154.058578 129.24)
		(end 151.68 131.618578)
		(width 0.1)
		(layer "In7.Cu")
		(net 1221)
	)
	(segment
		(start 151.68 144.891422)
		(end 153.02 146.231422)
		(width 0.1)
		(layer "In7.Cu")
		(net 1221)
	)
	(via
		(at 184.235 128.49)
		(size 0.45)
		(drill 0.2)
		(layers "F.Cu" "B.Cu")
		(net 1222)
	)
	(via
		(at 188.794455 114.014455)
		(size 0.45)
		(drill 0.2)
		(layers "F.Cu" "B.Cu")
		(net 1222)
	)
	(via
		(at 153.224455 164.245545)
		(size 0.45)
		(drill 0.2)
		(layers "F.Cu" "B.Cu")
		(net 1222)
	)
	(segment
		(start 188.794455 113.766967)
		(end 188.794455 114.014455)
		(width 0.1)
		(layer "B.Cu")
		(net 1222)
	)
	(segment
		(start 189.701422 112.86)
		(end 188.794455 113.766967)
		(width 0.1)
		(layer "B.Cu")
		(net 1222)
	)
	(segment
		(start 153.8625 165.131078)
		(end 153.224455 164.493033)
		(width 0.1)
		(layer "B.Cu")
		(net 1222)
	)
	(segment
		(start 189.963001 112.88)
		(end 189.943001 112.86)
		(width 0.1)
		(layer "B.Cu")
		(net 1222)
	)
	(segment
		(start 153.224455 164.493033)
		(end 153.224455 164.245545)
		(width 0.1)
		(layer "B.Cu")
		(net 1222)
	)
	(segment
		(start 154.3125 168.715)
		(end 153.8625 168.265)
		(width 0.1)
		(layer "B.Cu")
		(net 1222)
	)
	(segment
		(start 189.943001 112.86)
		(end 189.701422 112.86)
		(width 0.1)
		(layer "B.Cu")
		(net 1222)
	)
	(segment
		(start 153.8625 168.265)
		(end 153.8625 165.131078)
		(width 0.1)
		(layer "B.Cu")
		(net 1222)
	)
	(segment
		(start 183.59 115.961422)
		(end 183.59 127.658578)
		(width 0.1)
		(layer "In3.Cu")
		(net 1222)
	)
	(segment
		(start 184.06 128.128578)
		(end 184.06 128.315)
		(width 0.1)
		(layer "In3.Cu")
		(net 1222)
	)
	(segment
		(start 185.011422 114.54)
		(end 183.59 115.961422)
		(width 0.1)
		(layer "In3.Cu")
		(net 1222)
	)
	(segment
		(start 183.59 127.658578)
		(end 184.06 128.128578)
		(width 0.1)
		(layer "In3.Cu")
		(net 1222)
	)
	(segment
		(start 188.546967 114.014455)
		(end 188.021422 114.54)
		(width 0.1)
		(layer "In3.Cu")
		(net 1222)
	)
	(segment
		(start 188.021422 114.54)
		(end 185.011422 114.54)
		(width 0.1)
		(layer "In3.Cu")
		(net 1222)
	)
	(segment
		(start 188.794455 114.014455)
		(end 188.546967 114.014455)
		(width 0.1)
		(layer "In3.Cu")
		(net 1222)
	)
	(segment
		(start 184.06 128.315)
		(end 184.235 128.49)
		(width 0.1)
		(layer "In3.Cu")
		(net 1222)
	)
	(segment
		(start 152.976967 164.245545)
		(end 153.224455 164.245545)
		(width 0.1)
		(layer "In7.Cu")
		(net 1222)
	)
	(segment
		(start 184.235 128.49)
		(end 184.06 128.665)
		(width 0.1)
		(layer "In7.Cu")
		(net 1222)
	)
	(segment
		(start 154.141422 129.44)
		(end 151.88 131.701422)
		(width 0.1)
		(layer "In7.Cu")
		(net 1222)
	)
	(segment
		(start 183.801422 129.44)
		(end 154.141422 129.44)
		(width 0.1)
		(layer "In7.Cu")
		(net 1222)
	)
	(segment
		(start 151.88 144.808578)
		(end 153.22 146.148578)
		(width 0.1)
		(layer "In7.Cu")
		(net 1222)
	)
	(segment
		(start 153.22 151.091422)
		(end 152.48 151.831422)
		(width 0.1)
		(layer "In7.Cu")
		(net 1222)
	)
	(segment
		(start 153.22 146.148578)
		(end 153.22 151.091422)
		(width 0.1)
		(layer "In7.Cu")
		(net 1222)
	)
	(segment
		(start 152.48 163.748578)
		(end 152.976967 164.245545)
		(width 0.1)
		(layer "In7.Cu")
		(net 1222)
	)
	(segment
		(start 152.48 151.831422)
		(end 152.48 163.748578)
		(width 0.1)
		(layer "In7.Cu")
		(net 1222)
	)
	(segment
		(start 184.06 128.665)
		(end 184.06 129.181422)
		(width 0.1)
		(layer "In7.Cu")
		(net 1222)
	)
	(segment
		(start 184.06 129.181422)
		(end 183.801422 129.44)
		(width 0.1)
		(layer "In7.Cu")
		(net 1222)
	)
	(segment
		(start 151.88 131.701422)
		(end 151.88 144.808578)
		(width 0.1)
		(layer "In7.Cu")
		(net 1222)
	)
	(segment
		(start 164.4875 167.69)
		(end 164.0625 168.115)
		(width 0.1)
		(layer "B.Cu")
		(net 1223)
	)
	(segment
		(start 193.088578 145.5)
		(end 192.76 145.828578)
		(width 0.1)
		(layer "B.Cu")
		(net 1223)
	)
	(segment
		(start 192.76 145.828578)
		(end 192.76 154.888578)
		(width 0.1)
		(layer "B.Cu")
		(net 1223)
	)
	(segment
		(start 167.268578 157.46)
		(end 164.4875 160.241078)
		(width 0.1)
		(layer "B.Cu")
		(net 1223)
	)
	(segment
		(start 193.443 145.5)
		(end 193.088578 145.5)
		(width 0.1)
		(layer "B.Cu")
		(net 1223)
	)
	(segment
		(start 192.76 154.888578)
		(end 190.188578 157.46)
		(width 0.1)
		(layer "B.Cu")
		(net 1223)
	)
	(segment
		(start 190.188578 157.46)
		(end 167.268578 157.46)
		(width 0.1)
		(layer "B.Cu")
		(net 1223)
	)
	(segment
		(start 164.4875 160.241078)
		(end 164.4875 167.69)
		(width 0.1)
		(layer "B.Cu")
		(net 1223)
	)
	(segment
		(start 193.463 145.48)
		(end 193.443 145.5)
		(width 0.1)
		(layer "B.Cu")
		(net 1223)
	)
	(segment
		(start 193.171422 145.7)
		(end 192.96 145.911422)
		(width 0.1)
		(layer "B.Cu")
		(net 1224)
	)
	(segment
		(start 164.6875 167.69)
		(end 165.1125 168.115)
		(width 0.1)
		(layer "B.Cu")
		(net 1224)
	)
	(segment
		(start 192.96 154.971422)
		(end 190.271422 157.66)
		(width 0.1)
		(layer "B.Cu")
		(net 1224)
	)
	(segment
		(start 164.6875 160.323922)
		(end 164.6875 167.69)
		(width 0.1)
		(layer "B.Cu")
		(net 1224)
	)
	(segment
		(start 193.463 145.72)
		(end 193.443 145.7)
		(width 0.1)
		(layer "B.Cu")
		(net 1224)
	)
	(segment
		(start 192.96 145.911422)
		(end 192.96 154.971422)
		(width 0.1)
		(layer "B.Cu")
		(net 1224)
	)
	(segment
		(start 167.351422 157.66)
		(end 164.6875 160.323922)
		(width 0.1)
		(layer "B.Cu")
		(net 1224)
	)
	(segment
		(start 193.443 145.7)
		(end 193.171422 145.7)
		(width 0.1)
		(layer "B.Cu")
		(net 1224)
	)
	(segment
		(start 190.271422 157.66)
		(end 167.351422 157.66)
		(width 0.1)
		(layer "B.Cu")
		(net 1224)
	)
	(via
		(at 162.3875 176.81)
		(size 0.45)
		(drill 0.2)
		(layers "F.Cu" "B.Cu")
		(net 1225)
	)
	(via
		(at 177.425 80.16)
		(size 0.45)
		(drill 0.2)
		(layers "F.Cu" "B.Cu")
		(net 1225)
	)
	(via
		(at 195.85 87.055)
		(size 0.45)
		(drill 0.2)
		(layers "F.Cu" "B.Cu")
		(net 1225)
	)
	(segment
		(start 162.1625 175.785)
		(end 162.5625 176.185)
		(width 0.1)
		(layer "B.Cu")
		(net 1225)
	)
	(segment
		(start 162.5625 176.635)
		(end 162.3875 176.81)
		(width 0.1)
		(layer "B.Cu")
		(net 1225)
	)
	(segment
		(start 196.025 87.23)
		(end 195.85 87.055)
		(width 0.1)
		(layer "B.Cu")
		(net 1225)
	)
	(segment
		(start 196.458578 87.23)
		(end 196.025 87.23)
		(width 0.1)
		(layer "B.Cu")
		(net 1225)
	)
	(segment
		(start 196.670197 86.989803)
		(end 196.670197 87.018381)
		(width 0.1)
		(layer "B.Cu")
		(net 1225)
	)
	(segment
		(start 162.5625 176.185)
		(end 162.5625 176.635)
		(width 0.1)
		(layer "B.Cu")
		(net 1225)
	)
	(segment
		(start 196.670197 87.018381)
		(end 196.458578 87.23)
		(width 0.1)
		(layer "B.Cu")
		(net 1225)
	)
	(segment
		(start 175.261422 77.22)
		(end 163.568578 77.22)
		(width 0.1)
		(layer "In3.Cu")
		(net 1225)
	)
	(segment
		(start 161.758578 79.03)
		(end 154.518578 79.03)
		(width 0.1)
		(layer "In3.Cu")
		(net 1225)
	)
	(segment
		(start 177.25 79.985)
		(end 177.25 79.208578)
		(width 0.1)
		(layer "In3.Cu")
		(net 1225)
	)
	(segment
		(start 162.5625 174.453922)
		(end 161.638578 173.53)
		(width 0.1)
		(layer "In3.Cu")
		(net 1225)
	)
	(segment
		(start 162.5625 176.635)
		(end 162.5625 174.453922)
		(width 0.1)
		(layer "In3.Cu")
		(net 1225)
	)
	(segment
		(start 162.3875 176.81)
		(end 162.5625 176.635)
		(width 0.1)
		(layer "In3.Cu")
		(net 1225)
	)
	(segment
		(start 151.66 81.888578)
		(end 151.66 154.981422)
		(width 0.1)
		(layer "In3.Cu")
		(net 1225)
	)
	(segment
		(start 153.81 172.091422)
		(end 155.248578 173.53)
		(width 0.1)
		(layer "In3.Cu")
		(net 1225)
	)
	(segment
		(start 153.81 157.131422)
		(end 153.81 172.091422)
		(width 0.1)
		(layer "In3.Cu")
		(net 1225)
	)
	(segment
		(start 151.66 154.981422)
		(end 153.81 157.131422)
		(width 0.1)
		(layer "In3.Cu")
		(net 1225)
	)
	(segment
		(start 155.248578 173.53)
		(end 161.638578 173.53)
		(width 0.1)
		(layer "In3.Cu")
		(net 1225)
	)
	(segment
		(start 163.568578 77.22)
		(end 161.758578 79.03)
		(width 0.1)
		(layer "In3.Cu")
		(net 1225)
	)
	(segment
		(start 177.25 79.208578)
		(end 175.261422 77.22)
		(width 0.1)
		(layer "In3.Cu")
		(net 1225)
	)
	(segment
		(start 154.518578 79.03)
		(end 151.66 81.888578)
		(width 0.1)
		(layer "In3.Cu")
		(net 1225)
	)
	(segment
		(start 177.425 80.16)
		(end 177.25 79.985)
		(width 0.1)
		(layer "In3.Cu")
		(net 1225)
	)
	(segment
		(start 182.231422 87.23)
		(end 177.25 82.248578)
		(width 0.1)
		(layer "In5.Cu")
		(net 1225)
	)
	(segment
		(start 177.25 80.335)
		(end 177.425 80.16)
		(width 0.1)
		(layer "In5.Cu")
		(net 1225)
	)
	(segment
		(start 195.675 87.23)
		(end 182.231422 87.23)
		(width 0.1)
		(layer "In5.Cu")
		(net 1225)
	)
	(segment
		(start 195.85 87.055)
		(end 195.675 87.23)
		(width 0.1)
		(layer "In5.Cu")
		(net 1225)
	)
	(segment
		(start 177.25 82.248578)
		(end 177.25 80.335)
		(width 0.1)
		(layer "In5.Cu")
		(net 1225)
	)
	(via
		(at 176.875 80.16)
		(size 0.45)
		(drill 0.2)
		(layers "F.Cu" "B.Cu")
		(net 1226)
	)
	(via
		(at 162.9375 176.81)
		(size 0.45)
		(drill 0.2)
		(layers "F.Cu" "B.Cu")
		(net 1226)
	)
	(via
		(at 195.85 87.605)
		(size 0.45)
		(drill 0.2)
		(layers "F.Cu" "B.Cu")
		(net 1226)
	)
	(segment
		(start 163.1625 175.785)
		(end 162.7625 176.185)
		(width 0.1)
		(layer "B.Cu")
		(net 1226)
	)
	(segment
		(start 162.7625 176.185)
		(end 162.7625 176.635)
		(width 0.1)
		(layer "B.Cu")
		(net 1226)
	)
	(segment
		(start 196.830197 87.159803)
		(end 196.811619 87.159803)
		(width 0.1)
		(layer "B.Cu")
		(net 1226)
	)
	(segment
		(start 196.025 87.43)
		(end 195.85 87.605)
		(width 0.1)
		(layer "B.Cu")
		(net 1226)
	)
	(segment
		(start 196.541422 87.43)
		(end 196.025 87.43)
		(width 0.1)
		(layer "B.Cu")
		(net 1226)
	)
	(segment
		(start 162.7625 176.635)
		(end 162.9375 176.81)
		(width 0.1)
		(layer "B.Cu")
		(net 1226)
	)
	(segment
		(start 196.811619 87.159803)
		(end 196.541422 87.43)
		(width 0.1)
		(layer "B.Cu")
		(net 1226)
	)
	(segment
		(start 162.7625 174.371078)
		(end 161.721422 173.33)
		(width 0.1)
		(layer "In3.Cu")
		(net 1226)
	)
	(segment
		(start 162.9375 176.81)
		(end 162.7625 176.635)
		(width 0.1)
		(layer "In3.Cu")
		(net 1226)
	)
	(segment
		(start 154.01 157.048578)
		(end 154.01 172.008578)
		(width 0.1)
		(layer "In3.Cu")
		(net 1226)
	)
	(segment
		(start 175.178578 77.42)
		(end 163.651422 77.42)
		(width 0.1)
		(layer "In3.Cu")
		(net 1226)
	)
	(segment
		(start 163.651422 77.42)
		(end 161.841422 79.23)
		(width 0.1)
		(layer "In3.Cu")
		(net 1226)
	)
	(segment
		(start 155.331422 173.33)
		(end 161.721422 173.33)
		(width 0.1)
		(layer "In3.Cu")
		(net 1226)
	)
	(segment
		(start 151.86 154.898578)
		(end 154.01 157.048578)
		(width 0.1)
		(layer "In3.Cu")
		(net 1226)
	)
	(segment
		(start 162.7625 176.635)
		(end 162.7625 174.371078)
		(width 0.1)
		(layer "In3.Cu")
		(net 1226)
	)
	(segment
		(start 161.841422 79.23)
		(end 154.601422 79.23)
		(width 0.1)
		(layer "In3.Cu")
		(net 1226)
	)
	(segment
		(start 154.601422 79.23)
		(end 151.86 81.971422)
		(width 0.1)
		(layer "In3.Cu")
		(net 1226)
	)
	(segment
		(start 177.05 79.291422)
		(end 175.178578 77.42)
		(width 0.1)
		(layer "In3.Cu")
		(net 1226)
	)
	(segment
		(start 176.875 80.16)
		(end 177.05 79.985)
		(width 0.1)
		(layer "In3.Cu")
		(net 1226)
	)
	(segment
		(start 154.01 172.008578)
		(end 155.331422 173.33)
		(width 0.1)
		(layer "In3.Cu")
		(net 1226)
	)
	(segment
		(start 177.05 79.985)
		(end 177.05 79.291422)
		(width 0.1)
		(layer "In3.Cu")
		(net 1226)
	)
	(segment
		(start 151.86 81.971422)
		(end 151.86 154.898578)
		(width 0.1)
		(layer "In3.Cu")
		(net 1226)
	)
	(segment
		(start 195.675 87.43)
		(end 182.148578 87.43)
		(width 0.1)
		(layer "In5.Cu")
		(net 1226)
	)
	(segment
		(start 195.85 87.605)
		(end 195.675 87.43)
		(width 0.1)
		(layer "In5.Cu")
		(net 1226)
	)
	(segment
		(start 177.05 80.335)
		(end 176.875 80.16)
		(width 0.1)
		(layer "In5.Cu")
		(net 1226)
	)
	(segment
		(start 177.05 82.331422)
		(end 177.05 80.335)
		(width 0.1)
		(layer "In5.Cu")
		(net 1226)
	)
	(segment
		(start 182.148578 87.43)
		(end 177.05 82.331422)
		(width 0.1)
		(layer "In5.Cu")
		(net 1226)
	)
	(via
		(at 224.35 162.34)
		(size 0.45)
		(drill 0.2)
		(layers "F.Cu" "B.Cu")
		(net 1227)
	)
	(segment
		(start 268.85 80.2)
		(end 267.115 80.2)
		(width 0.1)
		(layer "F.Cu")
		(net 1228)
	)
	(segment
		(start 266.485 80.2)
		(end 266.8 79.885)
		(width 0.1)
		(layer "F.Cu")
		(net 1228)
	)
	(segment
		(start 264.75 80.2)
		(end 266.485 80.2)
		(width 0.1)
		(layer "F.Cu")
		(net 1228)
	)
	(segment
		(start 267.115 80.2)
		(end 266.8 79.885)
		(width 0.1)
		(layer "F.Cu")
		(net 1228)
	)
	(segment
		(start 261.2 80.2)
		(end 264.75 80.2)
		(width 0.1)
		(layer "F.Cu")
		(net 1228)
	)
	(segment
		(start 195.5 135.5)
		(end 195 136)
		(width 0.256)
		(layer "F.Cu")
		(net 1228)
	)
	(via
		(at 261.2 80.2)
		(size 0.45)
		(drill 0.2)
		(layers "F.Cu" "B.Cu")
		(net 1228)
	)
	(via
		(at 266.8 79.885)
		(size 0.45)
		(drill 0.2)
		(layers "F.Cu" "B.Cu")
		(net 1228)
	)
	(via
		(at 195 136)
		(size 0.45)
		(drill 0.2)
		(layers "F.Cu" "B.Cu")
		(net 1228)
	)
	(via
		(at 264.75 80.1)
		(size 0.45)
		(drill 0.2)
		(layers "F.Cu" "B.Cu")
		(net 1228)
	)
	(segment
		(start 210.848526 73.4)
		(end 259.8 73.4)
		(width 0.1)
		(layer "In3.Cu")
		(net 1228)
	)
	(segment
		(start 207.788 76.460526)
		(end 210.848526 73.4)
		(width 0.1)
		(layer "In3.Cu")
		(net 1228)
	)
	(segment
		(start 195 136)
		(end 194.4 135.4)
		(width 0.1)
		(layer "In3.Cu")
		(net 1228)
	)
	(segment
		(start 208.425 95.590684)
		(end 208.425 83.607316)
		(width 0.1)
		(layer "In3.Cu")
		(net 1228)
	)
	(segment
		(start 198.73 109.35)
		(end 198.73 105.285684)
		(width 0.1)
		(layer "In3.Cu")
		(net 1228)
	)
	(segment
		(start 261.4 80)
		(end 261.2 80.2)
		(width 0.1)
		(layer "In3.Cu")
		(net 1228)
	)
	(segment
		(start 198.73 105.285684)
		(end 208.425 95.590684)
		(width 0.1)
		(layer "In3.Cu")
		(net 1228)
	)
	(segment
		(start 194.4 135.4)
		(end 194.4 133.742158)
		(width 0.1)
		(layer "In3.Cu")
		(net 1228)
	)
	(segment
		(start 197.4 133.175)
		(end 197.4 110.68)
		(width 0.1)
		(layer "In3.Cu")
		(net 1228)
	)
	(segment
		(start 197.4 110.68)
		(end 198.73 109.35)
		(width 0.1)
		(layer "In3.Cu")
		(net 1228)
	)
	(segment
		(start 259.8 73.4)
		(end 261.4 75)
		(width 0.1)
		(layer "In3.Cu")
		(net 1228)
	)
	(segment
		(start 197.175 133.4)
		(end 197.4 133.175)
		(width 0.1)
		(layer "In3.Cu")
		(net 1228)
	)
	(segment
		(start 194.742158 133.4)
		(end 197.175 133.4)
		(width 0.1)
		(layer "In3.Cu")
		(net 1228)
	)
	(segment
		(start 207.788 82.970316)
		(end 207.788 76.460526)
		(width 0.1)
		(layer "In3.Cu")
		(net 1228)
	)
	(segment
		(start 208.425 83.607316)
		(end 207.788 82.970316)
		(width 0.1)
		(layer "In3.Cu")
		(net 1228)
	)
	(segment
		(start 261.4 75)
		(end 261.4 80)
		(width 0.1)
		(layer "In3.Cu")
		(net 1228)
	)
	(segment
		(start 194.4 133.742158)
		(end 194.742158 133.4)
		(width 0.1)
		(layer "In3.Cu")
		(net 1228)
	)
	(segment
		(start 193.615 167.1)
		(end 193.615 166.1)
		(width 0.177)
		(layer "F.Cu")
		(net 1230)
	)
	(segment
		(start 193.615 166.1)
		(end 193.6 166.085)
		(width 0.177)
		(layer "F.Cu")
		(net 1230)
	)
	(segment
		(start 193.6 166.085)
		(end 192.6 166.085)
		(width 0.177)
		(layer "F.Cu")
		(net 1230)
	)
	(segment
		(start 194.6 166.085)
		(end 193.6 166.085)
		(width 0.177)
		(layer "F.Cu")
		(net 1230)
	)
	(segment
		(start 227.69 144.66)
		(end 228.765 143.585)
		(width 0.256)
		(layer "F.Cu")
		(net 1231)
	)
	(segment
		(start 229.2815 138.372778)
		(end 229.233722 138.325)
		(width 0.256)
		(layer "F.Cu")
		(net 1231)
	)
	(segment
		(start 228.415 140.925)
		(end 228.725 141.235)
		(width 0.256)
		(layer "F.Cu")
		(net 1231)
	)
	(segment
		(start 229.16 140.8)
		(end 228.725 141.235)
		(width 0.256)
		(layer "F.Cu")
		(net 1231)
	)
	(segment
		(start 229.2815 140.8)
		(end 229.16 140.8)
		(width 0.256)
		(layer "F.Cu")
		(net 1231)
	)
	(segment
		(start 229.35 140.8685)
		(end 229.2815 140.8)
		(width 0.256)
		(layer "F.Cu")
		(net 1231)
	)
	(segment
		(start 227 140.925)
		(end 228.415 140.925)
		(width 0.256)
		(layer "F.Cu")
		(net 1231)
	)
	(segment
		(start 229.233722 138.325)
		(end 227 138.325)
		(width 0.256)
		(layer "F.Cu")
		(net 1231)
	)
	(segment
		(start 228.765 143.585)
		(end 228.765 142.75)
		(width 0.256)
		(layer "F.Cu")
		(net 1231)
	)
	(segment
		(start 227.69 145.84)
		(end 227.69 144.66)
		(width 0.256)
		(layer "F.Cu")
		(net 1231)
	)
	(segment
		(start 229.35 142.165)
		(end 229.35 140.8685)
		(width 0.256)
		(layer "F.Cu")
		(net 1231)
	)
	(segment
		(start 228.765 142.75)
		(end 229.35 142.165)
		(width 0.256)
		(layer "F.Cu")
		(net 1231)
	)
	(via
		(at 229.2815 140.8)
		(size 0.45)
		(drill 0.2)
		(layers "F.Cu" "B.Cu")
		(net 1231)
	)
	(via
		(at 229.2815 138.372778)
		(size 0.45)
		(drill 0.2)
		(layers "F.Cu" "B.Cu")
		(net 1231)
	)
	(segment
		(start 229.2815 138.372778)
		(end 229.825 138.916278)
		(width 0.256)
		(layer "In2.Cu")
		(net 1231)
	)
	(segment
		(start 229.825 140.225)
		(end 229.2815 140.7685)
		(width 0.256)
		(layer "In2.Cu")
		(net 1231)
	)
	(segment
		(start 229.825 138.916278)
		(end 229.825 140.225)
		(width 0.256)
		(layer "In2.Cu")
		(net 1231)
	)
	(segment
		(start 229.2815 140.7685)
		(end 229.2815 140.8)
		(width 0.256)
		(layer "In2.Cu")
		(net 1231)
	)
	(segment
		(start 264.75 94)
		(end 266.485 94)
		(width 0.1)
		(layer "F.Cu")
		(net 1232)
	)
	(segment
		(start 261.54 94.1)
		(end 261.56 94.08)
		(width 0.1)
		(layer "F.Cu")
		(net 1232)
	)
	(segment
		(start 267.115 94)
		(end 266.8 93.685)
		(width 0.1)
		(layer "F.Cu")
		(net 1232)
	)
	(segment
		(start 195.5 134.5)
		(end 195 135)
		(width 0.256)
		(layer "F.Cu")
		(net 1232)
	)
	(segment
		(start 266.485 94)
		(end 266.8 93.685)
		(width 0.1)
		(layer "F.Cu")
		(net 1232)
	)
	(segment
		(start 264.67 94.08)
		(end 264.75 94)
		(width 0.1)
		(layer "F.Cu")
		(net 1232)
	)
	(segment
		(start 268.85 94)
		(end 267.115 94)
		(width 0.1)
		(layer "F.Cu")
		(net 1232)
	)
	(segment
		(start 261.56 94.08)
		(end 264.67 94.08)
		(width 0.1)
		(layer "F.Cu")
		(net 1232)
	)
	(via
		(at 261.54 94.1)
		(size 0.45)
		(drill 0.2)
		(layers "F.Cu" "B.Cu")
		(net 1232)
	)
	(via
		(at 266.8 93.685)
		(size 0.45)
		(drill 0.2)
		(layers "F.Cu" "B.Cu")
		(net 1232)
	)
	(via
		(at 195 135)
		(size 0.45)
		(drill 0.2)
		(layers "F.Cu" "B.Cu")
		(net 1232)
	)
	(via
		(at 264.75 93.9)
		(size 0.45)
		(drill 0.2)
		(layers "F.Cu" "B.Cu")
		(net 1232)
	)
	(segment
		(start 261.4 84.117158)
		(end 261.4 81)
		(width 0.1)
		(layer "In3.Cu")
		(net 1232)
	)
	(segment
		(start 261 84.517158)
		(end 261.4 84.117158)
		(width 0.1)
		(layer "In3.Cu")
		(net 1232)
	)
	(segment
		(start 261.2 89.2)
		(end 261.6 88.8)
		(width 0.1)
		(layer "In3.Cu")
		(net 1232)
	)
	(segment
		(start 209.45 75.081367)
		(end 209.45 87.288301)
		(width 0.1)
		(layer "In3.Cu")
		(net 1232)
	)
	(segment
		(start 209.45 87.288301)
		(end 208.65 88.088301)
		(width 0.1)
		(layer "In3.Cu")
		(net 1232)
	)
	(segment
		(start 199.04 105.258526)
		(end 199.04 109.55)
		(width 0.1)
		(layer "In3.Cu")
		(net 1232)
	)
	(segment
		(start 261.6 88.8)
		(end 261.6 85.7)
		(width 0.1)
		(layer "In3.Cu")
		(net 1232)
	)
	(segment
		(start 261.8 90.2)
		(end 261.2 89.6)
		(width 0.1)
		(layer "In3.Cu")
		(net 1232)
	)
	(segment
		(start 261 85.1)
		(end 261 84.517158)
		(width 0.1)
		(layer "In3.Cu")
		(net 1232)
	)
	(segment
		(start 208.65 95.648526)
		(end 199.04 105.258526)
		(width 0.1)
		(layer "In3.Cu")
		(net 1232)
	)
	(segment
		(start 194.6 134.6)
		(end 195 135)
		(width 0.1)
		(layer "In3.Cu")
		(net 1232)
	)
	(segment
		(start 208.65 88.088301)
		(end 208.65 95.648526)
		(width 0.1)
		(layer "In3.Cu")
		(net 1232)
	)
	(segment
		(start 197.257842 133.6)
		(end 194.825 133.6)
		(width 0.1)
		(layer "In3.Cu")
		(net 1232)
	)
	(segment
		(start 261.6 85.7)
		(end 261 85.1)
		(width 0.1)
		(layer "In3.Cu")
		(net 1232)
	)
	(segment
		(start 261.2 79.6)
		(end 261.2 75.1)
		(width 0.1)
		(layer "In3.Cu")
		(net 1232)
	)
	(segment
		(start 261.2 75.1)
		(end 259.7 73.6)
		(width 0.1)
		(layer "In3.Cu")
		(net 1232)
	)
	(segment
		(start 194.825 133.6)
		(end 194.6 133.825)
		(width 0.1)
		(layer "In3.Cu")
		(net 1232)
	)
	(segment
		(start 194.6 133.825)
		(end 194.6 134.6)
		(width 0.1)
		(layer "In3.Cu")
		(net 1232)
	)
	(segment
		(start 259.7 73.6)
		(end 210.931368 73.6)
		(width 0.1)
		(layer "In3.Cu")
		(net 1232)
	)
	(segment
		(start 199.04 109.55)
		(end 197.6 110.99)
		(width 0.1)
		(layer "In3.Cu")
		(net 1232)
	)
	(segment
		(start 261.4 81)
		(end 260.8 80.4)
		(width 0.1)
		(layer "In3.Cu")
		(net 1232)
	)
	(segment
		(start 210.931368 73.6)
		(end 209.45 75.081367)
		(width 0.1)
		(layer "In3.Cu")
		(net 1232)
	)
	(segment
		(start 261.54 94.1)
		(end 261.8 93.84)
		(width 0.1)
		(layer "In3.Cu")
		(net 1232)
	)
	(segment
		(start 197.6 110.99)
		(end 197.6 133.257842)
		(width 0.1)
		(layer "In3.Cu")
		(net 1232)
	)
	(segment
		(start 260.8 80.4)
		(end 260.8 80)
		(width 0.1)
		(layer "In3.Cu")
		(net 1232)
	)
	(segment
		(start 261.8 93.84)
		(end 261.8 90.2)
		(width 0.1)
		(layer "In3.Cu")
		(net 1232)
	)
	(segment
		(start 197.6 133.257842)
		(end 197.257842 133.6)
		(width 0.1)
		(layer "In3.Cu")
		(net 1232)
	)
	(segment
		(start 260.8 80)
		(end 261.2 79.6)
		(width 0.1)
		(layer "In3.Cu")
		(net 1232)
	)
	(segment
		(start 261.2 89.6)
		(end 261.2 89.2)
		(width 0.1)
		(layer "In3.Cu")
		(net 1232)
	)
	(segment
		(start 267.115 89.4)
		(end 266.8 89.085)
		(width 0.1)
		(layer "F.Cu")
		(net 1233)
	)
	(segment
		(start 264.75 89.4)
		(end 266.485 89.4)
		(width 0.1)
		(layer "F.Cu")
		(net 1233)
	)
	(segment
		(start 261.6 89.4)
		(end 264.75 89.4)
		(width 0.1)
		(layer "F.Cu")
		(net 1233)
	)
	(segment
		(start 266.485 89.4)
		(end 266.8 89.085)
		(width 0.1)
		(layer "F.Cu")
		(net 1233)
	)
	(segment
		(start 268.85 89.4)
		(end 267.115 89.4)
		(width 0.1)
		(layer "F.Cu")
		(net 1233)
	)
	(segment
		(start 194.5 134.5)
		(end 194 135)
		(width 0.256)
		(layer "F.Cu")
		(net 1233)
	)
	(via
		(at 266.8 89.085)
		(size 0.45)
		(drill 0.2)
		(layers "F.Cu" "B.Cu")
		(net 1233)
	)
	(via
		(at 261.6 89.4)
		(size 0.45)
		(drill 0.2)
		(layers "F.Cu" "B.Cu")
		(net 1233)
	)
	(via
		(at 264.75 89.3)
		(size 0.45)
		(drill 0.2)
		(layers "F.Cu" "B.Cu")
		(net 1233)
	)
	(via
		(at 194 135)
		(size 0.45)
		(drill 0.2)
		(layers "F.Cu" "B.Cu")
		(net 1233)
	)
	(segment
		(start 261.8 85.6)
		(end 261.8 89.2)
		(width 0.1)
		(layer "In3.Cu")
		(net 1233)
	)
	(segment
		(start 193.6 132.825)
		(end 193.825 132.6)
		(width 0.1)
		(layer "In3.Cu")
		(net 1233)
	)
	(segment
		(start 194 135)
		(end 193.6 134.6)
		(width 0.1)
		(layer "In3.Cu")
		(net 1233)
	)
	(segment
		(start 208.225 83.690158)
		(end 207.588 83.053158)
		(width 0.1)
		(layer "In3.Cu")
		(net 1233)
	)
	(segment
		(start 208.225 95.507842)
		(end 208.225 83.690158)
		(width 0.1)
		(layer "In3.Cu")
		(net 1233)
	)
	(segment
		(start 210.765684 73.2)
		(end 259.9 73.2)
		(width 0.1)
		(layer "In3.Cu")
		(net 1233)
	)
	(segment
		(start 261.6 74.9)
		(end 261.6 84.2)
		(width 0.1)
		(layer "In3.Cu")
		(net 1233)
	)
	(segment
		(start 195.62 132.237842)
		(end 195.62 108.112842)
		(width 0.1)
		(layer "In3.Cu")
		(net 1233)
	)
	(segment
		(start 259.9 73.2)
		(end 261.6 74.9)
		(width 0.1)
		(layer "In3.Cu")
		(net 1233)
	)
	(segment
		(start 207.588 76.377684)
		(end 210.765684 73.2)
		(width 0.1)
		(layer "In3.Cu")
		(net 1233)
	)
	(segment
		(start 261.2 84.6)
		(end 261.2 85)
		(width 0.1)
		(layer "In3.Cu")
		(net 1233)
	)
	(segment
		(start 193.825 132.6)
		(end 195.257842 132.6)
		(width 0.1)
		(layer "In3.Cu")
		(net 1233)
	)
	(segment
		(start 261.2 85)
		(end 261.8 85.6)
		(width 0.1)
		(layer "In3.Cu")
		(net 1233)
	)
	(segment
		(start 193.6 134.6)
		(end 193.6 132.825)
		(width 0.1)
		(layer "In3.Cu")
		(net 1233)
	)
	(segment
		(start 195.62 108.112842)
		(end 208.225 95.507842)
		(width 0.1)
		(layer "In3.Cu")
		(net 1233)
	)
	(segment
		(start 207.588 83.053158)
		(end 207.588 76.377684)
		(width 0.1)
		(layer "In3.Cu")
		(net 1233)
	)
	(segment
		(start 261.6 84.2)
		(end 261.2 84.6)
		(width 0.1)
		(layer "In3.Cu")
		(net 1233)
	)
	(segment
		(start 261.8 89.2)
		(end 261.6 89.4)
		(width 0.1)
		(layer "In3.Cu")
		(net 1233)
	)
	(segment
		(start 195.257842 132.6)
		(end 195.62 132.237842)
		(width 0.1)
		(layer "In3.Cu")
		(net 1233)
	)
	(segment
		(start 220.935 97.535)
		(end 219.299999 95.899999)
		(width 0.1)
		(layer "F.Cu")
		(net 1234)
	)
	(segment
		(start 219.299999 95.899999)
		(end 218.892416 95.899999)
		(width 0.1)
		(layer "F.Cu")
		(net 1234)
	)
	(segment
		(start 220.935 98.575)
		(end 220.935 97.535)
		(width 0.1)
		(layer "F.Cu")
		(net 1234)
	)
	(segment
		(start 218.599999 95.607582)
		(end 218.599999 94.025499)
		(width 0.1)
		(layer "F.Cu")
		(net 1234)
	)
	(segment
		(start 218.892416 95.899999)
		(end 218.599999 95.607582)
		(width 0.1)
		(layer "F.Cu")
		(net 1234)
	)
	(segment
		(start 218.599999 94.025499)
		(end 218.799999 93.825499)
		(width 0.1)
		(layer "F.Cu")
		(net 1234)
	)
	(segment
		(start 203.5 126.5)
		(end 204 126)
		(width 0.256)
		(layer "F.Cu")
		(net 1234)
	)
	(via
		(at 204 126)
		(size 0.45)
		(drill 0.2)
		(layers "F.Cu" "B.Cu")
		(net 1234)
	)
	(via
		(at 218.799999 93.825499)
		(size 0.45)
		(drill 0.2)
		(layers "F.Cu" "B.Cu")
		(net 1234)
	)
	(segment
		(start 203.6 117.53)
		(end 203.6 125.6)
		(width 0.1)
		(layer "In3.Cu")
		(net 1234)
	)
	(segment
		(start 204.01 117.12)
		(end 203.6 117.53)
		(width 0.1)
		(layer "In3.Cu")
		(net 1234)
	)
	(segment
		(start 204.036421 108.246421)
		(end 204.01 108.272842)
		(width 0.1)
		(layer "In3.Cu")
		(net 1234)
	)
	(segment
		(start 204.036421 108.193579)
		(end 204.036421 108.246421)
		(width 0.1)
		(layer "In3.Cu")
		(net 1234)
	)
	(segment
		(start 218.799999 93.825499)
		(end 218.404501 93.825499)
		(width 0.1)
		(layer "In3.Cu")
		(net 1234)
	)
	(segment
		(start 204.01 108.272842)
		(end 204.01 117.12)
		(width 0.1)
		(layer "In3.Cu")
		(net 1234)
	)
	(segment
		(start 218.404501 93.825499)
		(end 204.036421 108.193579)
		(width 0.1)
		(layer "In3.Cu")
		(net 1234)
	)
	(segment
		(start 203.6 125.6)
		(end 204 126)
		(width 0.1)
		(layer "In3.Cu")
		(net 1234)
	)
	(segment
		(start 214.5 125.5)
		(end 215 125)
		(width 0.256)
		(layer "F.Cu")
		(net 1235)
	)
	(via
		(at 215 125)
		(size 0.45)
		(drill 0.2)
		(layers "F.Cu" "B.Cu")
		(net 1235)
	)
	(via
		(at 222.199999 98.774499)
		(size 0.45)
		(drill 0.2)
		(layers "F.Cu" "B.Cu")
		(net 1235)
	)
	(segment
		(start 219.897053 99.199999)
		(end 215.6 103.497052)
		(width 0.1)
		(layer "In3.Cu")
		(net 1235)
	)
	(segment
		(start 215.6 124.4)
		(end 215 125)
		(width 0.1)
		(layer "In3.Cu")
		(net 1235)
	)
	(segment
		(start 221.179894 98.899999)
		(end 220.879894 99.199999)
		(width 0.1)
		(layer "In3.Cu")
		(net 1235)
	)
	(segment
		(start 220.879894 99.199999)
		(end 219.897053 99.199999)
		(width 0.1)
		(layer "In3.Cu")
		(net 1235)
	)
	(segment
		(start 222.074499 98.899999)
		(end 221.179894 98.899999)
		(width 0.1)
		(layer "In3.Cu")
		(net 1235)
	)
	(segment
		(start 215.6 103.497052)
		(end 215.6 124.4)
		(width 0.1)
		(layer "In3.Cu")
		(net 1235)
	)
	(segment
		(start 222.199999 98.774499)
		(end 222.074499 98.899999)
		(width 0.1)
		(layer "In3.Cu")
		(net 1235)
	)
	(segment
		(start 205.5 128.5)
		(end 206 128)
		(width 0.256)
		(layer "F.Cu")
		(net 1236)
	)
	(segment
		(start 222.699999 96.799999)
		(end 220.499999 96.799999)
		(width 0.1)
		(layer "F.Cu")
		(net 1236)
	)
	(segment
		(start 223.475 98.575)
		(end 223.475 97.575)
		(width 0.1)
		(layer "F.Cu")
		(net 1236)
	)
	(segment
		(start 223.475 97.575)
		(end 222.699999 96.799999)
		(width 0.1)
		(layer "F.Cu")
		(net 1236)
	)
	(segment
		(start 220.499999 96.799999)
		(end 219.099999 95.399999)
		(width 0.1)
		(layer "F.Cu")
		(net 1236)
	)
	(via
		(at 206 128)
		(size 0.45)
		(drill 0.2)
		(layers "F.Cu" "B.Cu")
		(net 1236)
	)
	(via
		(at 219.099999 95.399999)
		(size 0.45)
		(drill 0.2)
		(layers "F.Cu" "B.Cu")
		(net 1236)
	)
	(segment
		(start 206 128)
		(end 206.6 127.4)
		(width 0.1)
		(layer "In3.Cu")
		(net 1236)
	)
	(segment
		(start 219.099999 95.399999)
		(end 218.579895 95.399999)
		(width 0.1)
		(layer "In3.Cu")
		(net 1236)
	)
	(segment
		(start 218.579895 95.399999)
		(end 206.6 107.379894)
		(width 0.1)
		(layer "In3.Cu")
		(net 1236)
	)
	(segment
		(start 206.6 107.379894)
		(end 206.6 127.4)
		(width 0.1)
		(layer "In3.Cu")
		(net 1236)
	)
	(segment
		(start 220.699999 96.499999)
		(end 223.699999 96.499999)
		(width 0.1)
		(layer "F.Cu")
		(net 1237)
	)
	(segment
		(start 214.999294 124.000706)
		(end 215.01293 124.000706)
		(width 0.256)
		(layer "F.Cu")
		(net 1237)
	)
	(segment
		(start 214.5 124.5)
		(end 214.999294 124.000706)
		(width 0.256)
		(layer "F.Cu")
		(net 1237)
	)
	(segment
		(start 220.099999 95.899999)
		(end 220.699999 96.499999)
		(width 0.1)
		(layer "F.Cu")
		(net 1237)
	)
	(segment
		(start 224.745 97.545)
		(end 224.745 98.575)
		(width 0.1)
		(layer "F.Cu")
		(net 1237)
	)
	(segment
		(start 220.099999 93.974499)
		(end 220.099999 95.899999)
		(width 0.1)
		(layer "F.Cu")
		(net 1237)
	)
	(segment
		(start 223.699999 96.499999)
		(end 224.745 97.545)
		(width 0.1)
		(layer "F.Cu")
		(net 1237)
	)
	(via
		(at 215.01293 124.000706)
		(size 0.45)
		(drill 0.2)
		(layers "F.Cu" "B.Cu")
		(net 1237)
	)
	(via
		(at 220.099999 93.974499)
		(size 0.45)
		(drill 0.2)
		(layers "F.Cu" "B.Cu")
		(net 1237)
	)
	(segment
		(start 219.474498 94.6)
		(end 220.099999 93.974499)
		(width 0.1)
		(layer "In3.Cu")
		(net 1237)
	)
	(segment
		(start 210.29 128.53)
		(end 205.69 128.53)
		(width 0.1)
		(layer "In3.Cu")
		(net 1237)
	)
	(segment
		(start 213.18 124.45)
		(end 212.96 124.45)
		(width 0.1)
		(layer "In3.Cu")
		(net 1237)
	)
	(segment
		(start 214.552224 123.54)
		(end 213.87 123.54)
		(width 0.1)
		(layer "In3.Cu")
		(net 1237)
	)
	(segment
		(start 218.5 94.6)
		(end 219.474498 94.6)
		(width 0.1)
		(layer "In3.Cu")
		(net 1237)
	)
	(segment
		(start 210.5 127.93)
		(end 210.5 128.32)
		(width 0.1)
		(layer "In3.Cu")
		(net 1237)
	)
	(segment
		(start 204.91 117.37)
		(end 204.91 108.19)
		(width 0.1)
		(layer "In3.Cu")
		(net 1237)
	)
	(segment
		(start 211.02 127.41)
		(end 210.5 127.93)
		(width 0.1)
		(layer "In3.Cu")
		(net 1237)
	)
	(segment
		(start 205.69 128.53)
		(end 205.4 128.24)
		(width 0.1)
		(layer "In3.Cu")
		(net 1237)
	)
	(segment
		(start 215.01293 124.000706)
		(end 214.552224 123.54)
		(width 0.1)
		(layer "In3.Cu")
		(net 1237)
	)
	(segment
		(start 212.27 127.41)
		(end 211.02 127.41)
		(width 0.1)
		(layer "In3.Cu")
		(net 1237)
	)
	(segment
		(start 212.52 124.89)
		(end 212.52 127.16)
		(width 0.1)
		(layer "In3.Cu")
		(net 1237)
	)
	(segment
		(start 213.52 123.89)
		(end 213.52 124.11)
		(width 0.1)
		(layer "In3.Cu")
		(net 1237)
	)
	(segment
		(start 212.96 124.45)
		(end 212.52 124.89)
		(width 0.1)
		(layer "In3.Cu")
		(net 1237)
	)
	(segment
		(start 210.5 128.32)
		(end 210.29 128.53)
		(width 0.1)
		(layer "In3.Cu")
		(net 1237)
	)
	(segment
		(start 212.52 127.16)
		(end 212.27 127.41)
		(width 0.1)
		(layer "In3.Cu")
		(net 1237)
	)
	(segment
		(start 205.4 128.24)
		(end 205.4 117.86)
		(width 0.1)
		(layer "In3.Cu")
		(net 1237)
	)
	(segment
		(start 213.87 123.54)
		(end 213.52 123.89)
		(width 0.1)
		(layer "In3.Cu")
		(net 1237)
	)
	(segment
		(start 205.4 117.86)
		(end 204.91 117.37)
		(width 0.1)
		(layer "In3.Cu")
		(net 1237)
	)
	(segment
		(start 213.52 124.11)
		(end 213.18 124.45)
		(width 0.1)
		(layer "In3.Cu")
		(net 1237)
	)
	(segment
		(start 204.91 108.19)
		(end 218.5 94.6)
		(width 0.1)
		(layer "In3.Cu")
		(net 1237)
	)
	(segment
		(start 225.999999 97.999999)
		(end 225.999999 98.559999)
		(width 0.1)
		(layer "F.Cu")
		(net 1238)
	)
	(segment
		(start 225.999999 98.559999)
		(end 226.015 98.575)
		(width 0.1)
		(layer "F.Cu")
		(net 1238)
	)
	(segment
		(start 213.5 123.5)
		(end 214 123)
		(width 0.256)
		(layer "F.Cu")
		(net 1238)
	)
	(via
		(at 214 123)
		(size 0.45)
		(drill 0.2)
		(layers "F.Cu" "B.Cu")
		(net 1238)
	)
	(via
		(at 225.999999 97.999999)
		(size 0.45)
		(drill 0.2)
		(layers "F.Cu" "B.Cu")
		(net 1238)
	)
	(segment
		(start 214.6 103.931368)
		(end 214.6 122.4)
		(width 0.1)
		(layer "In3.Cu")
		(net 1238)
	)
	(segment
		(start 225.999999 97.999999)
		(end 221.51421 97.999999)
		(width 0.1)
		(layer "In3.Cu")
		(net 1238)
	)
	(segment
		(start 221.51421 97.999999)
		(end 220.71421 98.799999)
		(width 0.1)
		(layer "In3.Cu")
		(net 1238)
	)
	(segment
		(start 219.731369 98.799999)
		(end 214.6 103.931368)
		(width 0.1)
		(layer "In3.Cu")
		(net 1238)
	)
	(segment
		(start 214.6 122.4)
		(end 214 123)
		(width 0.1)
		(layer "In3.Cu")
		(net 1238)
	)
	(segment
		(start 220.71421 98.799999)
		(end 219.731369 98.799999)
		(width 0.1)
		(layer "In3.Cu")
		(net 1238)
	)
	(segment
		(start 212.5 126.5)
		(end 213 126)
		(width 0.256)
		(layer "F.Cu")
		(net 1239)
	)
	(segment
		(start 213 126)
		(end 213.02 126)
		(width 0.256)
		(layer "F.Cu")
		(net 1239)
	)
	(segment
		(start 227.299999 99.025499)
		(end 227.285 99.0105)
		(width 0.1)
		(layer "F.Cu")
		(net 1239)
	)
	(segment
		(start 227.285 99.0105)
		(end 227.285 98.575)
		(width 0.1)
		(layer "F.Cu")
		(net 1239)
	)
	(via
		(at 227.299999 99.025499)
		(size 0.45)
		(drill 0.2)
		(layers "F.Cu" "B.Cu")
		(net 1239)
	)
	(via
		(at 213.02 126)
		(size 0.45)
		(drill 0.2)
		(layers "F.Cu" "B.Cu")
		(net 1239)
	)
	(segment
		(start 213.02 126)
		(end 213.62 125.4)
		(width 0.1)
		(layer "In3.Cu")
		(net 1239)
	)
	(segment
		(start 220.962736 99.399999)
		(end 221.162736 99.199999)
		(width 0.1)
		(layer "In3.Cu")
		(net 1239)
	)
	(segment
		(start 221.162736 99.199999)
		(end 227.125499 99.199999)
		(width 0.1)
		(layer "In3.Cu")
		(net 1239)
	)
	(segment
		(start 219.979895 99.399999)
		(end 220.962736 99.399999)
		(width 0.1)
		(layer "In3.Cu")
		(net 1239)
	)
	(segment
		(start 215.8 125)
		(end 215.8 103.579894)
		(width 0.1)
		(layer "In3.Cu")
		(net 1239)
	)
	(segment
		(start 215.4 125.4)
		(end 215.8 125)
		(width 0.1)
		(layer "In3.Cu")
		(net 1239)
	)
	(segment
		(start 213.62 125.4)
		(end 215.4 125.4)
		(width 0.1)
		(layer "In3.Cu")
		(net 1239)
	)
	(segment
		(start 215.8 103.579894)
		(end 219.979895 99.399999)
		(width 0.1)
		(layer "In3.Cu")
		(net 1239)
	)
	(segment
		(start 227.125499 99.199999)
		(end 227.299999 99.025499)
		(width 0.1)
		(layer "In3.Cu")
		(net 1239)
	)
	(segment
		(start 227.199999 96.399999)
		(end 227.285 96.314998)
		(width 0.1)
		(layer "F.Cu")
		(net 1240)
	)
	(segment
		(start 211.5 123.5)
		(end 212 123)
		(width 0.256)
		(layer "F.Cu")
		(net 1240)
	)
	(segment
		(start 227.285 96.314998)
		(end 227.285 94.51)
		(width 0.1)
		(layer "F.Cu")
		(net 1240)
	)
	(via
		(at 212 123)
		(size 0.45)
		(drill 0.2)
		(layers "F.Cu" "B.Cu")
		(net 1240)
	)
	(via
		(at 227.199999 96.399999)
		(size 0.45)
		(drill 0.2)
		(layers "F.Cu" "B.Cu")
		(net 1240)
	)
	(segment
		(start 220.324999 97.736261)
		(end 221.861261 96.199999)
		(width 0.1)
		(layer "In3.Cu")
		(net 1240)
	)
	(segment
		(start 219.342158 97.774999)
		(end 220.324999 97.774999)
		(width 0.1)
		(layer "In3.Cu")
		(net 1240)
	)
	(segment
		(start 212.41 104.681156)
		(end 214.045578 103.045578)
		(width 0.1)
		(layer "In3.Cu")
		(net 1240)
	)
	(segment
		(start 226.999999 96.199999)
		(end 227.199999 96.399999)
		(width 0.1)
		(layer "In3.Cu")
		(net 1240)
	)
	(segment
		(start 220.324999 97.774999)
		(end 220.324999 97.736261)
		(width 0.1)
		(layer "In3.Cu")
		(net 1240)
	)
	(segment
		(start 212 123)
		(end 212.41 122.59)
		(width 0.1)
		(layer "In3.Cu")
		(net 1240)
	)
	(segment
		(start 214.07158 103.045578)
		(end 219.342158 97.774999)
		(width 0.1)
		(layer "In3.Cu")
		(net 1240)
	)
	(segment
		(start 214.045578 103.045578)
		(end 214.07158 103.045578)
		(width 0.1)
		(layer "In3.Cu")
		(net 1240)
	)
	(segment
		(start 221.861261 96.199999)
		(end 226.999999 96.199999)
		(width 0.1)
		(layer "In3.Cu")
		(net 1240)
	)
	(segment
		(start 212.41 122.59)
		(end 212.41 104.681156)
		(width 0.1)
		(layer "In3.Cu")
		(net 1240)
	)
	(segment
		(start 228.499999 97.574499)
		(end 228.499999 98.519999)
		(width 0.1)
		(layer "F.Cu")
		(net 1241)
	)
	(segment
		(start 213.5 122.5)
		(end 214 122)
		(width 0.256)
		(layer "F.Cu")
		(net 1241)
	)
	(segment
		(start 228.499999 98.519999)
		(end 228.555 98.575)
		(width 0.1)
		(layer "F.Cu")
		(net 1241)
	)
	(via
		(at 228.499999 97.574499)
		(size 0.45)
		(drill 0.2)
		(layers "F.Cu" "B.Cu")
		(net 1241)
	)
	(via
		(at 214 122)
		(size 0.45)
		(drill 0.2)
		(layers "F.Cu" "B.Cu")
		(net 1241)
	)
	(segment
		(start 214.4 103.848526)
		(end 214.4 121.6)
		(width 0.1)
		(layer "In3.Cu")
		(net 1241)
	)
	(segment
		(start 228.499999 97.574499)
		(end 221.656868 97.574499)
		(width 0.1)
		(layer "In3.Cu")
		(net 1241)
	)
	(segment
		(start 220.631368 98.599999)
		(end 219.648526 98.599999)
		(width 0.1)
		(layer "In3.Cu")
		(net 1241)
	)
	(segment
		(start 221.656868 97.574499)
		(end 220.631368 98.599999)
		(width 0.1)
		(layer "In3.Cu")
		(net 1241)
	)
	(segment
		(start 219.648526 98.599999)
		(end 214.4 103.848526)
		(width 0.1)
		(layer "In3.Cu")
		(net 1241)
	)
	(segment
		(start 214.4 121.6)
		(end 214 122)
		(width 0.1)
		(layer "In3.Cu")
		(net 1241)
	)
	(segment
		(start 228.114811 96.614811)
		(end 228.114811 95.995189)
		(width 0.1)
		(layer "F.Cu")
		(net 1242)
	)
	(segment
		(start 212.5 123.5)
		(end 213 123)
		(width 0.256)
		(layer "F.Cu")
		(net 1242)
	)
	(segment
		(start 228.555 95.555)
		(end 228.555 94.51)
		(width 0.1)
		(layer "F.Cu")
		(net 1242)
	)
	(segment
		(start 228.114811 95.995189)
		(end 228.555 95.555)
		(width 0.1)
		(layer "F.Cu")
		(net 1242)
	)
	(via
		(at 228.114811 96.614811)
		(size 0.45)
		(drill 0.2)
		(layers "F.Cu" "B.Cu")
		(net 1242)
	)
	(via
		(at 213 123)
		(size 0.45)
		(drill 0.2)
		(layers "F.Cu" "B.Cu")
		(net 1242)
	)
	(segment
		(start 219.507843 98.174999)
		(end 213.4 104.282842)
		(width 0.1)
		(layer "In3.Cu")
		(net 1242)
	)
	(segment
		(start 213.4 104.282842)
		(end 213.4 122.6)
		(width 0.1)
		(layer "In3.Cu")
		(net 1242)
	)
	(segment
		(start 228.114811 96.614811)
		(end 227.754623 96.974999)
		(width 0.1)
		(layer "In3.Cu")
		(net 1242)
	)
	(segment
		(start 227.754623 96.974999)
		(end 221.690684 96.974999)
		(width 0.1)
		(layer "In3.Cu")
		(net 1242)
	)
	(segment
		(start 221.690684 96.974999)
		(end 220.490684 98.174999)
		(width 0.1)
		(layer "In3.Cu")
		(net 1242)
	)
	(segment
		(start 220.490684 98.174999)
		(end 219.507843 98.174999)
		(width 0.1)
		(layer "In3.Cu")
		(net 1242)
	)
	(segment
		(start 213.4 122.6)
		(end 213 123)
		(width 0.1)
		(layer "In3.Cu")
		(net 1242)
	)
	(segment
		(start 203.5 127.5)
		(end 204 127)
		(width 0.256)
		(layer "F.Cu")
		(net 1243)
	)
	(segment
		(start 230.499999 92.799999)
		(end 230.499999 96.899999)
		(width 0.1)
		(layer "F.Cu")
		(net 1243)
	)
	(segment
		(start 229.825 97.574998)
		(end 229.825 98.575)
		(width 0.1)
		(layer "F.Cu")
		(net 1243)
	)
	(segment
		(start 230.499999 96.899999)
		(end 229.825 97.574998)
		(width 0.1)
		(layer "F.Cu")
		(net 1243)
	)
	(via
		(at 204 127)
		(size 0.45)
		(drill 0.2)
		(layers "F.Cu" "B.Cu")
		(net 1243)
	)
	(via
		(at 230.499999 92.799999)
		(size 0.45)
		(drill 0.2)
		(layers "F.Cu" "B.Cu")
		(net 1243)
	)
	(segment
		(start 218.740001 93.199999)
		(end 203.82 108.12)
		(width 0.1)
		(layer "In3.Cu")
		(net 1243)
	)
	(segment
		(start 203.4 126.4)
		(end 204 127)
		(width 0.1)
		(layer "In3.Cu")
		(net 1243)
	)
	(segment
		(start 203.4 117.33)
		(end 203.4 126.4)
		(width 0.1)
		(layer "In3.Cu")
		(net 1243)
	)
	(segment
		(start 230.499999 92.799999)
		(end 229.599999 92.799999)
		(width 0.1)
		(layer "In3.Cu")
		(net 1243)
	)
	(segment
		(start 229.599999 92.799999)
		(end 229.199999 93.199999)
		(width 0.1)
		(layer "In3.Cu")
		(net 1243)
	)
	(segment
		(start 229.199999 93.199999)
		(end 218.740001 93.199999)
		(width 0.1)
		(layer "In3.Cu")
		(net 1243)
	)
	(segment
		(start 203.82 108.18)
		(end 203.79 108.21)
		(width 0.1)
		(layer "In3.Cu")
		(net 1243)
	)
	(segment
		(start 203.79 108.21)
		(end 203.79 116.94)
		(width 0.1)
		(layer "In3.Cu")
		(net 1243)
	)
	(segment
		(start 203.79 116.94)
		(end 203.4 117.33)
		(width 0.1)
		(layer "In3.Cu")
		(net 1243)
	)
	(segment
		(start 203.82 108.12)
		(end 203.82 108.18)
		(width 0.1)
		(layer "In3.Cu")
		(net 1243)
	)
	(segment
		(start 218.715 136.2)
		(end 218.7 136.2)
		(width 0.201)
		(layer "F.Cu")
		(net 1244)
	)
	(via
		(at 218.7 136.2)
		(size 0.45)
		(drill 0.2)
		(layers "F.Cu" "B.Cu")
		(net 1244)
	)
	(segment
		(start 204.5 126.5)
		(end 205 126)
		(width 0.256)
		(layer "F.Cu")
		(net 1245)
	)
	(via
		(at 229.799999 93.199999)
		(size 0.45)
		(drill 0.2)
		(layers "F.Cu" "B.Cu")
		(net 1245)
	)
	(via
		(at 205 126)
		(size 0.45)
		(drill 0.2)
		(layers "F.Cu" "B.Cu")
		(net 1245)
	)
	(segment
		(start 204.4 108.12)
		(end 204.4 125.4)
		(width 0.1)
		(layer "In3.Cu")
		(net 1245)
	)
	(segment
		(start 204.4 125.4)
		(end 205 126)
		(width 0.1)
		(layer "In3.Cu")
		(net 1245)
	)
	(segment
		(start 229.799999 93.199999)
		(end 229.599999 93.399999)
		(width 0.1)
		(layer "In3.Cu")
		(net 1245)
	)
	(segment
		(start 218.320001 94.199999)
		(end 204.4 108.12)
		(width 0.1)
		(layer "In3.Cu")
		(net 1245)
	)
	(segment
		(start 218.999999 94.199999)
		(end 218.320001 94.199999)
		(width 0.1)
		(layer "In3.Cu")
		(net 1245)
	)
	(segment
		(start 219.799999 93.399999)
		(end 218.999999 94.199999)
		(width 0.1)
		(layer "In3.Cu")
		(net 1245)
	)
	(segment
		(start 229.599999 93.399999)
		(end 219.799999 93.399999)
		(width 0.1)
		(layer "In3.Cu")
		(net 1245)
	)
	(segment
		(start 211.045 122.955)
		(end 211.045 122.93)
		(width 0.256)
		(layer "F.Cu")
		(net 1246)
	)
	(segment
		(start 231.095 96.821032)
		(end 231.095 98.575)
		(width 0.1)
		(layer "F.Cu")
		(net 1246)
	)
	(segment
		(start 210.5 123.5)
		(end 211.045 122.955)
		(width 0.256)
		(layer "F.Cu")
		(net 1246)
	)
	(segment
		(start 231.716032 96.2)
		(end 231.095 96.821032)
		(width 0.1)
		(layer "F.Cu")
		(net 1246)
	)
	(via
		(at 211.045 122.93)
		(size 0.45)
		(drill 0.2)
		(layers "F.Cu" "B.Cu")
		(net 1246)
	)
	(via
		(at 231.716032 96.2)
		(size 0.45)
		(drill 0.2)
		(layers "F.Cu" "B.Cu")
		(net 1246)
	)
	(segment
		(start 219.067631 97.174999)
		(end 220.037737 97.174999)
		(width 0.1)
		(layer "In3.Cu")
		(net 1246)
	)
	(segment
		(start 210.6 105.64263)
		(end 219.067631 97.174999)
		(width 0.1)
		(layer "In3.Cu")
		(net 1246)
	)
	(segment
		(start 211.045 122.93)
		(end 210.6 122.485)
		(width 0.1)
		(layer "In3.Cu")
		(net 1246)
	)
	(segment
		(start 231.116031 95.599999)
		(end 231.716032 96.2)
		(width 0.1)
		(layer "In3.Cu")
		(net 1246)
	)
	(segment
		(start 220.037737 97.174999)
		(end 221.612735 95.599999)
		(width 0.1)
		(layer "In3.Cu")
		(net 1246)
	)
	(segment
		(start 210.6 122.485)
		(end 210.6 105.64263)
		(width 0.1)
		(layer "In3.Cu")
		(net 1246)
	)
	(segment
		(start 221.612735 95.599999)
		(end 231.116031 95.599999)
		(width 0.1)
		(layer "In3.Cu")
		(net 1246)
	)
	(segment
		(start 204.5 125.5)
		(end 205 125)
		(width 0.256)
		(layer "F.Cu")
		(net 1247)
	)
	(via
		(at 230.999999 93.199999)
		(size 0.45)
		(drill 0.2)
		(layers "F.Cu" "B.Cu")
		(net 1247)
	)
	(via
		(at 205 125)
		(size 0.45)
		(drill 0.2)
		(layers "F.Cu" "B.Cu")
		(net 1247)
	)
	(segment
		(start 219.082841 94.399999)
		(end 218.410001 94.399999)
		(width 0.1)
		(layer "In3.Cu")
		(net 1247)
	)
	(segment
		(start 230.599999 93.599999)
		(end 219.882841 93.599999)
		(width 0.1)
		(layer "In3.Cu")
		(net 1247)
	)
	(segment
		(start 218.410001 94.399999)
		(end 204.6 108.21)
		(width 0.1)
		(layer "In3.Cu")
		(net 1247)
	)
	(segment
		(start 219.882841 93.599999)
		(end 219.082841 94.399999)
		(width 0.1)
		(layer "In3.Cu")
		(net 1247)
	)
	(segment
		(start 204.6 124.6)
		(end 205 125)
		(width 0.1)
		(layer "In3.Cu")
		(net 1247)
	)
	(segment
		(start 204.6 108.21)
		(end 204.6 124.6)
		(width 0.1)
		(layer "In3.Cu")
		(net 1247)
	)
	(segment
		(start 230.999999 93.199999)
		(end 230.599999 93.599999)
		(width 0.1)
		(layer "In3.Cu")
		(net 1247)
	)
	(segment
		(start 211.5 126.5)
		(end 212 126)
		(width 0.256)
		(layer "F.Cu")
		(net 1248)
	)
	(segment
		(start 233.635 96.435001)
		(end 233.635 98.575)
		(width 0.1)
		(layer "F.Cu")
		(net 1248)
	)
	(segment
		(start 233.535187 96.335188)
		(end 233.635 96.435001)
		(width 0.1)
		(layer "F.Cu")
		(net 1248)
	)
	(via
		(at 212 126)
		(size 0.45)
		(drill 0.2)
		(layers "F.Cu" "B.Cu")
		(net 1248)
	)
	(via
		(at 233.535187 96.335188)
		(size 0.45)
		(drill 0.2)
		(layers "F.Cu" "B.Cu")
		(net 1248)
	)
	(segment
		(start 219.233315 97.574999)
		(end 211.62 105.188314)
		(width 0.1)
		(layer "In3.Cu")
		(net 1248)
	)
	(segment
		(start 221.778419 95.999999)
		(end 220.203421 97.574999)
		(width 0.1)
		(layer "In3.Cu")
		(net 1248)
	)
	(segment
		(start 211.62 105.188314)
		(end 211.62 125.62)
		(width 0.1)
		(layer "In3.Cu")
		(net 1248)
	)
	(segment
		(start 211.62 125.62)
		(end 212 126)
		(width 0.1)
		(layer "In3.Cu")
		(net 1248)
	)
	(segment
		(start 229.882841 95.999999)
		(end 221.778419 95.999999)
		(width 0.1)
		(layer "In3.Cu")
		(net 1248)
	)
	(segment
		(start 220.203421 97.574999)
		(end 219.233315 97.574999)
		(width 0.1)
		(layer "In3.Cu")
		(net 1248)
	)
	(segment
		(start 233.024998 96.8)
		(end 230.682842 96.8)
		(width 0.1)
		(layer "In3.Cu")
		(net 1248)
	)
	(segment
		(start 233.535187 96.335188)
		(end 233.48981 96.335188)
		(width 0.1)
		(layer "In3.Cu")
		(net 1248)
	)
	(segment
		(start 230.682842 96.8)
		(end 229.882841 95.999999)
		(width 0.1)
		(layer "In3.Cu")
		(net 1248)
	)
	(segment
		(start 233.48981 96.335188)
		(end 233.024998 96.8)
		(width 0.1)
		(layer "In3.Cu")
		(net 1248)
	)
	(segment
		(start 234.905 99.194998)
		(end 234.905 98.575)
		(width 0.1)
		(layer "F.Cu")
		(net 1249)
	)
	(segment
		(start 234.899999 99.199999)
		(end 234.905 99.194998)
		(width 0.1)
		(layer "F.Cu")
		(net 1249)
	)
	(segment
		(start 213.5 126.5)
		(end 214 126)
		(width 0.256)
		(layer "F.Cu")
		(net 1249)
	)
	(via
		(at 234.899999 99.199999)
		(size 0.45)
		(drill 0.2)
		(layers "F.Cu" "B.Cu")
		(net 1249)
	)
	(via
		(at 214 126)
		(size 0.45)
		(drill 0.2)
		(layers "F.Cu" "B.Cu")
		(net 1249)
	)
	(segment
		(start 221.245579 99.399999)
		(end 221.045579 99.599999)
		(width 0.1)
		(layer "In3.Cu")
		(net 1249)
	)
	(segment
		(start 216 103.662736)
		(end 216 125.1)
		(width 0.1)
		(layer "In3.Cu")
		(net 1249)
	)
	(segment
		(start 234.899999 99.199999)
		(end 234.699999 99.399999)
		(width 0.1)
		(layer "In3.Cu")
		(net 1249)
	)
	(segment
		(start 216 125.1)
		(end 215.5 125.6)
		(width 0.1)
		(layer "In3.Cu")
		(net 1249)
	)
	(segment
		(start 214.4 125.6)
		(end 214 126)
		(width 0.1)
		(layer "In3.Cu")
		(net 1249)
	)
	(segment
		(start 234.699999 99.399999)
		(end 221.245579 99.399999)
		(width 0.1)
		(layer "In3.Cu")
		(net 1249)
	)
	(segment
		(start 215.5 125.6)
		(end 214.4 125.6)
		(width 0.1)
		(layer "In3.Cu")
		(net 1249)
	)
	(segment
		(start 220.062737 99.599999)
		(end 216 103.662736)
		(width 0.1)
		(layer "In3.Cu")
		(net 1249)
	)
	(segment
		(start 221.045579 99.599999)
		(end 220.062737 99.599999)
		(width 0.1)
		(layer "In3.Cu")
		(net 1249)
	)
	(segment
		(start 214.5 127.5)
		(end 215 127)
		(width 0.256)
		(layer "F.Cu")
		(net 1250)
	)
	(segment
		(start 234.299999 96.099999)
		(end 234.905 95.494998)
		(width 0.1)
		(layer "F.Cu")
		(net 1250)
	)
	(segment
		(start 234.299999 100.199999)
		(end 234.299999 96.099999)
		(width 0.1)
		(layer "F.Cu")
		(net 1250)
	)
	(segment
		(start 234.905 95.494998)
		(end 234.905 94.51)
		(width 0.1)
		(layer "F.Cu")
		(net 1250)
	)
	(via
		(at 215 127)
		(size 0.45)
		(drill 0.2)
		(layers "F.Cu" "B.Cu")
		(net 1250)
	)
	(via
		(at 234.299999 100.199999)
		(size 0.45)
		(drill 0.2)
		(layers "F.Cu" "B.Cu")
		(net 1250)
	)
	(segment
		(start 216.6 125.5)
		(end 216.6 103.911262)
		(width 0.1)
		(layer "In3.Cu")
		(net 1250)
	)
	(segment
		(start 221.294108 100.199999)
		(end 220.311263 100.199999)
		(width 0.1)
		(layer "In3.Cu")
		(net 1250)
	)
	(segment
		(start 215 127)
		(end 215.1 127)
		(width 0.1)
		(layer "In3.Cu")
		(net 1250)
	)
	(segment
		(start 221.494107 99.999999)
		(end 221.294108 100.199999)
		(width 0.1)
		(layer "In3.Cu")
		(net 1250)
	)
	(segment
		(start 234.299999 100.199999)
		(end 234.099999 99.999999)
		(width 0.1)
		(layer "In3.Cu")
		(net 1250)
	)
	(segment
		(start 234.099999 99.999999)
		(end 221.494107 99.999999)
		(width 0.1)
		(layer "In3.Cu")
		(net 1250)
	)
	(segment
		(start 216.6 103.911262)
		(end 220.311263 100.199999)
		(width 0.1)
		(layer "In3.Cu")
		(net 1250)
	)
	(segment
		(start 215.1 127)
		(end 216.6 125.5)
		(width 0.1)
		(layer "In3.Cu")
		(net 1250)
	)
	(segment
		(start 236.175 96.724998)
		(end 236.175 98.575)
		(width 0.1)
		(layer "F.Cu")
		(net 1251)
	)
	(segment
		(start 236.799999 92.874499)
		(end 236.799999 96.099999)
		(width 0.1)
		(layer "F.Cu")
		(net 1251)
	)
	(segment
		(start 205.5 125.5)
		(end 206 125)
		(width 0.256)
		(layer "F.Cu")
		(net 1251)
	)
	(segment
		(start 236.799999 96.099999)
		(end 236.175 96.724998)
		(width 0.1)
		(layer "F.Cu")
		(net 1251)
	)
	(via
		(at 236.799999 92.874499)
		(size 0.45)
		(drill 0.2)
		(layers "F.Cu" "B.Cu")
		(net 1251)
	)
	(via
		(at 206 125)
		(size 0.45)
		(drill 0.2)
		(layers "F.Cu" "B.Cu")
		(net 1251)
	)
	(segment
		(start 234.799999 93.999999)
		(end 220.949999 93.999999)
		(width 0.1)
		(layer "In3.Cu")
		(net 1251)
	)
	(segment
		(start 236.799999 92.874499)
		(end 235.925499 92.874499)
		(width 0.1)
		(layer "In3.Cu")
		(net 1251)
	)
	(segment
		(start 235.925499 92.874499)
		(end 234.799999 93.999999)
		(width 0.1)
		(layer "In3.Cu")
		(net 1251)
	)
	(segment
		(start 218.672053 95.024999)
		(end 206.4 107.297052)
		(width 0.1)
		(layer "In3.Cu")
		(net 1251)
	)
	(segment
		(start 219.924999 95.024999)
		(end 218.672053 95.024999)
		(width 0.1)
		(layer "In3.Cu")
		(net 1251)
	)
	(segment
		(start 220.949999 93.999999)
		(end 219.924999 95.024999)
		(width 0.1)
		(layer "In3.Cu")
		(net 1251)
	)
	(segment
		(start 206.4 107.297052)
		(end 206.4 124.6)
		(width 0.1)
		(layer "In3.Cu")
		(net 1251)
	)
	(segment
		(start 206 125)
		(end 206.4 124.6)
		(width 0.1)
		(layer "In3.Cu")
		(net 1251)
	)
	(segment
		(start 206.5 123.5)
		(end 207 123)
		(width 0.256)
		(layer "F.Cu")
		(net 1252)
	)
	(segment
		(start 236.199999 94.485001)
		(end 236.175 94.51)
		(width 0.1)
		(layer "F.Cu")
		(net 1252)
	)
	(segment
		(start 236.199999 93.474499)
		(end 236.199999 94.485001)
		(width 0.1)
		(layer "F.Cu")
		(net 1252)
	)
	(via
		(at 236.199999 93.474499)
		(size 0.45)
		(drill 0.2)
		(layers "F.Cu" "B.Cu")
		(net 1252)
	)
	(via
		(at 207 123)
		(size 0.45)
		(drill 0.2)
		(layers "F.Cu" "B.Cu")
		(net 1252)
	)
	(segment
		(start 207 123)
		(end 207.4 122.6)
		(width 0.1)
		(layer "In3.Cu")
		(net 1252)
	)
	(segment
		(start 235.474499 94.199999)
		(end 221.032841 94.199999)
		(width 0.1)
		(layer "In3.Cu")
		(net 1252)
	)
	(segment
		(start 219.457841 95.774999)
		(end 218.487737 95.774999)
		(width 0.1)
		(layer "In3.Cu")
		(net 1252)
	)
	(segment
		(start 221.032841 94.199999)
		(end 219.457841 95.774999)
		(width 0.1)
		(layer "In3.Cu")
		(net 1252)
	)
	(segment
		(start 218.487737 95.774999)
		(end 207.4 106.862736)
		(width 0.1)
		(layer "In3.Cu")
		(net 1252)
	)
	(segment
		(start 236.199999 93.474499)
		(end 235.474499 94.199999)
		(width 0.1)
		(layer "In3.Cu")
		(net 1252)
	)
	(segment
		(start 207.4 106.862736)
		(end 207.4 122.6)
		(width 0.1)
		(layer "In3.Cu")
		(net 1252)
	)
	(segment
		(start 238.09986 96.900138)
		(end 237.445 97.554998)
		(width 0.1)
		(layer "F.Cu")
		(net 1253)
	)
	(segment
		(start 237.445 97.554998)
		(end 237.445 98.575)
		(width 0.1)
		(layer "F.Cu")
		(net 1253)
	)
	(segment
		(start 206.5 128.5)
		(end 207 128)
		(width 0.256)
		(layer "F.Cu")
		(net 1253)
	)
	(segment
		(start 238.09986 92.899878)
		(end 238.09986 96.900138)
		(width 0.1)
		(layer "F.Cu")
		(net 1253)
	)
	(via
		(at 207 128)
		(size 0.45)
		(drill 0.2)
		(layers "F.Cu" "B.Cu")
		(net 1253)
	)
	(via
		(at 238.09986 92.899878)
		(size 0.45)
		(drill 0.2)
		(layers "F.Cu" "B.Cu")
		(net 1253)
	)
	(segment
		(start 238.09986 92.899878)
		(end 236.599739 94.399999)
		(width 0.1)
		(layer "In3.Cu")
		(net 1253)
	)
	(segment
		(start 236.599739 94.399999)
		(end 221.115683 94.399999)
		(width 0.1)
		(layer "In3.Cu")
		(net 1253)
	)
	(segment
		(start 219.540683 95.974999)
		(end 218.570579 95.974999)
		(width 0.1)
		(layer "In3.Cu")
		(net 1253)
	)
	(segment
		(start 207.6 106.945578)
		(end 207.6 127.4)
		(width 0.1)
		(layer "In3.Cu")
		(net 1253)
	)
	(segment
		(start 207.6 127.4)
		(end 207 128)
		(width 0.1)
		(layer "In3.Cu")
		(net 1253)
	)
	(segment
		(start 218.570579 95.974999)
		(end 207.6 106.945578)
		(width 0.1)
		(layer "In3.Cu")
		(net 1253)
	)
	(segment
		(start 221.115683 94.399999)
		(end 219.540683 95.974999)
		(width 0.1)
		(layer "In3.Cu")
		(net 1253)
	)
	(segment
		(start 237.445 96.166)
		(end 237.445 94.51)
		(width 0.1)
		(layer "F.Cu")
		(net 1254)
	)
	(segment
		(start 214.5 126.5)
		(end 215 126)
		(width 0.256)
		(layer "F.Cu")
		(net 1254)
	)
	(segment
		(start 236.811 96.8)
		(end 237.445 96.166)
		(width 0.1)
		(layer "F.Cu")
		(net 1254)
	)
	(via
		(at 215 126)
		(size 0.45)
		(drill 0.2)
		(layers "F.Cu" "B.Cu")
		(net 1254)
	)
	(via
		(at 236.811 96.8)
		(size 0.45)
		(drill 0.2)
		(layers "F.Cu" "B.Cu")
		(net 1254)
	)
	(segment
		(start 216.2 103.745578)
		(end 216.2 125.2)
		(width 0.1)
		(layer "In3.Cu")
		(net 1254)
	)
	(segment
		(start 236.811 96.8)
		(end 236.811 99.388998)
		(width 0.1)
		(layer "In3.Cu")
		(net 1254)
	)
	(segment
		(start 236.811 99.388998)
		(end 236.599999 99.599999)
		(width 0.1)
		(layer "In3.Cu")
		(net 1254)
	)
	(segment
		(start 236.599999 99.599999)
		(end 221.328422 99.599999)
		(width 0.1)
		(layer "In3.Cu")
		(net 1254)
	)
	(segment
		(start 215.4 126)
		(end 215 126)
		(width 0.1)
		(layer "In3.Cu")
		(net 1254)
	)
	(segment
		(start 221.328422 99.599999)
		(end 221.128422 99.799999)
		(width 0.1)
		(layer "In3.Cu")
		(net 1254)
	)
	(segment
		(start 221.128422 99.799999)
		(end 220.145579 99.799999)
		(width 0.1)
		(layer "In3.Cu")
		(net 1254)
	)
	(segment
		(start 220.145579 99.799999)
		(end 216.2 103.745578)
		(width 0.1)
		(layer "In3.Cu")
		(net 1254)
	)
	(segment
		(start 216.2 125.2)
		(end 215.4 126)
		(width 0.1)
		(layer "In3.Cu")
		(net 1254)
	)
	(segment
		(start 239.299999 92.900183)
		(end 239.299999 96.399999)
		(width 0.1)
		(layer "F.Cu")
		(net 1255)
	)
	(segment
		(start 207.5 126.5)
		(end 208 126)
		(width 0.256)
		(layer "F.Cu")
		(net 1255)
	)
	(segment
		(start 239.299999 96.399999)
		(end 238.715 96.984998)
		(width 0.1)
		(layer "F.Cu")
		(net 1255)
	)
	(segment
		(start 239.315794 92.884388)
		(end 239.299999 92.900183)
		(width 0.1)
		(layer "F.Cu")
		(net 1255)
	)
	(segment
		(start 238.715 96.984998)
		(end 238.715 98.575)
		(width 0.1)
		(layer "F.Cu")
		(net 1255)
	)
	(via
		(at 239.315794 92.884388)
		(size 0.45)
		(drill 0.2)
		(layers "F.Cu" "B.Cu")
		(net 1255)
	)
	(via
		(at 208 126)
		(size 0.45)
		(drill 0.2)
		(layers "F.Cu" "B.Cu")
		(net 1255)
	)
	(segment
		(start 218.653421 96.174999)
		(end 219.623525 96.174999)
		(width 0.1)
		(layer "In3.Cu")
		(net 1255)
	)
	(segment
		(start 237.599999 94.599999)
		(end 239.31561 92.884388)
		(width 0.1)
		(layer "In3.Cu")
		(net 1255)
	)
	(segment
		(start 208.4 106.42842)
		(end 218.653421 96.174999)
		(width 0.1)
		(layer "In3.Cu")
		(net 1255)
	)
	(segment
		(start 208.4 125.6)
		(end 208.4 106.42842)
		(width 0.1)
		(layer "In3.Cu")
		(net 1255)
	)
	(segment
		(start 221.198525 94.599999)
		(end 237.599999 94.599999)
		(width 0.1)
		(layer "In3.Cu")
		(net 1255)
	)
	(segment
		(start 208 126)
		(end 208.4 125.6)
		(width 0.1)
		(layer "In3.Cu")
		(net 1255)
	)
	(segment
		(start 219.623525 96.174999)
		(end 221.198525 94.599999)
		(width 0.1)
		(layer "In3.Cu")
		(net 1255)
	)
	(segment
		(start 239.31561 92.884388)
		(end 239.315794 92.884388)
		(width 0.1)
		(layer "In3.Cu")
		(net 1255)
	)
	(segment
		(start 211.965 127.035)
		(end 211.5 127.5)
		(width 0.256)
		(layer "F.Cu")
		(net 1256)
	)
	(segment
		(start 238.699999 95.799999)
		(end 238.715 95.784998)
		(width 0.1)
		(layer "F.Cu")
		(net 1256)
	)
	(segment
		(start 238.715 95.784998)
		(end 238.715 94.51)
		(width 0.1)
		(layer "F.Cu")
		(net 1256)
	)
	(segment
		(start 212 127.035)
		(end 211.965 127.035)
		(width 0.256)
		(layer "F.Cu")
		(net 1256)
	)
	(via
		(at 212 127.035)
		(size 0.45)
		(drill 0.2)
		(layers "F.Cu" "B.Cu")
		(net 1256)
	)
	(via
		(at 238.699999 95.799999)
		(size 0.45)
		(drill 0.2)
		(layers "F.Cu" "B.Cu")
		(net 1256)
	)
	(segment
		(start 211.42 126.455)
		(end 211.42 105.105472)
		(width 0.1)
		(layer "In3.Cu")
		(net 1256)
	)
	(segment
		(start 230.099999 95.799999)
		(end 230.9 96.6)
		(width 0.1)
		(layer "In3.Cu")
		(net 1256)
	)
	(segment
		(start 232.649998 96.6)
		(end 233.449999 95.799999)
		(width 0.1)
		(layer "In3.Cu")
		(net 1256)
	)
	(segment
		(start 230.9 96.6)
		(end 232.649998 96.6)
		(width 0.1)
		(layer "In3.Cu")
		(net 1256)
	)
	(segment
		(start 220.120579 97.374999)
		(end 221.695577 95.799999)
		(width 0.1)
		(layer "In3.Cu")
		(net 1256)
	)
	(segment
		(start 233.449999 95.799999)
		(end 238.699999 95.799999)
		(width 0.1)
		(layer "In3.Cu")
		(net 1256)
	)
	(segment
		(start 221.695577 95.799999)
		(end 230.099999 95.799999)
		(width 0.1)
		(layer "In3.Cu")
		(net 1256)
	)
	(segment
		(start 212 127.035)
		(end 211.42 126.455)
		(width 0.1)
		(layer "In3.Cu")
		(net 1256)
	)
	(segment
		(start 211.42 105.105472)
		(end 219.150473 97.374999)
		(width 0.1)
		(layer "In3.Cu")
		(net 1256)
	)
	(segment
		(start 219.150473 97.374999)
		(end 220.120579 97.374999)
		(width 0.1)
		(layer "In3.Cu")
		(net 1256)
	)
	(segment
		(start 210.5 125.5)
		(end 211 125)
		(width 0.256)
		(layer "F.Cu")
		(net 1257)
	)
	(segment
		(start 239.985 96.814998)
		(end 240.599999 96.199999)
		(width 0.1)
		(layer "F.Cu")
		(net 1257)
	)
	(segment
		(start 239.985 98.575)
		(end 239.985 96.814998)
		(width 0.1)
		(layer "F.Cu")
		(net 1257)
	)
	(via
		(at 240.599999 96.199999)
		(size 0.45)
		(drill 0.2)
		(layers "F.Cu" "B.Cu")
		(net 1257)
	)
	(via
		(at 211 125)
		(size 0.45)
		(drill 0.2)
		(layers "F.Cu" "B.Cu")
		(net 1257)
	)
	(segment
		(start 221.447051 95.199999)
		(end 219.872052 96.774999)
		(width 0.1)
		(layer "In3.Cu")
		(net 1257)
	)
	(segment
		(start 239.599999 95.199999)
		(end 221.447051 95.199999)
		(width 0.1)
		(layer "In3.Cu")
		(net 1257)
	)
	(segment
		(start 209.6 106.076946)
		(end 209.6 123.4)
		(width 0.1)
		(layer "In3.Cu")
		(net 1257)
	)
	(segment
		(start 210.5 124.5)
		(end 211 125)
		(width 0.1)
		(layer "In3.Cu")
		(net 1257)
	)
	(segment
		(start 240.599999 96.199999)
		(end 239.599999 95.199999)
		(width 0.1)
		(layer "In3.Cu")
		(net 1257)
	)
	(segment
		(start 219.872052 96.774999)
		(end 218.901947 96.774999)
		(width 0.1)
		(layer "In3.Cu")
		(net 1257)
	)
	(segment
		(start 209.6 123.4)
		(end 209.8 123.6)
		(width 0.1)
		(layer "In3.Cu")
		(net 1257)
	)
	(segment
		(start 210.3 123.6)
		(end 210.5 123.8)
		(width 0.1)
		(layer "In3.Cu")
		(net 1257)
	)
	(segment
		(start 209.8 123.6)
		(end 210.3 123.6)
		(width 0.1)
		(layer "In3.Cu")
		(net 1257)
	)
	(segment
		(start 218.901947 96.774999)
		(end 209.6 106.076946)
		(width 0.1)
		(layer "In3.Cu")
		(net 1257)
	)
	(segment
		(start 210.5 123.8)
		(end 210.5 124.5)
		(width 0.1)
		(layer "In3.Cu")
		(net 1257)
	)
	(segment
		(start 212.5 124.5)
		(end 213 124)
		(width 0.256)
		(layer "F.Cu")
		(net 1258)
	)
	(segment
		(start 239.985 94.51)
		(end 239.985 96.314998)
		(width 0.1)
		(layer "F.Cu")
		(net 1258)
	)
	(segment
		(start 239.985 96.314998)
		(end 239.499999 96.799999)
		(width 0.1)
		(layer "F.Cu")
		(net 1258)
	)
	(via
		(at 213 124)
		(size 0.45)
		(drill 0.2)
		(layers "F.Cu" "B.Cu")
		(net 1258)
	)
	(via
		(at 239.499999 96.799999)
		(size 0.45)
		(drill 0.2)
		(layers "F.Cu" "B.Cu")
		(net 1258)
	)
	(segment
		(start 220.573526 98.374999)
		(end 221.748526 97.199999)
		(width 0.1)
		(layer "In3.Cu")
		(net 1258)
	)
	(segment
		(start 213 124)
		(end 213.6 123.4)
		(width 0.1)
		(layer "In3.Cu")
		(net 1258)
	)
	(segment
		(start 233.499999 97.199999)
		(end 234.499998 96.2)
		(width 0.1)
		(layer "In3.Cu")
		(net 1258)
	)
	(segment
		(start 238.751992 96.799999)
		(end 239.499999 96.799999)
		(width 0.1)
		(layer "In3.Cu")
		(net 1258)
	)
	(segment
		(start 219.590685 98.374999)
		(end 220.573526 98.374999)
		(width 0.1)
		(layer "In3.Cu")
		(net 1258)
	)
	(segment
		(start 213.6 123.4)
		(end 213.6 104.365684)
		(width 0.1)
		(layer "In3.Cu")
		(net 1258)
	)
	(segment
		(start 213.6 104.365684)
		(end 219.590685 98.374999)
		(width 0.1)
		(layer "In3.Cu")
		(net 1258)
	)
	(segment
		(start 234.499998 96.2)
		(end 238.151993 96.2)
		(width 0.1)
		(layer "In3.Cu")
		(net 1258)
	)
	(segment
		(start 238.151993 96.2)
		(end 238.751992 96.799999)
		(width 0.1)
		(layer "In3.Cu")
		(net 1258)
	)
	(segment
		(start 221.748526 97.199999)
		(end 233.499999 97.199999)
		(width 0.1)
		(layer "In3.Cu")
		(net 1258)
	)
	(segment
		(start 212.5 125.5)
		(end 213 125)
		(width 0.256)
		(layer "F.Cu")
		(net 1259)
	)
	(via
		(at 213 125)
		(size 0.45)
		(drill 0.2)
		(layers "F.Cu" "B.Cu")
		(net 1259)
	)
	(via
		(at 241.199999 97.299999)
		(size 0.45)
		(drill 0.2)
		(layers "F.Cu" "B.Cu")
		(net 1259)
	)
	(segment
		(start 234.599998 96.4)
		(end 232.599999 98.399999)
		(width 0.1)
		(layer "In3.Cu")
		(net 1259)
	)
	(segment
		(start 215.4 124.2)
		(end 215.2 124.4)
		(width 0.1)
		(layer "In3.Cu")
		(net 1259)
	)
	(segment
		(start 238.96915 97.299999)
		(end 238.069151 96.4)
		(width 0.1)
		(layer "In3.Cu")
		(net 1259)
	)
	(segment
		(start 219.814211 98.999999)
		(end 215.4 103.41421)
		(width 0.1)
		(layer "In3.Cu")
		(net 1259)
	)
	(segment
		(start 221.397052 98.399999)
		(end 220.797052 98.999999)
		(width 0.1)
		(layer "In3.Cu")
		(net 1259)
	)
	(segment
		(start 213.6 124.4)
		(end 213 125)
		(width 0.1)
		(layer "In3.Cu")
		(net 1259)
	)
	(segment
		(start 220.797052 98.999999)
		(end 219.814211 98.999999)
		(width 0.1)
		(layer "In3.Cu")
		(net 1259)
	)
	(segment
		(start 241.199999 97.299999)
		(end 238.96915 97.299999)
		(width 0.1)
		(layer "In3.Cu")
		(net 1259)
	)
	(segment
		(start 215.4 103.41421)
		(end 215.4 124.2)
		(width 0.1)
		(layer "In3.Cu")
		(net 1259)
	)
	(segment
		(start 232.599999 98.399999)
		(end 221.397052 98.399999)
		(width 0.1)
		(layer "In3.Cu")
		(net 1259)
	)
	(segment
		(start 238.069151 96.4)
		(end 234.599998 96.4)
		(width 0.1)
		(layer "In3.Cu")
		(net 1259)
	)
	(segment
		(start 215.2 124.4)
		(end 213.6 124.4)
		(width 0.1)
		(layer "In3.Cu")
		(net 1259)
	)
	(segment
		(start 209.5 125.5)
		(end 210 125)
		(width 0.256)
		(layer "F.Cu")
		(net 1260)
	)
	(segment
		(start 243.189083 92.889689)
		(end 243.189083 96.910915)
		(width 0.1)
		(layer "F.Cu")
		(net 1260)
	)
	(segment
		(start 243.189083 96.910915)
		(end 242.525 97.574998)
		(width 0.1)
		(layer "F.Cu")
		(net 1260)
	)
	(segment
		(start 242.525 97.574998)
		(end 242.525 98.575)
		(width 0.1)
		(layer "F.Cu")
		(net 1260)
	)
	(via
		(at 243.189083 92.889689)
		(size 0.45)
		(drill 0.2)
		(layers "F.Cu" "B.Cu")
		(net 1260)
	)
	(via
		(at 210 125)
		(size 0.45)
		(drill 0.2)
		(layers "F.Cu" "B.Cu")
		(net 1260)
	)
	(segment
		(start 221.281367 94.799999)
		(end 219.706367 96.374999)
		(width 0.1)
		(layer "In3.Cu")
		(net 1260)
	)
	(segment
		(start 209.5 124.5)
		(end 210 125)
		(width 0.1)
		(layer "In3.Cu")
		(net 1260)
	)
	(segment
		(start 208.8 124.5)
		(end 209.5 124.5)
		(width 0.1)
		(layer "In3.Cu")
		(net 1260)
	)
	(segment
		(start 208.6 124.3)
		(end 208.8 124.5)
		(width 0.1)
		(layer "In3.Cu")
		(net 1260)
	)
	(segment
		(start 241.299999 94.799999)
		(end 221.281367 94.799999)
		(width 0.1)
		(layer "In3.Cu")
		(net 1260)
	)
	(segment
		(start 218.736263 96.374999)
		(end 208.6 106.511262)
		(width 0.1)
		(layer "In3.Cu")
		(net 1260)
	)
	(segment
		(start 243.189083 92.910915)
		(end 241.299999 94.799999)
		(width 0.1)
		(layer "In3.Cu")
		(net 1260)
	)
	(segment
		(start 219.706367 96.374999)
		(end 218.736263 96.374999)
		(width 0.1)
		(layer "In3.Cu")
		(net 1260)
	)
	(segment
		(start 243.189083 92.889689)
		(end 243.189083 92.910915)
		(width 0.1)
		(layer "In3.Cu")
		(net 1260)
	)
	(segment
		(start 208.6 106.511262)
		(end 208.6 124.3)
		(width 0.1)
		(layer "In3.Cu")
		(net 1260)
	)
	(segment
		(start 213.5 127.5)
		(end 214 127)
		(width 0.256)
		(layer "F.Cu")
		(net 1261)
	)
	(segment
		(start 241.899999 96.099999)
		(end 242.525 95.474998)
		(width 0.1)
		(layer "F.Cu")
		(net 1261)
	)
	(segment
		(start 241.899999 96.948999)
		(end 241.899999 96.099999)
		(width 0.1)
		(layer "F.Cu")
		(net 1261)
	)
	(segment
		(start 242.525 95.474998)
		(end 242.525 94.51)
		(width 0.1)
		(layer "F.Cu")
		(net 1261)
	)
	(via
		(at 241.899999 96.948999)
		(size 0.45)
		(drill 0.2)
		(layers "F.Cu" "B.Cu")
		(net 1261)
	)
	(via
		(at 214 127)
		(size 0.45)
		(drill 0.2)
		(layers "F.Cu" "B.Cu")
		(net 1261)
	)
	(segment
		(start 220.228421 99.999999)
		(end 216.4 103.82842)
		(width 0.1)
		(layer "In3.Cu")
		(net 1261)
	)
	(segment
		(start 221.411265 99.799999)
		(end 221.211265 99.999999)
		(width 0.1)
		(layer "In3.Cu")
		(net 1261)
	)
	(segment
		(start 241.899999 99.499999)
		(end 241.599999 99.799999)
		(width 0.1)
		(layer "In3.Cu")
		(net 1261)
	)
	(segment
		(start 241.899999 96.948999)
		(end 241.899999 99.499999)
		(width 0.1)
		(layer "In3.Cu")
		(net 1261)
	)
	(segment
		(start 221.211265 99.999999)
		(end 220.228421 99.999999)
		(width 0.1)
		(layer "In3.Cu")
		(net 1261)
	)
	(segment
		(start 214 127)
		(end 214.5 126.5)
		(width 0.1)
		(layer "In3.Cu")
		(net 1261)
	)
	(segment
		(start 216.4 125.4)
		(end 215.3 126.5)
		(width 0.1)
		(layer "In3.Cu")
		(net 1261)
	)
	(segment
		(start 214.5 126.5)
		(end 215.3 126.5)
		(width 0.1)
		(layer "In3.Cu")
		(net 1261)
	)
	(segment
		(start 241.599999 99.799999)
		(end 221.411265 99.799999)
		(width 0.1)
		(layer "In3.Cu")
		(net 1261)
	)
	(segment
		(start 216.4 103.82842)
		(end 216.4 125.4)
		(width 0.1)
		(layer "In3.Cu")
		(net 1261)
	)
	(segment
		(start 243.799999 96.574499)
		(end 243.799999 98.374499)
		(width 0.1)
		(layer "F.Cu")
		(net 1262)
	)
	(segment
		(start 211.5 125.5)
		(end 212 125)
		(width 0.256)
		(layer "F.Cu")
		(net 1262)
	)
	(via
		(at 243.799999 96.574499)
		(size 0.45)
		(drill 0.2)
		(layers "F.Cu" "B.Cu")
		(net 1262)
	)
	(via
		(at 212 125)
		(size 0.45)
		(drill 0.2)
		(layers "F.Cu" "B.Cu")
		(net 1262)
	)
	(segment
		(start 212.61 104.79)
		(end 219.425001 97.974999)
		(width 0.1)
		(layer "In3.Cu")
		(net 1262)
	)
	(segment
		(start 239.6 96.3)
		(end 240.199999 96.899999)
		(width 0.1)
		(layer "In3.Cu")
		(net 1262)
	)
	(segment
		(start 212.61 124.39)
		(end 212.61 104.79)
		(width 0.1)
		(layer "In3.Cu")
		(net 1262)
	)
	(segment
		(start 229.799999 96.199999)
		(end 230.6 97)
		(width 0.1)
		(layer "In3.Cu")
		(net 1262)
	)
	(segment
		(start 233.399998 97)
		(end 234.399998 96)
		(width 0.1)
		(layer "In3.Cu")
		(net 1262)
	)
	(segment
		(start 241.225499 96.574499)
		(end 243.799999 96.574499)
		(width 0.1)
		(layer "In3.Cu")
		(net 1262)
	)
	(segment
		(start 221.607842 96.774999)
		(end 227.424999 96.774999)
		(width 0.1)
		(layer "In3.Cu")
		(net 1262)
	)
	(segment
		(start 234.399998 96)
		(end 238.234835 96)
		(width 0.1)
		(layer "In3.Cu")
		(net 1262)
	)
	(segment
		(start 240.199999 96.899999)
		(end 240.899999 96.899999)
		(width 0.1)
		(layer "In3.Cu")
		(net 1262)
	)
	(segment
		(start 219.425001 97.974999)
		(end 220.407842 97.974999)
		(width 0.1)
		(layer "In3.Cu")
		(net 1262)
	)
	(segment
		(start 230.6 97)
		(end 233.399998 97)
		(width 0.1)
		(layer "In3.Cu")
		(net 1262)
	)
	(segment
		(start 212 125)
		(end 212.61 124.39)
		(width 0.1)
		(layer "In3.Cu")
		(net 1262)
	)
	(segment
		(start 227.424999 96.774999)
		(end 227.999999 96.199999)
		(width 0.1)
		(layer "In3.Cu")
		(net 1262)
	)
	(segment
		(start 227.999999 96.199999)
		(end 229.799999 96.199999)
		(width 0.1)
		(layer "In3.Cu")
		(net 1262)
	)
	(segment
		(start 240.899999 96.899999)
		(end 241.225499 96.574499)
		(width 0.1)
		(layer "In3.Cu")
		(net 1262)
	)
	(segment
		(start 238.234835 96)
		(end 238.534835 96.3)
		(width 0.1)
		(layer "In3.Cu")
		(net 1262)
	)
	(segment
		(start 220.407842 97.974999)
		(end 221.607842 96.774999)
		(width 0.1)
		(layer "In3.Cu")
		(net 1262)
	)
	(segment
		(start 238.534835 96.3)
		(end 239.6 96.3)
		(width 0.1)
		(layer "In3.Cu")
		(net 1262)
	)
	(segment
		(start 243.799999 94.505001)
		(end 243.795 94.51)
		(width 0.1)
		(layer "F.Cu")
		(net 1263)
	)
	(segment
		(start 210.5 127.5)
		(end 211 127)
		(width 0.256)
		(layer "F.Cu")
		(net 1263)
	)
	(segment
		(start 243.799999 93.399999)
		(end 243.799999 94.505001)
		(width 0.1)
		(layer "F.Cu")
		(net 1263)
	)
	(via
		(at 211 127)
		(size 0.45)
		(drill 0.2)
		(layers "F.Cu" "B.Cu")
		(net 1263)
	)
	(via
		(at 243.799999 93.399999)
		(size 0.45)
		(drill 0.2)
		(layers "F.Cu" "B.Cu")
		(net 1263)
	)
	(segment
		(start 221.364209 94.999999)
		(end 219.78921 96.574999)
		(width 0.1)
		(layer "In3.Cu")
		(net 1263)
	)
	(segment
		(start 209.4 105.994104)
		(end 209.4 124)
		(width 0.1)
		(layer "In3.Cu")
		(net 1263)
	)
	(segment
		(start 219.78921 96.574999)
		(end 218.819105 96.574999)
		(width 0.1)
		(layer "In3.Cu")
		(net 1263)
	)
	(segment
		(start 242.199999 94.999999)
		(end 221.364209 94.999999)
		(width 0.1)
		(layer "In3.Cu")
		(net 1263)
	)
	(segment
		(start 210.5 124.8)
		(end 210.5 126.5)
		(width 0.1)
		(layer "In3.Cu")
		(net 1263)
	)
	(segment
		(start 210.2 124.5)
		(end 210.5 124.8)
		(width 0.1)
		(layer "In3.Cu")
		(net 1263)
	)
	(segment
		(start 243.799999 93.399999)
		(end 242.199999 94.999999)
		(width 0.1)
		(layer "In3.Cu")
		(net 1263)
	)
	(segment
		(start 209.4 124)
		(end 209.9 124.5)
		(width 0.1)
		(layer "In3.Cu")
		(net 1263)
	)
	(segment
		(start 210.5 126.5)
		(end 211 127)
		(width 0.1)
		(layer "In3.Cu")
		(net 1263)
	)
	(segment
		(start 218.819105 96.574999)
		(end 209.4 105.994104)
		(width 0.1)
		(layer "In3.Cu")
		(net 1263)
	)
	(segment
		(start 209.9 124.5)
		(end 210.2 124.5)
		(width 0.1)
		(layer "In3.Cu")
		(net 1263)
	)
	(segment
		(start 210.5 124.5)
		(end 210.95 124.05)
		(width 0.256)
		(layer "F.Cu")
		(net 1264)
	)
	(segment
		(start 245.065 96.765)
		(end 244.899999 96.599999)
		(width 0.1)
		(layer "F.Cu")
		(net 1264)
	)
	(segment
		(start 210.95 124.05)
		(end 211.03 124.05)
		(width 0.256)
		(layer "F.Cu")
		(net 1264)
	)
	(segment
		(start 245.065 98.575)
		(end 245.065 96.765)
		(width 0.1)
		(layer "F.Cu")
		(net 1264)
	)
	(via
		(at 211.03 124.05)
		(size 0.45)
		(drill 0.2)
		(layers "F.Cu" "B.Cu")
		(net 1264)
	)
	(via
		(at 244.899999 96.599999)
		(size 0.45)
		(drill 0.2)
		(layers "F.Cu" "B.Cu")
		(net 1264)
	)
	(segment
		(start 210.4 105.559788)
		(end 218.984789 96.974999)
		(width 0.1)
		(layer "In3.Cu")
		(net 1264)
	)
	(segment
		(start 211.03 124.047158)
		(end 210.4 123.417158)
		(width 0.1)
		(layer "In3.Cu")
		(net 1264)
	)
	(segment
		(start 221.529893 95.399999)
		(end 239.199999 95.399999)
		(width 0.1)
		(layer "In3.Cu")
		(net 1264)
	)
	(segment
		(start 239.199999 95.399999)
		(end 240.399999 96.599999)
		(width 0.1)
		(layer "In3.Cu")
		(net 1264)
	)
	(segment
		(start 240.399999 96.599999)
		(end 240.799999 96.599999)
		(width 0.1)
		(layer "In3.Cu")
		(net 1264)
	)
	(segment
		(start 219.954894 96.974999)
		(end 221.529893 95.399999)
		(width 0.1)
		(layer "In3.Cu")
		(net 1264)
	)
	(segment
		(start 240.799999 96.599999)
		(end 241.199999 96.199999)
		(width 0.1)
		(layer "In3.Cu")
		(net 1264)
	)
	(segment
		(start 218.984789 96.974999)
		(end 219.954894 96.974999)
		(width 0.1)
		(layer "In3.Cu")
		(net 1264)
	)
	(segment
		(start 211.03 124.05)
		(end 211.03 124.047158)
		(width 0.1)
		(layer "In3.Cu")
		(net 1264)
	)
	(segment
		(start 210.4 123.417158)
		(end 210.4 105.559788)
		(width 0.1)
		(layer "In3.Cu")
		(net 1264)
	)
	(segment
		(start 241.199999 96.199999)
		(end 244.499999 96.199999)
		(width 0.1)
		(layer "In3.Cu")
		(net 1264)
	)
	(segment
		(start 244.499999 96.199999)
		(end 244.899999 96.599999)
		(width 0.1)
		(layer "In3.Cu")
		(net 1264)
	)
	(segment
		(start 245.065 92.834998)
		(end 245.099999 92.799999)
		(width 0.1)
		(layer "F.Cu")
		(net 1265)
	)
	(segment
		(start 245.065 94.51)
		(end 245.065 92.834998)
		(width 0.1)
		(layer "F.Cu")
		(net 1265)
	)
	(segment
		(start 205.5 124.5)
		(end 206 124)
		(width 0.256)
		(layer "F.Cu")
		(net 1265)
	)
	(via
		(at 245.099999 92.799999)
		(size 0.45)
		(drill 0.2)
		(layers "F.Cu" "B.Cu")
		(net 1265)
	)
	(via
		(at 206 124)
		(size 0.45)
		(drill 0.2)
		(layers "F.Cu" "B.Cu")
		(net 1265)
	)
	(segment
		(start 206 124)
		(end 205.6 123.6)
		(width 0.1)
		(layer "In3.Cu")
		(net 1265)
	)
	(segment
		(start 205.6 123.6)
		(end 205.6 117.64)
		(width 0.1)
		(layer "In3.Cu")
		(net 1265)
	)
	(segment
		(start 206.12 107.29)
		(end 218.585001 94.824999)
		(width 0.1)
		(layer "In3.Cu")
		(net 1265)
	)
	(segment
		(start 219.799999 94.824999)
		(end 220.824999 93.799999)
		(width 0.1)
		(layer "In3.Cu")
		(net 1265)
	)
	(segment
		(start 220.824999 93.799999)
		(end 234.717157 93.799999)
		(width 0.1)
		(layer "In3.Cu")
		(net 1265)
	)
	(segment
		(start 205.6 117.64)
		(end 206.12 117.12)
		(width 0.1)
		(layer "In3.Cu")
		(net 1265)
	)
	(segment
		(start 236.017157 92.499999)
		(end 244.799999 92.499999)
		(width 0.1)
		(layer "In3.Cu")
		(net 1265)
	)
	(segment
		(start 206.12 117.12)
		(end 206.12 107.29)
		(width 0.1)
		(layer "In3.Cu")
		(net 1265)
	)
	(segment
		(start 244.799999 92.499999)
		(end 245.099999 92.799999)
		(width 0.1)
		(layer "In3.Cu")
		(net 1265)
	)
	(segment
		(start 234.717157 93.799999)
		(end 236.017157 92.499999)
		(width 0.1)
		(layer "In3.Cu")
		(net 1265)
	)
	(segment
		(start 218.585001 94.824999)
		(end 219.799999 94.824999)
		(width 0.1)
		(layer "In3.Cu")
		(net 1265)
	)
	(segment
		(start 220.84 89.459998)
		(end 221.299999 88.999999)
		(width 0.182)
		(layer "F.Cu")
		(net 1266)
	)
	(segment
		(start 220.84 90.2875)
		(end 220.84 89.459998)
		(width 0.182)
		(layer "F.Cu")
		(net 1266)
	)
	(segment
		(start 211.5 118.5)
		(end 212 118)
		(width 0.256)
		(layer "F.Cu")
		(net 1266)
	)
	(via
		(at 212 118)
		(size 0.45)
		(drill 0.2)
		(layers "F.Cu" "B.Cu")
		(net 1266)
	)
	(via
		(at 221.299999 88.999999)
		(size 0.45)
		(drill 0.2)
		(layers "F.Cu" "B.Cu")
		(net 1266)
	)
	(segment
		(start 212.84 116.6225)
		(end 212.625 116.8375)
		(width 0.1)
		(layer "In5.Cu")
		(net 1266)
	)
	(segment
		(start 221.299999 88.999999)
		(end 221.099998 89.2)
		(width 0.1)
		(layer "In5.Cu")
		(net 1266)
	)
	(segment
		(start 214 99.75)
		(end 213.7 100.05)
		(width 0.1)
		(layer "In5.Cu")
		(net 1266)
	)
	(segment
		(start 215.95 88.45)
		(end 214.6 88.45)
		(width 0.1)
		(layer "In5.Cu")
		(net 1266)
	)
	(segment
		(start 213.7 90.2)
		(end 214 90.5)
		(width 0.1)
		(layer "In5.Cu")
		(net 1266)
	)
	(segment
		(start 213.7 100.05)
		(end 213.7 114.192169)
		(width 0.1)
		(layer "In5.Cu")
		(net 1266)
	)
	(segment
		(start 212.625 117.375)
		(end 212 118)
		(width 0.1)
		(layer "In5.Cu")
		(net 1266)
	)
	(segment
		(start 213.14 116.6225)
		(end 212.84 116.6225)
		(width 0.1)
		(layer "In5.Cu")
		(net 1266)
	)
	(segment
		(start 214.6 88.45)
		(end 213.7 89.35)
		(width 0.1)
		(layer "In5.Cu")
		(net 1266)
	)
	(segment
		(start 216.7 89.2)
		(end 215.95 88.45)
		(width 0.1)
		(layer "In5.Cu")
		(net 1266)
	)
	(segment
		(start 213.625 114.267169)
		(end 213.625 116.1375)
		(width 0.1)
		(layer "In5.Cu")
		(net 1266)
	)
	(segment
		(start 212.625 116.8375)
		(end 212.625 117.375)
		(width 0.1)
		(layer "In5.Cu")
		(net 1266)
	)
	(segment
		(start 213.7 89.35)
		(end 213.7 90.2)
		(width 0.1)
		(layer "In5.Cu")
		(net 1266)
	)
	(segment
		(start 213.625 116.1375)
		(end 213.14 116.6225)
		(width 0.1)
		(layer "In5.Cu")
		(net 1266)
	)
	(segment
		(start 221.099998 89.2)
		(end 216.7 89.2)
		(width 0.1)
		(layer "In5.Cu")
		(net 1266)
	)
	(segment
		(start 214 90.5)
		(end 214 99.75)
		(width 0.1)
		(layer "In5.Cu")
		(net 1266)
	)
	(segment
		(start 213.7 114.192169)
		(end 213.625 114.267169)
		(width 0.1)
		(layer "In5.Cu")
		(net 1266)
	)
	(segment
		(start 214.2825 114.4225)
		(end 214 114.4225)
		(width 0.256)
		(layer "F.Cu")
		(net 1267)
	)
	(segment
		(start 222.11 90.2875)
		(end 222.11 89.11)
		(width 0.182)
		(layer "F.Cu")
		(net 1267)
	)
	(segment
		(start 214.5 115.5)
		(end 214.5 114.64)
		(width 0.256)
		(layer "F.Cu")
		(net 1267)
	)
	(segment
		(start 222.11 89.11)
		(end 222.099999 89.099999)
		(width 0.182)
		(layer "F.Cu")
		(net 1267)
	)
	(segment
		(start 214.5 114.64)
		(end 214.2825 114.4225)
		(width 0.256)
		(layer "F.Cu")
		(net 1267)
	)
	(via
		(at 222.099999 89.099999)
		(size 0.45)
		(drill 0.2)
		(layers "F.Cu" "B.Cu")
		(net 1267)
	)
	(via
		(at 214 114.4225)
		(size 0.45)
		(drill 0.2)
		(layers "F.Cu" "B.Cu")
		(net 1267)
	)
	(segment
		(start 214.25 89.1)
		(end 214.275 89.075)
		(width 0.1)
		(layer "In5.Cu")
		(net 1267)
	)
	(segment
		(start 214.25 99.8)
		(end 214.25 89.1)
		(width 0.1)
		(layer "In5.Cu")
		(net 1267)
	)
	(segment
		(start 214 100.05)
		(end 214.25 99.8)
		(width 0.1)
		(layer "In5.Cu")
		(net 1267)
	)
	(segment
		(start 214.7 88.65)
		(end 215.85 88.65)
		(width 0.1)
		(layer "In5.Cu")
		(net 1267)
	)
	(segment
		(start 215.85 88.65)
		(end 216.6 89.4)
		(width 0.1)
		(layer "In5.Cu")
		(net 1267)
	)
	(segment
		(start 214 114.4225)
		(end 214 100.05)
		(width 0.1)
		(layer "In5.Cu")
		(net 1267)
	)
	(segment
		(start 221.799998 89.4)
		(end 222.099999 89.099999)
		(width 0.1)
		(layer "In5.Cu")
		(net 1267)
	)
	(segment
		(start 214.275 89.075)
		(end 214.7 88.65)
		(width 0.1)
		(layer "In5.Cu")
		(net 1267)
	)
	(segment
		(start 216.6 89.4)
		(end 221.799998 89.4)
		(width 0.1)
		(layer "In5.Cu")
		(net 1267)
	)
	(segment
		(start 223.38 90.2875)
		(end 223.38 91.9375)
		(width 0.182)
		(layer "F.Cu")
		(net 1268)
	)
	(segment
		(start 209.5 122.5)
		(end 210 122)
		(width 0.256)
		(layer "F.Cu")
		(net 1268)
	)
	(via
		(at 223.5 91.9)
		(size 0.45)
		(drill 0.2)
		(layers "F.Cu" "B.Cu")
		(net 1268)
	)
	(via
		(at 210 122)
		(size 0.45)
		(drill 0.2)
		(layers "F.Cu" "B.Cu")
		(net 1268)
	)
	(segment
		(start 216.9 94.35)
		(end 219.35 91.9)
		(width 0.1)
		(layer "In5.Cu")
		(net 1268)
	)
	(segment
		(start 210.4 121.6)
		(end 215.7 121.6)
		(width 0.1)
		(layer "In5.Cu")
		(net 1268)
	)
	(segment
		(start 215.7 121.6)
		(end 216.9 120.4)
		(width 0.1)
		(layer "In5.Cu")
		(net 1268)
	)
	(segment
		(start 216.9 120.4)
		(end 216.9 94.35)
		(width 0.1)
		(layer "In5.Cu")
		(net 1268)
	)
	(segment
		(start 219.35 91.9)
		(end 223.5 91.9)
		(width 0.1)
		(layer "In5.Cu")
		(net 1268)
	)
	(segment
		(start 210 122)
		(end 210.4 121.6)
		(width 0.1)
		(layer "In5.Cu")
		(net 1268)
	)
	(segment
		(start 210.5 117.5)
		(end 210.970773 117.970773)
		(width 0.256)
		(layer "F.Cu")
		(net 1269)
	)
	(segment
		(start 210.970773 117.970773)
		(end 211 117.970773)
		(width 0.256)
		(layer "F.Cu")
		(net 1269)
	)
	(via
		(at 211 117.970773)
		(size 0.45)
		(drill 0.2)
		(layers "F.Cu" "B.Cu")
		(net 1269)
	)
	(via
		(at 223.299999 86.399999)
		(size 0.45)
		(drill 0.2)
		(layers "F.Cu" "B.Cu")
		(net 1269)
	)
	(segment
		(start 213.2 86)
		(end 213.6 86.4)
		(width 0.1)
		(layer "In5.Cu")
		(net 1269)
	)
	(segment
		(start 210.7 114.769669)
		(end 210.7 89.5)
		(width 0.1)
		(layer "In5.Cu")
		(net 1269)
	)
	(segment
		(start 213.6 86.4)
		(end 223.299999 86.399999)
		(width 0.1)
		(layer "In5.Cu")
		(net 1269)
	)
	(segment
		(start 210.7 89.5)
		(end 211.875 88.325)
		(width 0.1)
		(layer "In5.Cu")
		(net 1269)
	)
	(segment
		(start 210.625 114.844669)
		(end 210.7 114.769669)
		(width 0.1)
		(layer "In5.Cu")
		(net 1269)
	)
	(segment
		(start 212.125 86)
		(end 213.2 86)
		(width 0.1)
		(layer "In5.Cu")
		(net 1269)
	)
	(segment
		(start 211 117.970773)
		(end 210.625 117.595773)
		(width 0.1)
		(layer "In5.Cu")
		(net 1269)
	)
	(segment
		(start 211.875 88.325)
		(end 211.875 86.25)
		(width 0.1)
		(layer "In5.Cu")
		(net 1269)
	)
	(segment
		(start 210.625 117.595773)
		(end 210.625 114.844669)
		(width 0.1)
		(layer "In5.Cu")
		(net 1269)
	)
	(segment
		(start 211.875 86.25)
		(end 212.125 86)
		(width 0.1)
		(layer "In5.Cu")
		(net 1269)
	)
	(segment
		(start 213.5 119.5)
		(end 214 119)
		(width 0.256)
		(layer "F.Cu")
		(net 1270)
	)
	(via
		(at 224.7 89.6)
		(size 0.45)
		(drill 0.2)
		(layers "F.Cu" "B.Cu")
		(net 1270)
	)
	(via
		(at 214 119)
		(size 0.45)
		(drill 0.2)
		(layers "F.Cu" "B.Cu")
		(net 1270)
	)
	(segment
		(start 214.4 116.58)
		(end 214.4 118.6)
		(width 0.1)
		(layer "In5.Cu")
		(net 1270)
	)
	(segment
		(start 214.8 91.45)
		(end 216.4255 89.8245)
		(width 0.1)
		(layer "In5.Cu")
		(net 1270)
	)
	(segment
		(start 224.7 89.6)
		(end 224.4755 89.8245)
		(width 0.1)
		(layer "In5.Cu")
		(net 1270)
	)
	(segment
		(start 214.4 118.6)
		(end 214 119)
		(width 0.1)
		(layer "In5.Cu")
		(net 1270)
	)
	(segment
		(start 214.8 91.45)
		(end 214.8 116.18)
		(width 0.1)
		(layer "In5.Cu")
		(net 1270)
	)
	(segment
		(start 214.8 116.18)
		(end 214.4 116.58)
		(width 0.1)
		(layer "In5.Cu")
		(net 1270)
	)
	(segment
		(start 224.4755 89.8245)
		(end 216.4255 89.8245)
		(width 0.1)
		(layer "In5.Cu")
		(net 1270)
	)
	(segment
		(start 207.5 115.5)
		(end 208 115)
		(width 0.256)
		(layer "F.Cu")
		(net 1271)
	)
	(segment
		(start 224.65 84.509999)
		(end 224.65 86.2225)
		(width 0.1)
		(layer "F.Cu")
		(net 1271)
	)
	(segment
		(start 224.64 84.499999)
		(end 224.65 84.509999)
		(width 0.1)
		(layer "F.Cu")
		(net 1271)
	)
	(via
		(at 224.64 84.499999)
		(size 0.45)
		(drill 0.2)
		(layers "F.Cu" "B.Cu")
		(net 1271)
	)
	(via
		(at 208 115)
		(size 0.45)
		(drill 0.2)
		(layers "F.Cu" "B.Cu")
		(net 1271)
	)
	(segment
		(start 208.15 85.85)
		(end 208.15 114.65)
		(width 0.1)
		(layer "In5.Cu")
		(net 1271)
	)
	(segment
		(start 210.13 83.87)
		(end 208.15 85.85)
		(width 0.1)
		(layer "In5.Cu")
		(net 1271)
	)
	(segment
		(start 224.64 84.499999)
		(end 224.010001 83.87)
		(width 0.1)
		(layer "In5.Cu")
		(net 1271)
	)
	(segment
		(start 208 114.8)
		(end 208 115)
		(width 0.1)
		(layer "In5.Cu")
		(net 1271)
	)
	(segment
		(start 208.15 114.65)
		(end 208 114.8)
		(width 0.1)
		(layer "In5.Cu")
		(net 1271)
	)
	(segment
		(start 224.010001 83.87)
		(end 210.13 83.87)
		(width 0.1)
		(layer "In5.Cu")
		(net 1271)
	)
	(segment
		(start 212.5 115.5)
		(end 213 115)
		(width 0.256)
		(layer "F.Cu")
		(net 1272)
	)
	(segment
		(start 225.312749 88.625499)
		(end 225.92 89.23275)
		(width 0.1)
		(layer "F.Cu")
		(net 1272)
	)
	(segment
		(start 225.299999 88.625499)
		(end 225.312749 88.625499)
		(width 0.1)
		(layer "F.Cu")
		(net 1272)
	)
	(segment
		(start 225.92 89.23275)
		(end 225.92 90.2225)
		(width 0.1)
		(layer "F.Cu")
		(net 1272)
	)
	(via
		(at 213 115)
		(size 0.45)
		(drill 0.2)
		(layers "F.Cu" "B.Cu")
		(net 1272)
	)
	(via
		(at 225.299999 88.625499)
		(size 0.45)
		(drill 0.2)
		(layers "F.Cu" "B.Cu")
		(net 1272)
	)
	(segment
		(start 225.0745 88.4)
		(end 225.299999 88.625499)
		(width 0.1)
		(layer "In5.Cu")
		(net 1272)
	)
	(segment
		(start 213.55 99.35)
		(end 213.55 90.9)
		(width 0.1)
		(layer "In5.Cu")
		(net 1272)
	)
	(segment
		(start 216.9 88.75)
		(end 220.65 88.75)
		(width 0.1)
		(layer "In5.Cu")
		(net 1272)
	)
	(segment
		(start 220.65 88.75)
		(end 221 88.4)
		(width 0.1)
		(layer "In5.Cu")
		(net 1272)
	)
	(segment
		(start 213 115)
		(end 213 99.9)
		(width 0.1)
		(layer "In5.Cu")
		(net 1272)
	)
	(segment
		(start 216.2 88.05)
		(end 216.9 88.75)
		(width 0.1)
		(layer "In5.Cu")
		(net 1272)
	)
	(segment
		(start 212.9 89.55)
		(end 214.4 88.05)
		(width 0.1)
		(layer "In5.Cu")
		(net 1272)
	)
	(segment
		(start 213.55 90.9)
		(end 212.9 90.25)
		(width 0.1)
		(layer "In5.Cu")
		(net 1272)
	)
	(segment
		(start 214.4 88.05)
		(end 216.2 88.05)
		(width 0.1)
		(layer "In5.Cu")
		(net 1272)
	)
	(segment
		(start 213 99.9)
		(end 213.55 99.35)
		(width 0.1)
		(layer "In5.Cu")
		(net 1272)
	)
	(segment
		(start 212.9 90.25)
		(end 212.9 89.55)
		(width 0.1)
		(layer "In5.Cu")
		(net 1272)
	)
	(segment
		(start 221 88.4)
		(end 225.0745 88.4)
		(width 0.1)
		(layer "In5.Cu")
		(net 1272)
	)
	(segment
		(start 211.5 115.5)
		(end 212 115)
		(width 0.256)
		(layer "F.Cu")
		(net 1273)
	)
	(segment
		(start 226.399999 87.999999)
		(end 225.92 87.52)
		(width 0.1)
		(layer "F.Cu")
		(net 1273)
	)
	(segment
		(start 225.92 87.52)
		(end 225.92 86.2225)
		(width 0.1)
		(layer "F.Cu")
		(net 1273)
	)
	(via
		(at 226.399999 87.999999)
		(size 0.45)
		(drill 0.2)
		(layers "F.Cu" "B.Cu")
		(net 1273)
	)
	(via
		(at 212 115)
		(size 0.45)
		(drill 0.2)
		(layers "F.Cu" "B.Cu")
		(net 1273)
	)
	(segment
		(start 211.7 89.85)
		(end 214.1 87.45)
		(width 0.1)
		(layer "In5.Cu")
		(net 1273)
	)
	(segment
		(start 216.95 87.725)
		(end 226.125 87.725)
		(width 0.1)
		(layer "In5.Cu")
		(net 1273)
	)
	(segment
		(start 226.125 87.725)
		(end 226.399999 87.999999)
		(width 0.1)
		(layer "In5.Cu")
		(net 1273)
	)
	(segment
		(start 211.7 99.6)
		(end 211.7 89.85)
		(width 0.1)
		(layer "In5.Cu")
		(net 1273)
	)
	(segment
		(start 212 99.9)
		(end 211.7 99.6)
		(width 0.1)
		(layer "In5.Cu")
		(net 1273)
	)
	(segment
		(start 214.1 87.45)
		(end 216.675 87.45)
		(width 0.1)
		(layer "In5.Cu")
		(net 1273)
	)
	(segment
		(start 212 115)
		(end 212 99.9)
		(width 0.1)
		(layer "In5.Cu")
		(net 1273)
	)
	(segment
		(start 216.675 87.45)
		(end 216.95 87.725)
		(width 0.1)
		(layer "In5.Cu")
		(net 1273)
	)
	(segment
		(start 228.2 88.1)
		(end 228.2 88.199999)
		(width 0.1)
		(layer "F.Cu")
		(net 1274)
	)
	(segment
		(start 227.19 89.209999)
		(end 227.19 90.2875)
		(width 0.1)
		(layer "F.Cu")
		(net 1274)
	)
	(segment
		(start 228.2 88.199999)
		(end 227.19 89.209999)
		(width 0.1)
		(layer "F.Cu")
		(net 1274)
	)
	(segment
		(start 210.5 115.5)
		(end 211 115)
		(width 0.256)
		(layer "F.Cu")
		(net 1274)
	)
	(via
		(at 228.2 88.1)
		(size 0.45)
		(drill 0.2)
		(layers "F.Cu" "B.Cu")
		(net 1274)
	)
	(via
		(at 211 115)
		(size 0.45)
		(drill 0.2)
		(layers "F.Cu" "B.Cu")
		(net 1274)
	)
	(segment
		(start 227.175 87.075)
		(end 217.275 87.075)
		(width 0.1)
		(layer "In5.Cu")
		(net 1274)
	)
	(segment
		(start 228.2 88.1)
		(end 227.175 87.075)
		(width 0.1)
		(layer "In5.Cu")
		(net 1274)
	)
	(segment
		(start 211 89.6)
		(end 211 115)
		(width 0.1)
		(layer "In5.Cu")
		(net 1274)
	)
	(segment
		(start 217 86.8)
		(end 213.8 86.8)
		(width 0.1)
		(layer "In5.Cu")
		(net 1274)
	)
	(segment
		(start 213.8 86.8)
		(end 211 89.6)
		(width 0.1)
		(layer "In5.Cu")
		(net 1274)
	)
	(segment
		(start 217.275 87.075)
		(end 217 86.8)
		(width 0.1)
		(layer "In5.Cu")
		(net 1274)
	)
	(segment
		(start 226.899999 88.299999)
		(end 227.19 88.009998)
		(width 0.1)
		(layer "F.Cu")
		(net 1275)
	)
	(segment
		(start 227.19 88.009998)
		(end 227.19 86.2225)
		(width 0.1)
		(layer "F.Cu")
		(net 1275)
	)
	(segment
		(start 211.5 116.5)
		(end 212 116)
		(width 0.256)
		(layer "F.Cu")
		(net 1275)
	)
	(via
		(at 226.899999 88.299999)
		(size 0.45)
		(drill 0.2)
		(layers "F.Cu" "B.Cu")
		(net 1275)
	)
	(via
		(at 212 116)
		(size 0.45)
		(drill 0.2)
		(layers "F.Cu" "B.Cu")
		(net 1275)
	)
	(segment
		(start 212.3 114.769669)
		(end 212.3 99.85)
		(width 0.1)
		(layer "In5.Cu")
		(net 1275)
	)
	(segment
		(start 216.85 87.95)
		(end 225.8 87.95)
		(width 0.1)
		(layer "In5.Cu")
		(net 1275)
	)
	(segment
		(start 226.249999 88.399999)
		(end 226.799999 88.399999)
		(width 0.1)
		(layer "In5.Cu")
		(net 1275)
	)
	(segment
		(start 226.799999 88.399999)
		(end 226.899999 88.299999)
		(width 0.1)
		(layer "In5.Cu")
		(net 1275)
	)
	(segment
		(start 212.3 99.85)
		(end 211.95 99.5)
		(width 0.1)
		(layer "In5.Cu")
		(net 1275)
	)
	(segment
		(start 212.375 114.844669)
		(end 212.3 114.769669)
		(width 0.1)
		(layer "In5.Cu")
		(net 1275)
	)
	(segment
		(start 212.375 115.625)
		(end 212.375 114.844669)
		(width 0.1)
		(layer "In5.Cu")
		(net 1275)
	)
	(segment
		(start 214.2 87.65)
		(end 216.55 87.65)
		(width 0.1)
		(layer "In5.Cu")
		(net 1275)
	)
	(segment
		(start 211.95 99.5)
		(end 211.95 89.9)
		(width 0.1)
		(layer "In5.Cu")
		(net 1275)
	)
	(segment
		(start 212 116)
		(end 212.375 115.625)
		(width 0.1)
		(layer "In5.Cu")
		(net 1275)
	)
	(segment
		(start 225.8 87.95)
		(end 226.249999 88.399999)
		(width 0.1)
		(layer "In5.Cu")
		(net 1275)
	)
	(segment
		(start 216.55 87.65)
		(end 216.85 87.95)
		(width 0.1)
		(layer "In5.Cu")
		(net 1275)
	)
	(segment
		(start 211.95 89.9)
		(end 214.2 87.65)
		(width 0.1)
		(layer "In5.Cu")
		(net 1275)
	)
	(segment
		(start 209.975 117.025)
		(end 209.5 117.5)
		(width 0.256)
		(layer "F.Cu")
		(net 1276)
	)
	(segment
		(start 209.975 117)
		(end 209.975 117.025)
		(width 0.256)
		(layer "F.Cu")
		(net 1276)
	)
	(via
		(at 209.975 117)
		(size 0.45)
		(drill 0.2)
		(layers "F.Cu" "B.Cu")
		(net 1276)
	)
	(via
		(at 228.399999 85.799999)
		(size 0.45)
		(drill 0.2)
		(layers "F.Cu" "B.Cu")
		(net 1276)
	)
	(segment
		(start 209.975 117)
		(end 209.575 116.6)
		(width 0.1)
		(layer "In5.Cu")
		(net 1276)
	)
	(segment
		(start 209.575 116.6)
		(end 209.575 114.675)
		(width 0.1)
		(layer "In5.Cu")
		(net 1276)
	)
	(segment
		(start 228.1225 85.5225)
		(end 228.399999 85.799999)
		(width 0.1)
		(layer "In5.Cu")
		(net 1276)
	)
	(segment
		(start 222.0625 85.5225)
		(end 228.1225 85.5225)
		(width 0.1)
		(layer "In5.Cu")
		(net 1276)
	)
	(segment
		(start 221.21 84.67)
		(end 222.0625 85.5225)
		(width 0.1)
		(layer "In5.Cu")
		(net 1276)
	)
	(segment
		(start 209.3 86.4)
		(end 211.03 84.67)
		(width 0.1)
		(layer "In5.Cu")
		(net 1276)
	)
	(segment
		(start 209.575 114.675)
		(end 209.3 114.4)
		(width 0.1)
		(layer "In5.Cu")
		(net 1276)
	)
	(segment
		(start 209.3 114.4)
		(end 209.3 86.4)
		(width 0.1)
		(layer "In5.Cu")
		(net 1276)
	)
	(segment
		(start 211.03 84.67)
		(end 221.21 84.67)
		(width 0.1)
		(layer "In5.Cu")
		(net 1276)
	)
	(segment
		(start 229.74 89.099999)
		(end 229.73 89.109999)
		(width 0.1)
		(layer "F.Cu")
		(net 1277)
	)
	(segment
		(start 229.73 89.109999)
		(end 229.73 90.2875)
		(width 0.1)
		(layer "F.Cu")
		(net 1277)
	)
	(segment
		(start 212.5 116.5)
		(end 213 116)
		(width 0.256)
		(layer "F.Cu")
		(net 1277)
	)
	(via
		(at 229.74 89.099999)
		(size 0.45)
		(drill 0.2)
		(layers "F.Cu" "B.Cu")
		(net 1277)
	)
	(via
		(at 213 116)
		(size 0.45)
		(drill 0.2)
		(layers "F.Cu" "B.Cu")
		(net 1277)
	)
	(segment
		(start 220.7 89)
		(end 221.1 88.6)
		(width 0.1)
		(layer "In5.Cu")
		(net 1277)
	)
	(segment
		(start 224.425 89.025)
		(end 225.007842 89.025)
		(width 0.1)
		(layer "In5.Cu")
		(net 1277)
	)
	(segment
		(start 229.54 89.299999)
		(end 229.74 89.099999)
		(width 0.1)
		(layer "In5.Cu")
		(net 1277)
	)
	(segment
		(start 213.375 115.625)
		(end 213.375 114.844669)
		(width 0.1)
		(layer "In5.Cu")
		(net 1277)
	)
	(segment
		(start 213 116)
		(end 213.375 115.625)
		(width 0.1)
		(layer "In5.Cu")
		(net 1277)
	)
	(segment
		(start 221.1 88.6)
		(end 224 88.6)
		(width 0.1)
		(layer "In5.Cu")
		(net 1277)
	)
	(segment
		(start 213.375 114.844669)
		(end 213.3 114.769669)
		(width 0.1)
		(layer "In5.Cu")
		(net 1277)
	)
	(segment
		(start 214.5 88.25)
		(end 216.05 88.25)
		(width 0.1)
		(layer "In5.Cu")
		(net 1277)
	)
	(segment
		(start 213.3 90.35)
		(end 213.3 89.45)
		(width 0.1)
		(layer "In5.Cu")
		(net 1277)
	)
	(segment
		(start 213.75 99.5)
		(end 213.75 90.8)
		(width 0.1)
		(layer "In5.Cu")
		(net 1277)
	)
	(segment
		(start 216.8 89)
		(end 220.7 89)
		(width 0.1)
		(layer "In5.Cu")
		(net 1277)
	)
	(segment
		(start 213.3 99.95)
		(end 213.75 99.5)
		(width 0.1)
		(layer "In5.Cu")
		(net 1277)
	)
	(segment
		(start 213.75 90.8)
		(end 213.3 90.35)
		(width 0.1)
		(layer "In5.Cu")
		(net 1277)
	)
	(segment
		(start 225.282841 89.299999)
		(end 229.54 89.299999)
		(width 0.1)
		(layer "In5.Cu")
		(net 1277)
	)
	(segment
		(start 216.05 88.25)
		(end 216.8 89)
		(width 0.1)
		(layer "In5.Cu")
		(net 1277)
	)
	(segment
		(start 213.3 114.769669)
		(end 213.3 99.95)
		(width 0.1)
		(layer "In5.Cu")
		(net 1277)
	)
	(segment
		(start 225.007842 89.025)
		(end 225.282841 89.299999)
		(width 0.1)
		(layer "In5.Cu")
		(net 1277)
	)
	(segment
		(start 213.3 89.45)
		(end 214.5 88.25)
		(width 0.1)
		(layer "In5.Cu")
		(net 1277)
	)
	(segment
		(start 224 88.6)
		(end 224.425 89.025)
		(width 0.1)
		(layer "In5.Cu")
		(net 1277)
	)
	(segment
		(start 209.001766 115.998234)
		(end 208.5 116.5)
		(width 0.256)
		(layer "F.Cu")
		(net 1278)
	)
	(segment
		(start 209.013946 115.998234)
		(end 209.001766 115.998234)
		(width 0.256)
		(layer "F.Cu")
		(net 1278)
	)
	(via
		(at 209.013946 115.998234)
		(size 0.45)
		(drill 0.2)
		(layers "F.Cu" "B.Cu")
		(net 1278)
	)
	(via
		(at 229.699999 85.799999)
		(size 0.45)
		(drill 0.2)
		(layers "F.Cu" "B.Cu")
		(net 1278)
	)
	(segment
		(start 209.375 114.844669)
		(end 209.05 114.519669)
		(width 0.1)
		(layer "In5.Cu")
		(net 1278)
	)
	(segment
		(start 222.15 85.31)
		(end 229.21 85.31)
		(width 0.1)
		(layer "In5.Cu")
		(net 1278)
	)
	(segment
		(start 229.21 85.31)
		(end 229.699999 85.799999)
		(width 0.1)
		(layer "In5.Cu")
		(net 1278)
	)
	(segment
		(start 209.013946 115.998234)
		(end 209.375 115.63718)
		(width 0.1)
		(layer "In5.Cu")
		(net 1278)
	)
	(segment
		(start 209.375 115.63718)
		(end 209.375 114.844669)
		(width 0.1)
		(layer "In5.Cu")
		(net 1278)
	)
	(segment
		(start 210.947158 84.47)
		(end 221.31 84.47)
		(width 0.1)
		(layer "In5.Cu")
		(net 1278)
	)
	(segment
		(start 209.05 86.367158)
		(end 210.947158 84.47)
		(width 0.1)
		(layer "In5.Cu")
		(net 1278)
	)
	(segment
		(start 209.05 114.519669)
		(end 209.05 86.367158)
		(width 0.1)
		(layer "In5.Cu")
		(net 1278)
	)
	(segment
		(start 221.31 84.47)
		(end 222.15 85.31)
		(width 0.1)
		(layer "In5.Cu")
		(net 1278)
	)
	(segment
		(start 213.98 121.02)
		(end 214.025 121.02)
		(width 0.256)
		(layer "F.Cu")
		(net 1279)
	)
	(segment
		(start 213.5 121.5)
		(end 213.98 121.02)
		(width 0.256)
		(layer "F.Cu")
		(net 1279)
	)
	(via
		(at 214.025 121.02)
		(size 0.45)
		(drill 0.2)
		(layers "F.Cu" "B.Cu")
		(net 1279)
	)
	(via
		(at 231 91.6)
		(size 0.45)
		(drill 0.2)
		(layers "F.Cu" "B.Cu")
		(net 1279)
	)
	(segment
		(start 216.6 120.3)
		(end 216.6 94.15)
		(width 0.1)
		(layer "In5.Cu")
		(net 1279)
	)
	(segment
		(start 230.9 91.5)
		(end 231 91.6)
		(width 0.1)
		(layer "In5.Cu")
		(net 1279)
	)
	(segment
		(start 216.6 94.15)
		(end 219.25 91.5)
		(width 0.1)
		(layer "In5.Cu")
		(net 1279)
	)
	(segment
		(start 214.405 121.4)
		(end 215.5 121.4)
		(width 0.1)
		(layer "In5.Cu")
		(net 1279)
	)
	(segment
		(start 215.5 121.4)
		(end 216.6 120.3)
		(width 0.1)
		(layer "In5.Cu")
		(net 1279)
	)
	(segment
		(start 219.25 91.5)
		(end 230.9 91.5)
		(width 0.1)
		(layer "In5.Cu")
		(net 1279)
	)
	(segment
		(start 214.025 121.02)
		(end 214.405 121.4)
		(width 0.1)
		(layer "In5.Cu")
		(net 1279)
	)
	(segment
		(start 208.5 117.5)
		(end 209 117)
		(width 0.256)
		(layer "F.Cu")
		(net 1280)
	)
	(via
		(at 230.999999 85.799999)
		(size 0.45)
		(drill 0.2)
		(layers "F.Cu" "B.Cu")
		(net 1280)
	)
	(via
		(at 209 117)
		(size 0.45)
		(drill 0.2)
		(layers "F.Cu" "B.Cu")
		(net 1280)
	)
	(segment
		(start 208.75 114.719669)
		(end 208.75 86.25)
		(width 0.1)
		(layer "In5.Cu")
		(net 1280)
	)
	(segment
		(start 208.625 114.844669)
		(end 208.75 114.719669)
		(width 0.1)
		(layer "In5.Cu")
		(net 1280)
	)
	(segment
		(start 222.23 85.1)
		(end 230.3 85.1)
		(width 0.1)
		(layer "In5.Cu")
		(net 1280)
	)
	(segment
		(start 208.75 86.25)
		(end 210.73 84.27)
		(width 0.1)
		(layer "In5.Cu")
		(net 1280)
	)
	(segment
		(start 230.3 85.1)
		(end 230.999999 85.799999)
		(width 0.1)
		(layer "In5.Cu")
		(net 1280)
	)
	(segment
		(start 221.4 84.27)
		(end 222.23 85.1)
		(width 0.1)
		(layer "In5.Cu")
		(net 1280)
	)
	(segment
		(start 208.625 116.625)
		(end 208.625 114.844669)
		(width 0.1)
		(layer "In5.Cu")
		(net 1280)
	)
	(segment
		(start 209 117)
		(end 208.625 116.625)
		(width 0.1)
		(layer "In5.Cu")
		(net 1280)
	)
	(segment
		(start 210.73 84.27)
		(end 221.4 84.27)
		(width 0.1)
		(layer "In5.Cu")
		(net 1280)
	)
	(segment
		(start 214.5 120.5)
		(end 215 120)
		(width 0.256)
		(layer "F.Cu")
		(net 1281)
	)
	(via
		(at 215 120)
		(size 0.45)
		(drill 0.2)
		(layers "F.Cu" "B.Cu")
		(net 1281)
	)
	(via
		(at 232.27 90.2215)
		(size 0.45)
		(drill 0.2)
		(layers "F.Cu" "B.Cu")
		(net 1281)
	)
	(segment
		(start 215.4 91.5)
		(end 215.4 119.6)
		(width 0.1)
		(layer "In5.Cu")
		(net 1281)
	)
	(segment
		(start 215.4 119.6)
		(end 215 120)
		(width 0.1)
		(layer "In5.Cu")
		(net 1281)
	)
	(segment
		(start 216.6 90.3)
		(end 215.4 91.5)
		(width 0.1)
		(layer "In5.Cu")
		(net 1281)
	)
	(segment
		(start 232.1915 90.3)
		(end 216.6 90.3)
		(width 0.1)
		(layer "In5.Cu")
		(net 1281)
	)
	(segment
		(start 232.27 90.2215)
		(end 232.1915 90.3)
		(width 0.1)
		(layer "In5.Cu")
		(net 1281)
	)
	(segment
		(start 212.5 120.5)
		(end 213 120)
		(width 0.256)
		(layer "F.Cu")
		(net 1282)
	)
	(via
		(at 233.54 90.2215)
		(size 0.45)
		(drill 0.2)
		(layers "F.Cu" "B.Cu")
		(net 1282)
	)
	(via
		(at 213 120)
		(size 0.45)
		(drill 0.2)
		(layers "F.Cu" "B.Cu")
		(net 1282)
	)
	(segment
		(start 215.225 120.375)
		(end 213.375 120.375)
		(width 0.1)
		(layer "In5.Cu")
		(net 1282)
	)
	(segment
		(start 216.6 90.6)
		(end 215.7 91.5)
		(width 0.1)
		(layer "In5.Cu")
		(net 1282)
	)
	(segment
		(start 215.7 91.5)
		(end 215.7 119.9)
		(width 0.1)
		(layer "In5.Cu")
		(net 1282)
	)
	(segment
		(start 233.1615 90.6)
		(end 216.6 90.6)
		(width 0.1)
		(layer "In5.Cu")
		(net 1282)
	)
	(segment
		(start 215.7 119.9)
		(end 215.225 120.375)
		(width 0.1)
		(layer "In5.Cu")
		(net 1282)
	)
	(segment
		(start 233.54 90.2215)
		(end 233.1615 90.6)
		(width 0.1)
		(layer "In5.Cu")
		(net 1282)
	)
	(segment
		(start 213.375 120.375)
		(end 213 120)
		(width 0.1)
		(layer "In5.Cu")
		(net 1282)
	)
	(segment
		(start 212.5 121.5)
		(end 212.974886 121.025114)
		(width 0.256)
		(layer "F.Cu")
		(net 1283)
	)
	(segment
		(start 212.974886 121.025114)
		(end 212.987642 121.025114)
		(width 0.256)
		(layer "F.Cu")
		(net 1283)
	)
	(via
		(at 234.81 90.2215)
		(size 0.45)
		(drill 0.2)
		(layers "F.Cu" "B.Cu")
		(net 1283)
	)
	(via
		(at 212.987642 121.025114)
		(size 0.45)
		(drill 0.2)
		(layers "F.Cu" "B.Cu")
		(net 1283)
	)
	(segment
		(start 216 91.5)
		(end 216.6 90.9)
		(width 0.1)
		(layer "In5.Cu")
		(net 1283)
	)
	(segment
		(start 213.412756 120.6)
		(end 215.4 120.6)
		(width 0.1)
		(layer "In5.Cu")
		(net 1283)
	)
	(segment
		(start 234.1315 90.9)
		(end 234.81 90.2215)
		(width 0.1)
		(layer "In5.Cu")
		(net 1283)
	)
	(segment
		(start 216.6 90.9)
		(end 234.1315 90.9)
		(width 0.1)
		(layer "In5.Cu")
		(net 1283)
	)
	(segment
		(start 216 120)
		(end 216 91.5)
		(width 0.1)
		(layer "In5.Cu")
		(net 1283)
	)
	(segment
		(start 212.987642 121.025114)
		(end 213.412756 120.6)
		(width 0.1)
		(layer "In5.Cu")
		(net 1283)
	)
	(segment
		(start 215.4 120.6)
		(end 216 120)
		(width 0.1)
		(layer "In5.Cu")
		(net 1283)
	)
	(segment
		(start 209.5 115.5)
		(end 210 115)
		(width 0.256)
		(layer "F.Cu")
		(net 1284)
	)
	(via
		(at 210 115)
		(size 0.45)
		(drill 0.2)
		(layers "F.Cu" "B.Cu")
		(net 1284)
	)
	(via
		(at 234.799999 86.199999)
		(size 0.45)
		(drill 0.2)
		(layers "F.Cu" "B.Cu")
		(net 1284)
	)
	(segment
		(start 211.125 84.9)
		(end 209.55 86.475)
		(width 0.1)
		(layer "In5.Cu")
		(net 1284)
	)
	(segment
		(start 222.575 85.95)
		(end 213.85 85.95)
		(width 0.1)
		(layer "In5.Cu")
		(net 1284)
	)
	(segment
		(start 234.599999 86.399999)
		(end 227.899999 86.399999)
		(width 0.1)
		(layer "In5.Cu")
		(net 1284)
	)
	(segment
		(start 211.97 84.9)
		(end 211.125 84.9)
		(width 0.1)
		(layer "In5.Cu")
		(net 1284)
	)
	(segment
		(start 234.799999 86.199999)
		(end 234.599999 86.399999)
		(width 0.1)
		(layer "In5.Cu")
		(net 1284)
	)
	(segment
		(start 212.645 85.575)
		(end 211.97 84.9)
		(width 0.1)
		(layer "In5.Cu")
		(net 1284)
	)
	(segment
		(start 227.2225 85.7225)
		(end 222.8025 85.7225)
		(width 0.1)
		(layer "In5.Cu")
		(net 1284)
	)
	(segment
		(start 222.8025 85.7225)
		(end 222.575 85.95)
		(width 0.1)
		(layer "In5.Cu")
		(net 1284)
	)
	(segment
		(start 210 114.75)
		(end 210 115)
		(width 0.1)
		(layer "In5.Cu")
		(net 1284)
	)
	(segment
		(start 227.899999 86.399999)
		(end 227.2225 85.7225)
		(width 0.1)
		(layer "In5.Cu")
		(net 1284)
	)
	(segment
		(start 213.475 85.575)
		(end 212.645 85.575)
		(width 0.1)
		(layer "In5.Cu")
		(net 1284)
	)
	(segment
		(start 209.55 86.475)
		(end 209.55 114.3)
		(width 0.1)
		(layer "In5.Cu")
		(net 1284)
	)
	(segment
		(start 209.55 114.3)
		(end 210 114.75)
		(width 0.1)
		(layer "In5.Cu")
		(net 1284)
	)
	(segment
		(start 213.85 85.95)
		(end 213.475 85.575)
		(width 0.1)
		(layer "In5.Cu")
		(net 1284)
	)
	(segment
		(start 214.5 121.5)
		(end 215 121)
		(width 0.256)
		(layer "F.Cu")
		(net 1285)
	)
	(via
		(at 215 121)
		(size 0.45)
		(drill 0.2)
		(layers "F.Cu" "B.Cu")
		(net 1285)
	)
	(via
		(at 236.079 90.2215)
		(size 0.45)
		(drill 0.2)
		(layers "F.Cu" "B.Cu")
		(net 1285)
	)
	(segment
		(start 236.079 90.2215)
		(end 235.1005 91.2)
		(width 0.1)
		(layer "In5.Cu")
		(net 1285)
	)
	(segment
		(start 218.8 91.4)
		(end 217.55 91.4)
		(width 0.1)
		(layer "In5.Cu")
		(net 1285)
	)
	(segment
		(start 216.5 91.6)
		(end 216.3 91.8)
		(width 0.1)
		(layer "In5.Cu")
		(net 1285)
	)
	(segment
		(start 235.1005 91.2)
		(end 219 91.2)
		(width 0.1)
		(layer "In5.Cu")
		(net 1285)
	)
	(segment
		(start 219 91.2)
		(end 218.8 91.4)
		(width 0.1)
		(layer "In5.Cu")
		(net 1285)
	)
	(segment
		(start 215.4 121)
		(end 215 121)
		(width 0.1)
		(layer "In5.Cu")
		(net 1285)
	)
	(segment
		(start 217.55 91.4)
		(end 217.35 91.6)
		(width 0.1)
		(layer "In5.Cu")
		(net 1285)
	)
	(segment
		(start 216.3 120.1)
		(end 215.4 121)
		(width 0.1)
		(layer "In5.Cu")
		(net 1285)
	)
	(segment
		(start 217.35 91.6)
		(end 216.5 91.6)
		(width 0.1)
		(layer "In5.Cu")
		(net 1285)
	)
	(segment
		(start 216.3 91.8)
		(end 216.3 120.1)
		(width 0.1)
		(layer "In5.Cu")
		(net 1285)
	)
	(segment
		(start 209.5 116.5)
		(end 210 116)
		(width 0.256)
		(layer "F.Cu")
		(net 1286)
	)
	(via
		(at 235.999999 86.799999)
		(size 0.45)
		(drill 0.2)
		(layers "F.Cu" "B.Cu")
		(net 1286)
	)
	(via
		(at 210 116)
		(size 0.45)
		(drill 0.2)
		(layers "F.Cu" "B.Cu")
		(net 1286)
	)
	(segment
		(start 213.725 86.2)
		(end 222.65 86.2)
		(width 0.1)
		(layer "In5.Cu")
		(net 1286)
	)
	(segment
		(start 212.485 85.775)
		(end 213.3 85.775)
		(width 0.1)
		(layer "In5.Cu")
		(net 1286)
	)
	(segment
		(start 210.45 114.6)
		(end 210.45 85.95)
		(width 0.1)
		(layer "In5.Cu")
		(net 1286)
	)
	(segment
		(start 210 116)
		(end 210.375 115.625)
		(width 0.1)
		(layer "In5.Cu")
		(net 1286)
	)
	(segment
		(start 213.3 85.775)
		(end 213.725 86.2)
		(width 0.1)
		(layer "In5.Cu")
		(net 1286)
	)
	(segment
		(start 235.799999 86.599999)
		(end 235.999999 86.799999)
		(width 0.1)
		(layer "In5.Cu")
		(net 1286)
	)
	(segment
		(start 211.3 85.1)
		(end 211.81 85.1)
		(width 0.1)
		(layer "In5.Cu")
		(net 1286)
	)
	(segment
		(start 210.375 114.675)
		(end 210.45 114.6)
		(width 0.1)
		(layer "In5.Cu")
		(net 1286)
	)
	(segment
		(start 222.9275 85.9225)
		(end 227.1225 85.9225)
		(width 0.1)
		(layer "In5.Cu")
		(net 1286)
	)
	(segment
		(start 227.799999 86.599999)
		(end 235.799999 86.599999)
		(width 0.1)
		(layer "In5.Cu")
		(net 1286)
	)
	(segment
		(start 227.1225 85.9225)
		(end 227.799999 86.599999)
		(width 0.1)
		(layer "In5.Cu")
		(net 1286)
	)
	(segment
		(start 210.375 115.625)
		(end 210.375 114.675)
		(width 0.1)
		(layer "In5.Cu")
		(net 1286)
	)
	(segment
		(start 211.81 85.1)
		(end 212.485 85.775)
		(width 0.1)
		(layer "In5.Cu")
		(net 1286)
	)
	(segment
		(start 222.65 86.2)
		(end 222.9275 85.9225)
		(width 0.1)
		(layer "In5.Cu")
		(net 1286)
	)
	(segment
		(start 210.45 85.95)
		(end 211.3 85.1)
		(width 0.1)
		(layer "In5.Cu")
		(net 1286)
	)
	(segment
		(start 214.5 122.5)
		(end 215 122)
		(width 0.256)
		(layer "F.Cu")
		(net 1287)
	)
	(segment
		(start 237.35 90.2875)
		(end 237.35 89.9225)
		(width 0.182)
		(layer "F.Cu")
		(net 1287)
	)
	(via
		(at 215 122)
		(size 0.45)
		(drill 0.2)
		(layers "F.Cu" "B.Cu")
		(net 1287)
	)
	(via
		(at 237.35 89.9225)
		(size 0.45)
		(drill 0.2)
		(layers "F.Cu" "B.Cu")
		(net 1287)
	)
	(segment
		(start 217.2 120.5)
		(end 215.7 122)
		(width 0.1)
		(layer "In5.Cu")
		(net 1287)
	)
	(segment
		(start 215.7 122)
		(end 215 122)
		(width 0.1)
		(layer "In5.Cu")
		(net 1287)
	)
	(segment
		(start 235.5775 92.3225)
		(end 219.4275 92.3225)
		(width 0.1)
		(layer "In5.Cu")
		(net 1287)
	)
	(segment
		(start 217.2 94.55)
		(end 217.2 120.5)
		(width 0.1)
		(layer "In5.Cu")
		(net 1287)
	)
	(segment
		(start 237.35 89.9225)
		(end 237.35 90.55)
		(width 0.1)
		(layer "In5.Cu")
		(net 1287)
	)
	(segment
		(start 237.35 90.55)
		(end 235.5775 92.3225)
		(width 0.1)
		(layer "In5.Cu")
		(net 1287)
	)
	(segment
		(start 219.4275 92.3225)
		(end 217.2 94.55)
		(width 0.1)
		(layer "In5.Cu")
		(net 1287)
	)
	(segment
		(start 237.35 87.949998)
		(end 237.35 86.2225)
		(width 0.1)
		(layer "F.Cu")
		(net 1288)
	)
	(segment
		(start 236.699999 88.599999)
		(end 237.35 87.949998)
		(width 0.1)
		(layer "F.Cu")
		(net 1288)
	)
	(segment
		(start 214.5 119.5)
		(end 215 119)
		(width 0.256)
		(layer "F.Cu")
		(net 1288)
	)
	(via
		(at 236.699999 88.599999)
		(size 0.45)
		(drill 0.2)
		(layers "F.Cu" "B.Cu")
		(net 1288)
	)
	(via
		(at 215 119)
		(size 0.45)
		(drill 0.2)
		(layers "F.Cu" "B.Cu")
		(net 1288)
	)
	(segment
		(start 215 119)
		(end 214.625 118.625)
		(width 0.1)
		(layer "In5.Cu")
		(net 1288)
	)
	(segment
		(start 214.625 116.705)
		(end 215.1 116.23)
		(width 0.1)
		(layer "In5.Cu")
		(net 1288)
	)
	(segment
		(start 216.5755 90.0245)
		(end 224.875498 90.0245)
		(width 0.1)
		(layer "In5.Cu")
		(net 1288)
	)
	(segment
		(start 215.1 91.5)
		(end 216.5755 90.0245)
		(width 0.1)
		(layer "In5.Cu")
		(net 1288)
	)
	(segment
		(start 236.699999 89.14)
		(end 236.699999 88.599999)
		(width 0.1)
		(layer "In5.Cu")
		(net 1288)
	)
	(segment
		(start 236.14 89.699999)
		(end 236.699999 89.14)
		(width 0.1)
		(layer "In5.Cu")
		(net 1288)
	)
	(segment
		(start 225.199999 89.699999)
		(end 236.14 89.699999)
		(width 0.1)
		(layer "In5.Cu")
		(net 1288)
	)
	(segment
		(start 224.875498 90.0245)
		(end 225.199999 89.699999)
		(width 0.1)
		(layer "In5.Cu")
		(net 1288)
	)
	(segment
		(start 215.1 116.23)
		(end 215.1 91.5)
		(width 0.1)
		(layer "In5.Cu")
		(net 1288)
	)
	(segment
		(start 214.625 118.625)
		(end 214.625 116.705)
		(width 0.1)
		(layer "In5.Cu")
		(net 1288)
	)
	(segment
		(start 208.5 122.5)
		(end 209 122)
		(width 0.256)
		(layer "F.Cu")
		(net 1289)
	)
	(via
		(at 239.099999 88.799999)
		(size 0.45)
		(drill 0.2)
		(layers "F.Cu" "B.Cu")
		(net 1289)
	)
	(via
		(at 209 122)
		(size 0.45)
		(drill 0.2)
		(layers "F.Cu" "B.Cu")
		(net 1289)
	)
	(segment
		(start 239.199999 87.899999)
		(end 239.199999 88.699999)
		(width 0.1)
		(layer "In5.Cu")
		(net 1289)
	)
	(segment
		(start 210.43 84.07)
		(end 221.5 84.07)
		(width 0.1)
		(layer "In5.Cu")
		(net 1289)
	)
	(segment
		(start 239.199999 88.699999)
		(end 239.099999 88.799999)
		(width 0.1)
		(layer "In5.Cu")
		(net 1289)
	)
	(segment
		(start 222.33 84.9)
		(end 236.2 84.9)
		(width 0.1)
		(layer "In5.Cu")
		(net 1289)
	)
	(segment
		(start 208.375 114.811827)
		(end 208.45 114.736827)
		(width 0.1)
		(layer "In5.Cu")
		(net 1289)
	)
	(segment
		(start 208.45 86.05)
		(end 210.43 84.07)
		(width 0.1)
		(layer "In5.Cu")
		(net 1289)
	)
	(segment
		(start 208.45 114.736827)
		(end 208.45 86.05)
		(width 0.1)
		(layer "In5.Cu")
		(net 1289)
	)
	(segment
		(start 221.5 84.07)
		(end 222.33 84.9)
		(width 0.1)
		(layer "In5.Cu")
		(net 1289)
	)
	(segment
		(start 236.2 84.9)
		(end 239.199999 87.899999)
		(width 0.1)
		(layer "In5.Cu")
		(net 1289)
	)
	(segment
		(start 208.375 121.375)
		(end 208.375 114.811827)
		(width 0.1)
		(layer "In5.Cu")
		(net 1289)
	)
	(segment
		(start 209 122)
		(end 208.375 121.375)
		(width 0.1)
		(layer "In5.Cu")
		(net 1289)
	)
	(segment
		(start 237.914811 87.985187)
		(end 238.62 87.279998)
		(width 0.1)
		(layer "F.Cu")
		(net 1290)
	)
	(segment
		(start 212.02 116.98)
		(end 212.025 116.98)
		(width 0.256)
		(layer "F.Cu")
		(net 1290)
	)
	(segment
		(start 238.62 87.279998)
		(end 238.62 86.2225)
		(width 0.1)
		(layer "F.Cu")
		(net 1290)
	)
	(segment
		(start 211.5 117.5)
		(end 212.02 116.98)
		(width 0.256)
		(layer "F.Cu")
		(net 1290)
	)
	(via
		(at 237.914811 87.985187)
		(size 0.45)
		(drill 0.2)
		(layers "F.Cu" "B.Cu")
		(net 1290)
	)
	(via
		(at 212.025 116.98)
		(size 0.45)
		(drill 0.2)
		(layers "F.Cu" "B.Cu")
		(net 1290)
	)
	(segment
		(start 220.55 88.5)
		(end 220.9 88.15)
		(width 0.1)
		(layer "In5.Cu")
		(net 1290)
	)
	(segment
		(start 235.682841 87.799999)
		(end 237.729623 87.799999)
		(width 0.1)
		(layer "In5.Cu")
		(net 1290)
	)
	(segment
		(start 212.625 90.375)
		(end 212.625 89.525)
		(width 0.1)
		(layer "In5.Cu")
		(net 1290)
	)
	(segment
		(start 212.625 99.875)
		(end 213.35 99.15)
		(width 0.1)
		(layer "In5.Cu")
		(net 1290)
	)
	(segment
		(start 212.625 116.38)
		(end 212.625 99.875)
		(width 0.1)
		(layer "In5.Cu")
		(net 1290)
	)
	(segment
		(start 216.3 87.85)
		(end 216.95 88.5)
		(width 0.1)
		(layer "In5.Cu")
		(net 1290)
	)
	(segment
		(start 225.552416 88.15)
		(end 226.502416 89.1)
		(width 0.1)
		(layer "In5.Cu")
		(net 1290)
	)
	(segment
		(start 234.782841 88.699999)
		(end 235.682841 87.799999)
		(width 0.1)
		(layer "In5.Cu")
		(net 1290)
	)
	(segment
		(start 213.35 91.1)
		(end 212.625 90.375)
		(width 0.1)
		(layer "In5.Cu")
		(net 1290)
	)
	(segment
		(start 216.95 88.5)
		(end 220.55 88.5)
		(width 0.1)
		(layer "In5.Cu")
		(net 1290)
	)
	(segment
		(start 212.025 116.98)
		(end 212.625 116.38)
		(width 0.1)
		(layer "In5.Cu")
		(net 1290)
	)
	(segment
		(start 226.502416 89.1)
		(end 229.1 89.1)
		(width 0.1)
		(layer "In5.Cu")
		(net 1290)
	)
	(segment
		(start 237.729623 87.799999)
		(end 237.914811 87.985187)
		(width 0.1)
		(layer "In5.Cu")
		(net 1290)
	)
	(segment
		(start 220.9 88.15)
		(end 225.552416 88.15)
		(width 0.1)
		(layer "In5.Cu")
		(net 1290)
	)
	(segment
		(start 212.625 89.525)
		(end 214.3 87.85)
		(width 0.1)
		(layer "In5.Cu")
		(net 1290)
	)
	(segment
		(start 229.1 89.1)
		(end 229.500001 88.699999)
		(width 0.1)
		(layer "In5.Cu")
		(net 1290)
	)
	(segment
		(start 214.3 87.85)
		(end 216.3 87.85)
		(width 0.1)
		(layer "In5.Cu")
		(net 1290)
	)
	(segment
		(start 213.35 99.15)
		(end 213.35 91.1)
		(width 0.1)
		(layer "In5.Cu")
		(net 1290)
	)
	(segment
		(start 229.500001 88.699999)
		(end 234.782841 88.699999)
		(width 0.1)
		(layer "In5.Cu")
		(net 1290)
	)
	(segment
		(start 211.5 120.5)
		(end 211.984934 120.015066)
		(width 0.256)
		(layer "F.Cu")
		(net 1291)
	)
	(segment
		(start 211.984934 120.015066)
		(end 212.025956 120.015066)
		(width 0.256)
		(layer "F.Cu")
		(net 1291)
	)
	(via
		(at 239.891 90.2215)
		(size 0.45)
		(drill 0.2)
		(layers "F.Cu" "B.Cu")
		(net 1291)
	)
	(via
		(at 212.025956 120.015066)
		(size 0.45)
		(drill 0.2)
		(layers "F.Cu" "B.Cu")
		(net 1291)
	)
	(segment
		(start 211.5 89.75)
		(end 214.05 87.2)
		(width 0.1)
		(layer "In5.Cu")
		(net 1291)
	)
	(segment
		(start 239.1215 90.2215)
		(end 239.891 90.2215)
		(width 0.1)
		(layer "In5.Cu")
		(net 1291)
	)
	(segment
		(start 216.75 87.2)
		(end 217.0625 87.5125)
		(width 0.1)
		(layer "In5.Cu")
		(net 1291)
	)
	(segment
		(start 238.499999 89.599999)
		(end 239.1215 90.2215)
		(width 0.1)
		(layer "In5.Cu")
		(net 1291)
	)
	(segment
		(start 212.025956 120.015066)
		(end 211.625 119.61411)
		(width 0.1)
		(layer "In5.Cu")
		(net 1291)
	)
	(segment
		(start 211.625 119.61411)
		(end 211.625 114.844669)
		(width 0.1)
		(layer "In5.Cu")
		(net 1291)
	)
	(segment
		(start 211.7 114.769669)
		(end 211.7 99.9)
		(width 0.1)
		(layer "In5.Cu")
		(net 1291)
	)
	(segment
		(start 234.699999 88.499999)
		(end 235.599999 87.599999)
		(width 0.1)
		(layer "In5.Cu")
		(net 1291)
	)
	(segment
		(start 235.599999 87.599999)
		(end 238.199999 87.599999)
		(width 0.1)
		(layer "In5.Cu")
		(net 1291)
	)
	(segment
		(start 211.5 99.7)
		(end 211.5 89.75)
		(width 0.1)
		(layer "In5.Cu")
		(net 1291)
	)
	(segment
		(start 229.300001 88.499999)
		(end 234.699999 88.499999)
		(width 0.1)
		(layer "In5.Cu")
		(net 1291)
	)
	(segment
		(start 228.05 88.9)
		(end 228.9 88.9)
		(width 0.1)
		(layer "In5.Cu")
		(net 1291)
	)
	(segment
		(start 238.499999 87.899999)
		(end 238.499999 89.599999)
		(width 0.1)
		(layer "In5.Cu")
		(net 1291)
	)
	(segment
		(start 238.199999 87.599999)
		(end 238.499999 87.899999)
		(width 0.1)
		(layer "In5.Cu")
		(net 1291)
	)
	(segment
		(start 217.0625 87.5125)
		(end 226.6625 87.5125)
		(width 0.1)
		(layer "In5.Cu")
		(net 1291)
	)
	(segment
		(start 211.7 99.9)
		(end 211.5 99.7)
		(width 0.1)
		(layer "In5.Cu")
		(net 1291)
	)
	(segment
		(start 228.9 88.9)
		(end 229.300001 88.499999)
		(width 0.1)
		(layer "In5.Cu")
		(net 1291)
	)
	(segment
		(start 226.6625 87.5125)
		(end 228.05 88.9)
		(width 0.1)
		(layer "In5.Cu")
		(net 1291)
	)
	(segment
		(start 214.05 87.2)
		(end 216.75 87.2)
		(width 0.1)
		(layer "In5.Cu")
		(net 1291)
	)
	(segment
		(start 211.625 114.844669)
		(end 211.7 114.769669)
		(width 0.1)
		(layer "In5.Cu")
		(net 1291)
	)
	(segment
		(start 212.5 118.5)
		(end 213 118)
		(width 0.256)
		(layer "F.Cu")
		(net 1292)
	)
	(segment
		(start 239.89 87.02)
		(end 239.89 86.2225)
		(width 0.1)
		(layer "F.Cu")
		(net 1292)
	)
	(segment
		(start 238.310001 88.599999)
		(end 239.89 87.02)
		(width 0.1)
		(layer "F.Cu")
		(net 1292)
	)
	(segment
		(start 237.999999 88.599999)
		(end 238.310001 88.599999)
		(width 0.1)
		(layer "F.Cu")
		(net 1292)
	)
	(via
		(at 213 118)
		(size 0.45)
		(drill 0.2)
		(layers "F.Cu" "B.Cu")
		(net 1292)
	)
	(via
		(at 237.999999 88.599999)
		(size 0.45)
		(drill 0.2)
		(layers "F.Cu" "B.Cu")
		(net 1292)
	)
	(segment
		(start 214.5 116.13)
		(end 214.5 91.45)
		(width 0.1)
		(layer "In5.Cu")
		(net 1292)
	)
	(segment
		(start 224.925 89.225)
		(end 225.199999 89.499999)
		(width 0.1)
		(layer "In5.Cu")
		(net 1292)
	)
	(segment
		(start 216.3255 89.6245)
		(end 224.075499 89.6245)
		(width 0.1)
		(layer "In5.Cu")
		(net 1292)
	)
	(segment
		(start 214.5 91.45)
		(end 216.3255 89.6245)
		(width 0.1)
		(layer "In5.Cu")
		(net 1292)
	)
	(segment
		(start 213.495 117.505)
		(end 213.495 116.735)
		(width 0.1)
		(layer "In5.Cu")
		(net 1292)
	)
	(segment
		(start 225.199999 89.499999)
		(end 229.870331 89.499999)
		(width 0.1)
		(layer "In5.Cu")
		(net 1292)
	)
	(segment
		(start 235.765683 87.999999)
		(end 237.399999 87.999999)
		(width 0.1)
		(layer "In5.Cu")
		(net 1292)
	)
	(segment
		(start 230.470331 88.899999)
		(end 234.865683 88.899999)
		(width 0.1)
		(layer "In5.Cu")
		(net 1292)
	)
	(segment
		(start 213.745 116.485)
		(end 214.145 116.485)
		(width 0.1)
		(layer "In5.Cu")
		(net 1292)
	)
	(segment
		(start 229.870331 89.499999)
		(end 230.470331 88.899999)
		(width 0.1)
		(layer "In5.Cu")
		(net 1292)
	)
	(segment
		(start 213.495 116.735)
		(end 213.745 116.485)
		(width 0.1)
		(layer "In5.Cu")
		(net 1292)
	)
	(segment
		(start 234.865683 88.899999)
		(end 235.765683 87.999999)
		(width 0.1)
		(layer "In5.Cu")
		(net 1292)
	)
	(segment
		(start 224.075499 89.6245)
		(end 224.474999 89.225)
		(width 0.1)
		(layer "In5.Cu")
		(net 1292)
	)
	(segment
		(start 237.399999 87.999999)
		(end 237.999999 88.599999)
		(width 0.1)
		(layer "In5.Cu")
		(net 1292)
	)
	(segment
		(start 214.145 116.485)
		(end 214.5 116.13)
		(width 0.1)
		(layer "In5.Cu")
		(net 1292)
	)
	(segment
		(start 213 118)
		(end 213.495 117.505)
		(width 0.1)
		(layer "In5.Cu")
		(net 1292)
	)
	(segment
		(start 224.474999 89.225)
		(end 224.925 89.225)
		(width 0.1)
		(layer "In5.Cu")
		(net 1292)
	)
	(segment
		(start 211.5 121.5)
		(end 212 121)
		(width 0.256)
		(layer "F.Cu")
		(net 1293)
	)
	(via
		(at 212 121)
		(size 0.45)
		(drill 0.2)
		(layers "F.Cu" "B.Cu")
		(net 1293)
	)
	(via
		(at 241.199999 90.199999)
		(size 0.45)
		(drill 0.2)
		(layers "F.Cu" "B.Cu")
		(net 1293)
	)
	(segment
		(start 238.299999 87.399999)
		(end 238.699999 87.799999)
		(width 0.1)
		(layer "In5.Cu")
		(net 1293)
	)
	(segment
		(start 213.925 87)
		(end 216.875 87)
		(width 0.1)
		(layer "In5.Cu")
		(net 1293)
	)
	(segment
		(start 228.182842 88.7)
		(end 228.7 88.7)
		(width 0.1)
		(layer "In5.Cu")
		(net 1293)
	)
	(segment
		(start 217.175 87.3)
		(end 226.782842 87.3)
		(width 0.1)
		(layer "In5.Cu")
		(net 1293)
	)
	(segment
		(start 228.7 88.7)
		(end 229.100001 88.299999)
		(width 0.1)
		(layer "In5.Cu")
		(net 1293)
	)
	(segment
		(start 240.599999 89.599999)
		(end 241.199999 90.199999)
		(width 0.1)
		(layer "In5.Cu")
		(net 1293)
	)
	(segment
		(start 211.375 120.375)
		(end 211.375 114.844669)
		(width 0.1)
		(layer "In5.Cu")
		(net 1293)
	)
	(segment
		(start 238.899999 89.599999)
		(end 240.599999 89.599999)
		(width 0.1)
		(layer "In5.Cu")
		(net 1293)
	)
	(segment
		(start 211.3 89.625)
		(end 213.925 87)
		(width 0.1)
		(layer "In5.Cu")
		(net 1293)
	)
	(segment
		(start 212 121)
		(end 211.375 120.375)
		(width 0.1)
		(layer "In5.Cu")
		(net 1293)
	)
	(segment
		(start 211.375 114.844669)
		(end 211.3 114.769669)
		(width 0.1)
		(layer "In5.Cu")
		(net 1293)
	)
	(segment
		(start 216.875 87)
		(end 217.175 87.3)
		(width 0.1)
		(layer "In5.Cu")
		(net 1293)
	)
	(segment
		(start 211.3 114.769669)
		(end 211.3 89.625)
		(width 0.1)
		(layer "In5.Cu")
		(net 1293)
	)
	(segment
		(start 238.699999 87.799999)
		(end 238.699999 89.399999)
		(width 0.1)
		(layer "In5.Cu")
		(net 1293)
	)
	(segment
		(start 226.782842 87.3)
		(end 228.182842 88.7)
		(width 0.1)
		(layer "In5.Cu")
		(net 1293)
	)
	(segment
		(start 235.499999 87.399999)
		(end 238.299999 87.399999)
		(width 0.1)
		(layer "In5.Cu")
		(net 1293)
	)
	(segment
		(start 238.699999 89.399999)
		(end 238.899999 89.599999)
		(width 0.1)
		(layer "In5.Cu")
		(net 1293)
	)
	(segment
		(start 234.599999 88.299999)
		(end 235.499999 87.399999)
		(width 0.1)
		(layer "In5.Cu")
		(net 1293)
	)
	(segment
		(start 229.100001 88.299999)
		(end 234.599999 88.299999)
		(width 0.1)
		(layer "In5.Cu")
		(net 1293)
	)
	(segment
		(start 205.5 129.5)
		(end 206 129)
		(width 0.256)
		(layer "F.Cu")
		(net 1294)
	)
	(segment
		(start 235.865 142.965)
		(end 235.865 143.45)
		(width 0.182)
		(layer "F.Cu")
		(net 1294)
	)
	(segment
		(start 234.885188 141.985188)
		(end 235.865 142.965)
		(width 0.182)
		(layer "F.Cu")
		(net 1294)
	)
	(segment
		(start 234.885188 138.385188)
		(end 234.885188 141.985188)
		(width 0.182)
		(layer "F.Cu")
		(net 1294)
	)
	(via
		(at 234.885188 138.385188)
		(size 0.45)
		(drill 0.2)
		(layers "F.Cu" "B.Cu")
		(net 1294)
	)
	(via
		(at 206 129)
		(size 0.45)
		(drill 0.2)
		(layers "F.Cu" "B.Cu")
		(net 1294)
	)
	(via
		(at 252.975 147.3)
		(size 0.45)
		(drill 0.2)
		(layers "F.Cu" "B.Cu")
		(net 1294)
	)
	(segment
		(start 252.975 147.55)
		(end 253.3 147.875)
		(width 0.1)
		(layer "B.Cu")
		(net 1294)
	)
	(segment
		(start 252.975 147.55)
		(end 252.975 147.3)
		(width 0.1)
		(layer "B.Cu")
		(net 1294)
	)
	(segment
		(start 253.3 148.273)
		(end 253.3 147.875)
		(width 0.1)
		(layer "B.Cu")
		(net 1294)
	)
	(segment
		(start 242.45 137.23)
		(end 242.18 137.5)
		(width 0.1)
		(layer "In7.Cu")
		(net 1294)
	)
	(segment
		(start 239.261143 133.34)
		(end 239.651143 133.73)
		(width 0.1)
		(layer "In7.Cu")
		(net 1294)
	)
	(segment
		(start 244.15 145.25)
		(end 245.65 145.25)
		(width 0.1)
		(layer "In7.Cu")
		(net 1294)
	)
	(segment
		(start 235.35 134.312842)
		(end 236.322842 133.34)
		(width 0.1)
		(layer "In7.Cu")
		(net 1294)
	)
	(segment
		(start 218.587158 140.75)
		(end 220.800001 140.75)
		(width 0.1)
		(layer "In7.Cu")
		(net 1294)
	)
	(segment
		(start 202.717158 137.6)
		(end 203.22 137.6)
		(width 0.1)
		(layer "In7.Cu")
		(net 1294)
	)
	(segment
		(start 202.4 137.282843)
		(end 202.717158 137.6)
		(width 0.1)
		(layer "In7.Cu")
		(net 1294)
	)
	(segment
		(start 252.55 144.85)
		(end 252.975 145.275)
		(width 0.1)
		(layer "In7.Cu")
		(net 1294)
	)
	(segment
		(start 231.5 137.1)
		(end 233.25 138.85)
		(width 0.1)
		(layer "In7.Cu")
		(net 1294)
	)
	(segment
		(start 242.18 143.28)
		(end 244.15 145.25)
		(width 0.1)
		(layer "In7.Cu")
		(net 1294)
	)
	(segment
		(start 239.651143 133.73)
		(end 240.14079 133.73)
		(width 0.1)
		(layer "In7.Cu")
		(net 1294)
	)
	(segment
		(start 242.18 137.5)
		(end 242.18 143.28)
		(width 0.1)
		(layer "In7.Cu")
		(net 1294)
	)
	(segment
		(start 204.457158 139.61)
		(end 217.447158 139.61)
		(width 0.1)
		(layer "In7.Cu")
		(net 1294)
	)
	(segment
		(start 246.05 144.85)
		(end 252.55 144.85)
		(width 0.1)
		(layer "In7.Cu")
		(net 1294)
	)
	(segment
		(start 206 129)
		(end 205.6 129.4)
		(width 0.1)
		(layer "In7.Cu")
		(net 1294)
	)
	(segment
		(start 224.45 137.1)
		(end 231.5 137.1)
		(width 0.1)
		(layer "In7.Cu")
		(net 1294)
	)
	(segment
		(start 233.25 138.85)
		(end 234.420376 138.85)
		(width 0.1)
		(layer "In7.Cu")
		(net 1294)
	)
	(segment
		(start 204.437157 139.59)
		(end 204.457158 139.61)
		(width 0.1)
		(layer "In7.Cu")
		(net 1294)
	)
	(segment
		(start 205.6 129.4)
		(end 203.067157 129.4)
		(width 0.1)
		(layer "In7.Cu")
		(net 1294)
	)
	(segment
		(start 234.420376 138.85)
		(end 234.885188 138.385188)
		(width 0.1)
		(layer "In7.Cu")
		(net 1294)
	)
	(segment
		(start 217.447158 139.61)
		(end 218.587158 140.75)
		(width 0.1)
		(layer "In7.Cu")
		(net 1294)
	)
	(segment
		(start 234.885188 138.385188)
		(end 234.885188 137.794812)
		(width 0.1)
		(layer "In7.Cu")
		(net 1294)
	)
	(segment
		(start 234.885188 137.794812)
		(end 235.35 137.33)
		(width 0.1)
		(layer "In7.Cu")
		(net 1294)
	)
	(segment
		(start 252.975 145.275)
		(end 252.975 147.3)
		(width 0.1)
		(layer "In7.Cu")
		(net 1294)
	)
	(segment
		(start 203.38 137.76)
		(end 203.38 138.55)
		(width 0.1)
		(layer "In7.Cu")
		(net 1294)
	)
	(segment
		(start 204.42 139.59)
		(end 204.437157 139.59)
		(width 0.1)
		(layer "In7.Cu")
		(net 1294)
	)
	(segment
		(start 240.14079 133.73)
		(end 242.45 136.03921)
		(width 0.1)
		(layer "In7.Cu")
		(net 1294)
	)
	(segment
		(start 220.800001 140.75)
		(end 224.45 137.1)
		(width 0.1)
		(layer "In7.Cu")
		(net 1294)
	)
	(segment
		(start 236.322842 133.34)
		(end 239.261143 133.34)
		(width 0.1)
		(layer "In7.Cu")
		(net 1294)
	)
	(segment
		(start 202.4 130.067158)
		(end 202.4 137.282843)
		(width 0.1)
		(layer "In7.Cu")
		(net 1294)
	)
	(segment
		(start 245.65 145.25)
		(end 246.05 144.85)
		(width 0.1)
		(layer "In7.Cu")
		(net 1294)
	)
	(segment
		(start 203.067157 129.4)
		(end 202.4 130.067158)
		(width 0.1)
		(layer "In7.Cu")
		(net 1294)
	)
	(segment
		(start 242.45 136.03921)
		(end 242.45 137.23)
		(width 0.1)
		(layer "In7.Cu")
		(net 1294)
	)
	(segment
		(start 235.35 137.33)
		(end 235.35 134.312842)
		(width 0.1)
		(layer "In7.Cu")
		(net 1294)
	)
	(segment
		(start 203.38 138.55)
		(end 204.42 139.59)
		(width 0.1)
		(layer "In7.Cu")
		(net 1294)
	)
	(segment
		(start 203.22 137.6)
		(end 203.38 137.76)
		(width 0.1)
		(layer "In7.Cu")
		(net 1294)
	)
	(segment
		(start 234 138.3)
		(end 234 142.4)
		(width 0.182)
		(layer "F.Cu")
		(net 1295)
	)
	(segment
		(start 234.094939 138.205061)
		(end 234.094939 137.644939)
		(width 0.182)
		(layer "F.Cu")
		(net 1295)
	)
	(segment
		(start 234.9 144.9)
		(end 235.45 145.45)
		(width 0.182)
		(layer "F.Cu")
		(net 1295)
	)
	(segment
		(start 234 142.4)
		(end 234.9 143.3)
		(width 0.182)
		(layer "F.Cu")
		(net 1295)
	)
	(segment
		(start 205.5 130.5)
		(end 206 131)
		(width 0.256)
		(layer "F.Cu")
		(net 1295)
	)
	(segment
		(start 234.9 143.3)
		(end 234.9 144.9)
		(width 0.182)
		(layer "F.Cu")
		(net 1295)
	)
	(segment
		(start 235.45 145.45)
		(end 235.865 145.45)
		(width 0.182)
		(layer "F.Cu")
		(net 1295)
	)
	(segment
		(start 234.094939 137.644939)
		(end 233.75 137.3)
		(width 0.182)
		(layer "F.Cu")
		(net 1295)
	)
	(segment
		(start 234.094939 138.205061)
		(end 234 138.3)
		(width 0.182)
		(layer "F.Cu")
		(net 1295)
	)
	(via
		(at 252.725 148.075)
		(size 0.45)
		(drill 0.2)
		(layers "F.Cu" "B.Cu")
		(net 1295)
	)
	(via
		(at 206 131)
		(size 0.45)
		(drill 0.2)
		(layers "F.Cu" "B.Cu")
		(net 1295)
	)
	(via
		(at 233.75 137.3)
		(size 0.45)
		(drill 0.2)
		(layers "F.Cu" "B.Cu")
		(net 1295)
	)
	(segment
		(start 252.527 148.273)
		(end 252.725 148.075)
		(width 0.1)
		(layer "B.Cu")
		(net 1295)
	)
	(segment
		(start 252.5 148.273)
		(end 252.527 148.273)
		(width 0.1)
		(layer "B.Cu")
		(net 1295)
	)
	(segment
		(start 239.2 132.04)
		(end 234.44 132.04)
		(width 0.1)
		(layer "In7.Cu")
		(net 1295)
	)
	(segment
		(start 234.44 132.04)
		(end 233.75 132.73)
		(width 0.1)
		(layer "In7.Cu")
		(net 1295)
	)
	(segment
		(start 255.05 148.075)
		(end 255.05 144.8)
		(width 0.1)
		(layer "In7.Cu")
		(net 1295)
	)
	(segment
		(start 239.56 132.4)
		(end 239.2 132.04)
		(width 0.1)
		(layer "In7.Cu")
		(net 1295)
	)
	(segment
		(start 205.6 130.6)
		(end 206 131)
		(width 0.1)
		(layer "In7.Cu")
		(net 1295)
	)
	(segment
		(start 233.75 137.3)
		(end 232.94 136.49)
		(width 0.1)
		(layer "In7.Cu")
		(net 1295)
	)
	(segment
		(start 244.69 142.79)
		(end 244.69 141.77)
		(width 0.1)
		(layer "In7.Cu")
		(net 1295)
	)
	(segment
		(start 239.56 132.790331)
		(end 239.56 132.4)
		(width 0.1)
		(layer "In7.Cu")
		(net 1295)
	)
	(segment
		(start 245.7 143.8)
		(end 244.69 142.79)
		(width 0.1)
		(layer "In7.Cu")
		(net 1295)
	)
	(segment
		(start 203.6 136.25)
		(end 203.6 130.75)
		(width 0.1)
		(layer "In7.Cu")
		(net 1295)
	)
	(segment
		(start 245.22 141.24)
		(end 245.22 137.960684)
		(width 0.1)
		(layer "In7.Cu")
		(net 1295)
	)
	(segment
		(start 233.75 132.73)
		(end 233.75 137.3)
		(width 0.1)
		(layer "In7.Cu")
		(net 1295)
	)
	(segment
		(start 244.69 141.77)
		(end 245.22 141.24)
		(width 0.1)
		(layer "In7.Cu")
		(net 1295)
	)
	(segment
		(start 255.05 144.8)
		(end 254.05 143.8)
		(width 0.1)
		(layer "In7.Cu")
		(net 1295)
	)
	(segment
		(start 254.05 143.8)
		(end 245.7 143.8)
		(width 0.1)
		(layer "In7.Cu")
		(net 1295)
	)
	(segment
		(start 252.725 148.075)
		(end 252.875 148.225)
		(width 0.1)
		(layer "In7.Cu")
		(net 1295)
	)
	(segment
		(start 252.875 148.225)
		(end 254.9 148.225)
		(width 0.1)
		(layer "In7.Cu")
		(net 1295)
	)
	(segment
		(start 245.22 137.960684)
		(end 240.389316 133.13)
		(width 0.1)
		(layer "In7.Cu")
		(net 1295)
	)
	(segment
		(start 203.75 130.6)
		(end 205.6 130.6)
		(width 0.1)
		(layer "In7.Cu")
		(net 1295)
	)
	(segment
		(start 216.66 137.09)
		(end 215.995 136.425)
		(width 0.1)
		(layer "In7.Cu")
		(net 1295)
	)
	(segment
		(start 221.867157 137.09)
		(end 216.66 137.09)
		(width 0.1)
		(layer "In7.Cu")
		(net 1295)
	)
	(segment
		(start 203.775 136.425)
		(end 203.6 136.25)
		(width 0.1)
		(layer "In7.Cu")
		(net 1295)
	)
	(segment
		(start 240.389316 133.13)
		(end 239.899669 133.13)
		(width 0.1)
		(layer "In7.Cu")
		(net 1295)
	)
	(segment
		(start 215.995 136.425)
		(end 203.775 136.425)
		(width 0.1)
		(layer "In7.Cu")
		(net 1295)
	)
	(segment
		(start 239.899669 133.13)
		(end 239.56 132.790331)
		(width 0.1)
		(layer "In7.Cu")
		(net 1295)
	)
	(segment
		(start 222.467157 136.49)
		(end 221.867157 137.09)
		(width 0.1)
		(layer "In7.Cu")
		(net 1295)
	)
	(segment
		(start 232.94 136.49)
		(end 222.467157 136.49)
		(width 0.1)
		(layer "In7.Cu")
		(net 1295)
	)
	(segment
		(start 203.6 130.75)
		(end 203.75 130.6)
		(width 0.1)
		(layer "In7.Cu")
		(net 1295)
	)
	(segment
		(start 254.9 148.225)
		(end 255.05 148.075)
		(width 0.1)
		(layer "In7.Cu")
		(net 1295)
	)
	(segment
		(start 235.65 146.45)
		(end 235.865 146.45)
		(width 0.182)
		(layer "F.Cu")
		(net 1296)
	)
	(segment
		(start 233.6 138.1745)
		(end 233.675 138.2495)
		(width 0.182)
		(layer "F.Cu")
		(net 1296)
	)
	(segment
		(start 234.4 145.2)
		(end 235.65 146.45)
		(width 0.182)
		(layer "F.Cu")
		(net 1296)
	)
	(segment
		(start 233.675 142.875)
		(end 234.4 143.6)
		(width 0.182)
		(layer "F.Cu")
		(net 1296)
	)
	(segment
		(start 234.4 143.6)
		(end 234.4 145.2)
		(width 0.182)
		(layer "F.Cu")
		(net 1296)
	)
	(segment
		(start 233.675 138.2495)
		(end 233.675 142.875)
		(width 0.182)
		(layer "F.Cu")
		(net 1296)
	)
	(segment
		(start 206.5 130.5)
		(end 207 131)
		(width 0.256)
		(layer "F.Cu")
		(net 1296)
	)
	(via
		(at 207 131)
		(size 0.45)
		(drill 0.2)
		(layers "F.Cu" "B.Cu")
		(net 1296)
	)
	(via
		(at 233.6 138.1745)
		(size 0.45)
		(drill 0.2)
		(layers "F.Cu" "B.Cu")
		(net 1296)
	)
	(via
		(at 254.1 147.3)
		(size 0.45)
		(drill 0.2)
		(layers "F.Cu" "B.Cu")
		(net 1296)
	)
	(segment
		(start 254.1 148.273)
		(end 254.1 147.3)
		(width 0.1)
		(layer "B.Cu")
		(net 1296)
	)
	(segment
		(start 203.692158 136.625)
		(end 215.725 136.625)
		(width 0.1)
		(layer "In7.Cu")
		(net 1296)
	)
	(segment
		(start 253.475 144.15)
		(end 245.425 144.15)
		(width 0.1)
		(layer "In7.Cu")
		(net 1296)
	)
	(segment
		(start 239.36 132.873173)
		(end 239.36 132.482842)
		(width 0.1)
		(layer "In7.Cu")
		(net 1296)
	)
	(segment
		(start 245.425 144.15)
		(end 244.33 143.055)
		(width 0.1)
		(layer "In7.Cu")
		(net 1296)
	)
	(segment
		(start 254.1 144.775)
		(end 253.475 144.15)
		(width 0.1)
		(layer "In7.Cu")
		(net 1296)
	)
	(segment
		(start 203.4 136.332843)
		(end 203.692158 136.625)
		(width 0.1)
		(layer "In7.Cu")
		(net 1296)
	)
	(segment
		(start 232.1155 136.69)
		(end 233.6 138.1745)
		(width 0.1)
		(layer "In7.Cu")
		(net 1296)
	)
	(segment
		(start 216.49 137.39)
		(end 222.137158 137.39)
		(width 0.1)
		(layer "In7.Cu")
		(net 1296)
	)
	(segment
		(start 234.162373 137.612127)
		(end 233.6 138.1745)
		(width 0.1)
		(layer "In7.Cu")
		(net 1296)
	)
	(segment
		(start 254.1 147.3)
		(end 254.1 144.775)
		(width 0.1)
		(layer "In7.Cu")
		(net 1296)
	)
	(segment
		(start 244.33 143.055)
		(end 244.33 141.6)
		(width 0.1)
		(layer "In7.Cu")
		(net 1296)
	)
	(segment
		(start 244.96 137.983526)
		(end 240.306474 133.33)
		(width 0.1)
		(layer "In7.Cu")
		(net 1296)
	)
	(segment
		(start 239.36 132.482842)
		(end 239.117158 132.24)
		(width 0.1)
		(layer "In7.Cu")
		(net 1296)
	)
	(segment
		(start 206.4 130.4)
		(end 203.667158 130.4)
		(width 0.1)
		(layer "In7.Cu")
		(net 1296)
	)
	(segment
		(start 207 131)
		(end 206.4 130.4)
		(width 0.1)
		(layer "In7.Cu")
		(net 1296)
	)
	(segment
		(start 244.33 141.6)
		(end 244.96 140.97)
		(width 0.1)
		(layer "In7.Cu")
		(net 1296)
	)
	(segment
		(start 244.96 140.97)
		(end 244.96 137.983526)
		(width 0.1)
		(layer "In7.Cu")
		(net 1296)
	)
	(segment
		(start 239.816827 133.33)
		(end 239.36 132.873173)
		(width 0.1)
		(layer "In7.Cu")
		(net 1296)
	)
	(segment
		(start 203.667158 130.4)
		(end 203.4 130.667158)
		(width 0.1)
		(layer "In7.Cu")
		(net 1296)
	)
	(segment
		(start 239.117158 132.24)
		(end 234.71 132.24)
		(width 0.1)
		(layer "In7.Cu")
		(net 1296)
	)
	(segment
		(start 234.162373 132.787627)
		(end 234.162373 137.612127)
		(width 0.1)
		(layer "In7.Cu")
		(net 1296)
	)
	(segment
		(start 222.137158 137.39)
		(end 222.837158 136.69)
		(width 0.1)
		(layer "In7.Cu")
		(net 1296)
	)
	(segment
		(start 222.837158 136.69)
		(end 232.1155 136.69)
		(width 0.1)
		(layer "In7.Cu")
		(net 1296)
	)
	(segment
		(start 203.4 130.667158)
		(end 203.4 136.332843)
		(width 0.1)
		(layer "In7.Cu")
		(net 1296)
	)
	(segment
		(start 215.725 136.625)
		(end 216.49 137.39)
		(width 0.1)
		(layer "In7.Cu")
		(net 1296)
	)
	(segment
		(start 234.71 132.24)
		(end 234.162373 132.787627)
		(width 0.1)
		(layer "In7.Cu")
		(net 1296)
	)
	(segment
		(start 240.306474 133.33)
		(end 239.816827 133.33)
		(width 0.1)
		(layer "In7.Cu")
		(net 1296)
	)
	(segment
		(start 234.4 142.142)
		(end 234.4 138.2)
		(width 0.182)
		(layer "F.Cu")
		(net 1297)
	)
	(segment
		(start 207.5 130.5)
		(end 208 131)
		(width 0.256)
		(layer "F.Cu")
		(net 1297)
	)
	(segment
		(start 234.616 137.984)
		(end 234.616 137.356464)
		(width 0.182)
		(layer "F.Cu")
		(net 1297)
	)
	(segment
		(start 234.616 137.356464)
		(end 234.537373 137.277837)
		(width 0.182)
		(layer "F.Cu")
		(net 1297)
	)
	(segment
		(start 235.3 143.042)
		(end 234.4 142.142)
		(width 0.182)
		(layer "F.Cu")
		(net 1297)
	)
	(segment
		(start 235.865 144.45)
		(end 235.55 144.45)
		(width 0.182)
		(layer "F.Cu")
		(net 1297)
	)
	(segment
		(start 234.4 138.2)
		(end 234.616 137.984)
		(width 0.182)
		(layer "F.Cu")
		(net 1297)
	)
	(segment
		(start 235.55 144.45)
		(end 235.3 144.2)
		(width 0.182)
		(layer "F.Cu")
		(net 1297)
	)
	(segment
		(start 235.3 144.2)
		(end 235.3 143.042)
		(width 0.182)
		(layer "F.Cu")
		(net 1297)
	)
	(via
		(at 208 131)
		(size 0.45)
		(drill 0.2)
		(layers "F.Cu" "B.Cu")
		(net 1297)
	)
	(via
		(at 253.525 147.325)
		(size 0.45)
		(drill 0.2)
		(layers "F.Cu" "B.Cu")
		(net 1297)
	)
	(via
		(at 234.537373 137.277837)
		(size 0.45)
		(drill 0.2)
		(layers "F.Cu" "B.Cu")
		(net 1297)
	)
	(segment
		(start 253.7 148.273)
		(end 253.7 147.5)
		(width 0.1)
		(layer "B.Cu")
		(net 1297)
	)
	(segment
		(start 253.7 147.5)
		(end 253.525 147.325)
		(width 0.1)
		(layer "B.Cu")
		(net 1297)
	)
	(segment
		(start 202.8 137.4)
		(end 202.6 137.2)
		(width 0.1)
		(layer "In7.Cu")
		(net 1297)
	)
	(segment
		(start 234.110171 138.608579)
		(end 233.291421 138.608579)
		(width 0.1)
		(layer "In7.Cu")
		(net 1297)
	)
	(segment
		(start 242.425 137.544669)
		(end 242.65 137.319669)
		(width 0.1)
		(layer "In7.Cu")
		(net 1297)
	)
	(segment
		(start 234.575 137.315464)
		(end 234.575 138.143751)
		(width 0.1)
		(layer "In7.Cu")
		(net 1297)
	)
	(segment
		(start 253.525 145)
		(end 252.975 144.45)
		(width 0.1)
		(layer "In7.Cu")
		(net 1297)
	)
	(segment
		(start 239.313985 133.11)
		(end 236.27 133.11)
		(width 0.1)
		(layer "In7.Cu")
		(net 1297)
	)
	(segment
		(start 235.15 136.66521)
		(end 234.537373 137.277837)
		(width 0.1)
		(layer "In7.Cu")
		(net 1297)
	)
	(segment
		(start 203.59 137.64)
		(end 203.35 137.4)
		(width 0.1)
		(layer "In7.Cu")
		(net 1297)
	)
	(segment
		(start 252.975 144.45)
		(end 244.225 144.45)
		(width 0.1)
		(layer "In7.Cu")
		(net 1297)
	)
	(segment
		(start 235.15 134.23)
		(end 235.15 136.66521)
		(width 0.1)
		(layer "In7.Cu")
		(net 1297)
	)
	(segment
		(start 202.6 137.2)
		(end 202.6 130.15)
		(width 0.1)
		(layer "In7.Cu")
		(net 1297)
	)
	(segment
		(start 253.525 147.325)
		(end 253.525 145)
		(width 0.1)
		(layer "In7.Cu")
		(net 1297)
	)
	(segment
		(start 231.572842 136.89)
		(end 224.377158 136.89)
		(width 0.1)
		(layer "In7.Cu")
		(net 1297)
	)
	(segment
		(start 242.65 137.319669)
		(end 242.65 135.956368)
		(width 0.1)
		(layer "In7.Cu")
		(net 1297)
	)
	(segment
		(start 234.575 138.143751)
		(end 234.110171 138.608579)
		(width 0.1)
		(layer "In7.Cu")
		(net 1297)
	)
	(segment
		(start 239.733985 133.53)
		(end 239.313985 133.11)
		(width 0.1)
		(layer "In7.Cu")
		(net 1297)
	)
	(segment
		(start 236.27 133.11)
		(end 235.15 134.23)
		(width 0.1)
		(layer "In7.Cu")
		(net 1297)
	)
	(segment
		(start 207.15 129.6)
		(end 207.4 129.85)
		(width 0.1)
		(layer "In7.Cu")
		(net 1297)
	)
	(segment
		(start 217.53 139.41)
		(end 204.54 139.41)
		(width 0.1)
		(layer "In7.Cu")
		(net 1297)
	)
	(segment
		(start 204.54 139.41)
		(end 203.59 138.46)
		(width 0.1)
		(layer "In7.Cu")
		(net 1297)
	)
	(segment
		(start 244.225 144.45)
		(end 242.425 142.65)
		(width 0.1)
		(layer "In7.Cu")
		(net 1297)
	)
	(segment
		(start 234.537373 137.277837)
		(end 234.575 137.315464)
		(width 0.1)
		(layer "In7.Cu")
		(net 1297)
	)
	(segment
		(start 207.4 130.4)
		(end 208 131)
		(width 0.1)
		(layer "In7.Cu")
		(net 1297)
	)
	(segment
		(start 220.717158 140.55)
		(end 218.67 140.55)
		(width 0.1)
		(layer "In7.Cu")
		(net 1297)
	)
	(segment
		(start 242.65 135.956368)
		(end 240.223632 133.53)
		(width 0.1)
		(layer "In7.Cu")
		(net 1297)
	)
	(segment
		(start 233.291421 138.608579)
		(end 231.572842 136.89)
		(width 0.1)
		(layer "In7.Cu")
		(net 1297)
	)
	(segment
		(start 203.35 137.4)
		(end 202.8 137.4)
		(width 0.1)
		(layer "In7.Cu")
		(net 1297)
	)
	(segment
		(start 224.377158 136.89)
		(end 220.717158 140.55)
		(width 0.1)
		(layer "In7.Cu")
		(net 1297)
	)
	(segment
		(start 242.425 142.65)
		(end 242.425 137.544669)
		(width 0.1)
		(layer "In7.Cu")
		(net 1297)
	)
	(segment
		(start 218.67 140.55)
		(end 217.53 139.41)
		(width 0.1)
		(layer "In7.Cu")
		(net 1297)
	)
	(segment
		(start 202.6 130.15)
		(end 203.15 129.6)
		(width 0.1)
		(layer "In7.Cu")
		(net 1297)
	)
	(segment
		(start 203.15 129.6)
		(end 207.15 129.6)
		(width 0.1)
		(layer "In7.Cu")
		(net 1297)
	)
	(segment
		(start 207.4 129.85)
		(end 207.4 130.4)
		(width 0.1)
		(layer "In7.Cu")
		(net 1297)
	)
	(segment
		(start 203.59 138.46)
		(end 203.59 137.64)
		(width 0.1)
		(layer "In7.Cu")
		(net 1297)
	)
	(segment
		(start 240.223632 133.53)
		(end 239.733985 133.53)
		(width 0.1)
		(layer "In7.Cu")
		(net 1297)
	)
	(segment
		(start 255.7 83.8)
		(end 256.35 83.15)
		(width 0.1)
		(layer "F.Cu")
		(net 1299)
	)
	(segment
		(start 214.5 134.5)
		(end 215.025 135.025)
		(width 0.256)
		(layer "F.Cu")
		(net 1299)
	)
	(segment
		(start 257.45 83.15)
		(end 258.235 83.15)
		(width 0.1)
		(layer "F.Cu")
		(net 1299)
	)
	(segment
		(start 258.235 83.15)
		(end 258.4 83.315)
		(width 0.1)
		(layer "F.Cu")
		(net 1299)
	)
	(segment
		(start 215.025 135.025)
		(end 215.056164 135.025)
		(width 0.256)
		(layer "F.Cu")
		(net 1299)
	)
	(segment
		(start 256.35 83.15)
		(end 257.45 83.15)
		(width 0.1)
		(layer "F.Cu")
		(net 1299)
	)
	(via
		(at 258.4 83.315)
		(size 0.45)
		(drill 0.2)
		(layers "F.Cu" "B.Cu")
		(net 1299)
	)
	(via
		(at 215.056164 135.025)
		(size 0.45)
		(drill 0.2)
		(layers "F.Cu" "B.Cu")
		(net 1299)
	)
	(via
		(at 255.7 83.8)
		(size 0.45)
		(drill 0.2)
		(layers "F.Cu" "B.Cu")
		(net 1299)
	)
	(segment
		(start 253.5 93.9)
		(end 253.5 86.4)
		(width 0.1)
		(layer "In3.Cu")
		(net 1299)
	)
	(segment
		(start 215.96421 135.25)
		(end 220.302948 135.25)
		(width 0.1)
		(layer "In3.Cu")
		(net 1299)
	)
	(segment
		(start 229.2 132.9)
		(end 229.2 107.099998)
		(width 0.1)
		(layer "In3.Cu")
		(net 1299)
	)
	(segment
		(start 253.5 86.4)
		(end 255.7 84.2)
		(width 0.1)
		(layer "In3.Cu")
		(net 1299)
	)
	(segment
		(start 215.056164 135.025)
		(end 215.73921 135.025)
		(width 0.1)
		(layer "In3.Cu")
		(net 1299)
	)
	(segment
		(start 220.502948 135.45)
		(end 226.65 135.45)
		(width 0.1)
		(layer "In3.Cu")
		(net 1299)
	)
	(segment
		(start 232.999998 103.3)
		(end 243.6 103.3)
		(width 0.1)
		(layer "In3.Cu")
		(net 1299)
	)
	(segment
		(start 215.73921 135.025)
		(end 215.96421 135.25)
		(width 0.1)
		(layer "In3.Cu")
		(net 1299)
	)
	(segment
		(start 253.2 94.2)
		(end 253.5 93.9)
		(width 0.1)
		(layer "In3.Cu")
		(net 1299)
	)
	(segment
		(start 220.302948 135.25)
		(end 220.502948 135.45)
		(width 0.1)
		(layer "In3.Cu")
		(net 1299)
	)
	(segment
		(start 229.2 107.099998)
		(end 232.999998 103.3)
		(width 0.1)
		(layer "In3.Cu")
		(net 1299)
	)
	(segment
		(start 243.6 103.3)
		(end 252.7 94.2)
		(width 0.1)
		(layer "In3.Cu")
		(net 1299)
	)
	(segment
		(start 255.7 84.2)
		(end 255.7 83.8)
		(width 0.1)
		(layer "In3.Cu")
		(net 1299)
	)
	(segment
		(start 252.7 94.2)
		(end 253.2 94.2)
		(width 0.1)
		(layer "In3.Cu")
		(net 1299)
	)
	(segment
		(start 226.65 135.45)
		(end 229.2 132.9)
		(width 0.1)
		(layer "In3.Cu")
		(net 1299)
	)
	(segment
		(start 211.5 142.5)
		(end 212 143)
		(width 0.256)
		(layer "F.Cu")
		(net 1300)
	)
	(segment
		(start 256.3 86.2)
		(end 256.95 85.55)
		(width 0.1)
		(layer "F.Cu")
		(net 1300)
	)
	(segment
		(start 257.45 85.55)
		(end 258.235 85.55)
		(width 0.1)
		(layer "F.Cu")
		(net 1300)
	)
	(segment
		(start 258.235 85.55)
		(end 258.4 85.715)
		(width 0.1)
		(layer "F.Cu")
		(net 1300)
	)
	(segment
		(start 256.95 85.55)
		(end 257.45 85.55)
		(width 0.1)
		(layer "F.Cu")
		(net 1300)
	)
	(via
		(at 216.8005 140.01)
		(size 0.45)
		(drill 0.2)
		(layers "F.Cu" "B.Cu")
		(net 1300)
	)
	(via
		(at 258.4 85.715)
		(size 0.45)
		(drill 0.2)
		(layers "F.Cu" "B.Cu")
		(net 1300)
	)
	(via
		(at 256.3 86.2)
		(size 0.45)
		(drill 0.2)
		(layers "F.Cu" "B.Cu")
		(net 1300)
	)
	(via
		(at 212 143)
		(size 0.45)
		(drill 0.2)
		(layers "F.Cu" "B.Cu")
		(net 1300)
	)
	(segment
		(start 212.5 142.5)
		(end 212 143)
		(width 0.1)
		(layer "B.Cu")
		(net 1300)
	)
	(segment
		(start 216.8005 140.01)
		(end 216.8 140.0105)
		(width 0.1)
		(layer "B.Cu")
		(net 1300)
	)
	(segment
		(start 216.8 140.0105)
		(end 216.8 142.3)
		(width 0.1)
		(layer "B.Cu")
		(net 1300)
	)
	(segment
		(start 216.8 142.3)
		(end 216.6 142.5)
		(width 0.1)
		(layer "B.Cu")
		(net 1300)
	)
	(segment
		(start 216.6 142.5)
		(end 212.5 142.5)
		(width 0.1)
		(layer "B.Cu")
		(net 1300)
	)
	(segment
		(start 233.025 125.4)
		(end 233.025 108.474998)
		(width 0.1)
		(layer "In3.Cu")
		(net 1300)
	)
	(segment
		(start 233.5 126.325)
		(end 233.5 125.875)
		(width 0.1)
		(layer "In3.Cu")
		(net 1300)
	)
	(segment
		(start 222.301474 138.6)
		(end 222.501474 138.4)
		(width 0.1)
		(layer "In3.Cu")
		(net 1300)
	)
	(segment
		(start 233.5 125.875)
		(end 233.025 125.4)
		(width 0.1)
		(layer "In3.Cu")
		(net 1300)
	)
	(segment
		(start 256.5 97.1)
		(end 256.5 86.4)
		(width 0.1)
		(layer "In3.Cu")
		(net 1300)
	)
	(segment
		(start 217.44 138.6)
		(end 222.301474 138.6)
		(width 0.1)
		(layer "In3.Cu")
		(net 1300)
	)
	(segment
		(start 246.4 107.2)
		(end 256.5 97.1)
		(width 0.1)
		(layer "In3.Cu")
		(net 1300)
	)
	(segment
		(start 217.21 138.83)
		(end 217.44 138.6)
		(width 0.1)
		(layer "In3.Cu")
		(net 1300)
	)
	(segment
		(start 233.025 108.474998)
		(end 234.299998 107.2)
		(width 0.1)
		(layer "In3.Cu")
		(net 1300)
	)
	(segment
		(start 217.21 139.6005)
		(end 217.21 138.83)
		(width 0.1)
		(layer "In3.Cu")
		(net 1300)
	)
	(segment
		(start 216.8005 140.01)
		(end 217.21 139.6005)
		(width 0.1)
		(layer "In3.Cu")
		(net 1300)
	)
	(segment
		(start 227.5 138.4)
		(end 233.1 132.8)
		(width 0.1)
		(layer "In3.Cu")
		(net 1300)
	)
	(segment
		(start 233.1 132.8)
		(end 233.1 126.725)
		(width 0.1)
		(layer "In3.Cu")
		(net 1300)
	)
	(segment
		(start 222.501474 138.4)
		(end 227.5 138.4)
		(width 0.1)
		(layer "In3.Cu")
		(net 1300)
	)
	(segment
		(start 256.5 86.4)
		(end 256.3 86.2)
		(width 0.1)
		(layer "In3.Cu")
		(net 1300)
	)
	(segment
		(start 233.1 126.725)
		(end 233.5 126.325)
		(width 0.1)
		(layer "In3.Cu")
		(net 1300)
	)
	(segment
		(start 234.299998 107.2)
		(end 246.4 107.2)
		(width 0.1)
		(layer "In3.Cu")
		(net 1300)
	)
	(segment
		(start 212.5 135.5)
		(end 213 136)
		(width 0.256)
		(layer "F.Cu")
		(net 1301)
	)
	(segment
		(start 256.45 87.95)
		(end 257.45 87.95)
		(width 0.1)
		(layer "F.Cu")
		(net 1301)
	)
	(segment
		(start 258.235 87.95)
		(end 258.4 88.115)
		(width 0.1)
		(layer "F.Cu")
		(net 1301)
	)
	(segment
		(start 257.45 87.95)
		(end 258.235 87.95)
		(width 0.1)
		(layer "F.Cu")
		(net 1301)
	)
	(segment
		(start 254.3 89.5)
		(end 254.9 89.5)
		(width 0.1)
		(layer "F.Cu")
		(net 1301)
	)
	(segment
		(start 254.9 89.5)
		(end 256.45 87.95)
		(width 0.1)
		(layer "F.Cu")
		(net 1301)
	)
	(via
		(at 254.3 89.5)
		(size 0.45)
		(drill 0.2)
		(layers "F.Cu" "B.Cu")
		(net 1301)
	)
	(via
		(at 258.4 88.115)
		(size 0.45)
		(drill 0.2)
		(layers "F.Cu" "B.Cu")
		(net 1301)
	)
	(via
		(at 213 136)
		(size 0.45)
		(drill 0.2)
		(layers "F.Cu" "B.Cu")
		(net 1301)
	)
	(segment
		(start 215.798524 135.65)
		(end 215.773524 135.625)
		(width 0.1)
		(layer "In3.Cu")
		(net 1301)
	)
	(segment
		(start 253.9 94.299998)
		(end 253.3 94.9)
		(width 0.1)
		(layer "In3.Cu")
		(net 1301)
	)
	(segment
		(start 220.337264 135.85)
		(end 220.137264 135.65)
		(width 0.1)
		(layer "In3.Cu")
		(net 1301)
	)
	(segment
		(start 254.3 89.5)
		(end 254.5 89.7)
		(width 0.1)
		(layer "In3.Cu")
		(net 1301)
	)
	(segment
		(start 229.8 132.865684)
		(end 226.815684 135.85)
		(width 0.1)
		(layer "In3.Cu")
		(net 1301)
	)
	(segment
		(start 253.9 93.2)
		(end 253.9 94.299998)
		(width 0.1)
		(layer "In3.Cu")
		(net 1301)
	)
	(segment
		(start 220.137264 135.65)
		(end 215.798524 135.65)
		(width 0.1)
		(layer "In3.Cu")
		(net 1301)
	)
	(segment
		(start 254.5 92.6)
		(end 253.9 93.2)
		(width 0.1)
		(layer "In3.Cu")
		(net 1301)
	)
	(segment
		(start 233.199998 103.9)
		(end 229.8 107.299998)
		(width 0.1)
		(layer "In3.Cu")
		(net 1301)
	)
	(segment
		(start 243.9 103.9)
		(end 233.199998 103.9)
		(width 0.1)
		(layer "In3.Cu")
		(net 1301)
	)
	(segment
		(start 215.773524 135.625)
		(end 213.375 135.625)
		(width 0.1)
		(layer "In3.Cu")
		(net 1301)
	)
	(segment
		(start 229.8 107.299998)
		(end 229.8 132.865684)
		(width 0.1)
		(layer "In3.Cu")
		(net 1301)
	)
	(segment
		(start 254.5 89.7)
		(end 254.5 92.6)
		(width 0.1)
		(layer "In3.Cu")
		(net 1301)
	)
	(segment
		(start 252.9 94.9)
		(end 243.9 103.9)
		(width 0.1)
		(layer "In3.Cu")
		(net 1301)
	)
	(segment
		(start 213.375 135.625)
		(end 213 136)
		(width 0.1)
		(layer "In3.Cu")
		(net 1301)
	)
	(segment
		(start 253.3 94.9)
		(end 252.9 94.9)
		(width 0.1)
		(layer "In3.Cu")
		(net 1301)
	)
	(segment
		(start 226.815684 135.85)
		(end 220.337264 135.85)
		(width 0.1)
		(layer "In3.Cu")
		(net 1301)
	)
	(segment
		(start 210.987717 136.000037)
		(end 210.987717 135.987717)
		(width 0.256)
		(layer "F.Cu")
		(net 1302)
	)
	(segment
		(start 254.75 90.35)
		(end 257.45 90.35)
		(width 0.1)
		(layer "F.Cu")
		(net 1302)
	)
	(segment
		(start 258.235 90.35)
		(end 258.4 90.515)
		(width 0.1)
		(layer "F.Cu")
		(net 1302)
	)
	(segment
		(start 210.987717 135.987717)
		(end 210.5 135.5)
		(width 0.256)
		(layer "F.Cu")
		(net 1302)
	)
	(segment
		(start 257.45 90.35)
		(end 258.235 90.35)
		(width 0.1)
		(layer "F.Cu")
		(net 1302)
	)
	(segment
		(start 254.1 91)
		(end 254.75 90.35)
		(width 0.1)
		(layer "F.Cu")
		(net 1302)
	)
	(via
		(at 210.987717 136.000037)
		(size 0.45)
		(drill 0.2)
		(layers "F.Cu" "B.Cu")
		(net 1302)
	)
	(via
		(at 254.1 91)
		(size 0.45)
		(drill 0.2)
		(layers "F.Cu" "B.Cu")
		(net 1302)
	)
	(via
		(at 258.4 90.515)
		(size 0.45)
		(drill 0.2)
		(layers "F.Cu" "B.Cu")
		(net 1302)
	)
	(segment
		(start 220.220106 135.45)
		(end 220.420106 135.65)
		(width 0.1)
		(layer "In3.Cu")
		(net 1302)
	)
	(segment
		(start 229.5 107.199998)
		(end 233.099998 103.6)
		(width 0.1)
		(layer "In3.Cu")
		(net 1302)
	)
	(segment
		(start 253.7 93.1)
		(end 254.3 92.5)
		(width 0.1)
		(layer "In3.Cu")
		(net 1302)
	)
	(segment
		(start 226.732842 135.65)
		(end 229.5 132.882842)
		(width 0.1)
		(layer "In3.Cu")
		(net 1302)
	)
	(segment
		(start 229.5 132.882842)
		(end 229.5 107.199998)
		(width 0.1)
		(layer "In3.Cu")
		(net 1302)
	)
	(segment
		(start 220.420106 135.65)
		(end 226.732842 135.65)
		(width 0.1)
		(layer "In3.Cu")
		(net 1302)
	)
	(segment
		(start 254.3 92.5)
		(end 254.3 91.2)
		(width 0.1)
		(layer "In3.Cu")
		(net 1302)
	)
	(segment
		(start 253.7 94.099998)
		(end 253.7 93.1)
		(width 0.1)
		(layer "In3.Cu")
		(net 1302)
	)
	(segment
		(start 252.9 94.5)
		(end 253.299998 94.5)
		(width 0.1)
		(layer "In3.Cu")
		(net 1302)
	)
	(segment
		(start 233.099998 103.6)
		(end 243.8 103.6)
		(width 0.1)
		(layer "In3.Cu")
		(net 1302)
	)
	(segment
		(start 253.299998 94.5)
		(end 253.7 94.099998)
		(width 0.1)
		(layer "In3.Cu")
		(net 1302)
	)
	(segment
		(start 210.987717 136.000037)
		(end 211.562754 135.425)
		(width 0.1)
		(layer "In3.Cu")
		(net 1302)
	)
	(segment
		(start 254.3 91.2)
		(end 254.1 91)
		(width 0.1)
		(layer "In3.Cu")
		(net 1302)
	)
	(segment
		(start 211.562754 135.425)
		(end 215.856367 135.425)
		(width 0.1)
		(layer "In3.Cu")
		(net 1302)
	)
	(segment
		(start 215.856367 135.425)
		(end 215.881367 135.45)
		(width 0.1)
		(layer "In3.Cu")
		(net 1302)
	)
	(segment
		(start 243.8 103.6)
		(end 252.9 94.5)
		(width 0.1)
		(layer "In3.Cu")
		(net 1302)
	)
	(segment
		(start 215.881367 135.45)
		(end 220.220106 135.45)
		(width 0.1)
		(layer "In3.Cu")
		(net 1302)
	)
	(segment
		(start 258.235 92.75)
		(end 258.4 92.915)
		(width 0.1)
		(layer "F.Cu")
		(net 1303)
	)
	(segment
		(start 254.95 92.75)
		(end 257.45 92.75)
		(width 0.1)
		(layer "F.Cu")
		(net 1303)
	)
	(segment
		(start 257.45 92.75)
		(end 258.235 92.75)
		(width 0.1)
		(layer "F.Cu")
		(net 1303)
	)
	(segment
		(start 254.3 93.4)
		(end 254.95 92.75)
		(width 0.1)
		(layer "F.Cu")
		(net 1303)
	)
	(segment
		(start 214.5 135.5)
		(end 215 136)
		(width 0.256)
		(layer "F.Cu")
		(net 1303)
	)
	(via
		(at 254.3 93.4)
		(size 0.45)
		(drill 0.2)
		(layers "F.Cu" "B.Cu")
		(net 1303)
	)
	(via
		(at 215 136)
		(size 0.45)
		(drill 0.2)
		(layers "F.Cu" "B.Cu")
		(net 1303)
	)
	(via
		(at 258.4 92.915)
		(size 0.45)
		(drill 0.2)
		(layers "F.Cu" "B.Cu")
		(net 1303)
	)
	(segment
		(start 253.4 95.2)
		(end 254.5 94.1)
		(width 0.1)
		(layer "In3.Cu")
		(net 1303)
	)
	(segment
		(start 254.5 93.6)
		(end 254.3 93.4)
		(width 0.1)
		(layer "In3.Cu")
		(net 1303)
	)
	(segment
		(start 216.465684 136.6)
		(end 221.473048 136.6)
		(width 0.1)
		(layer "In3.Cu")
		(net 1303)
	)
	(segment
		(start 253 95.2)
		(end 253.4 95.2)
		(width 0.1)
		(layer "In3.Cu")
		(net 1303)
	)
	(segment
		(start 216.040684 136.175)
		(end 216.465684 136.6)
		(width 0.1)
		(layer "In3.Cu")
		(net 1303)
	)
	(segment
		(start 244 104.2)
		(end 253 95.2)
		(width 0.1)
		(layer "In3.Cu")
		(net 1303)
	)
	(segment
		(start 230.1 107.399998)
		(end 233.299998 104.2)
		(width 0.1)
		(layer "In3.Cu")
		(net 1303)
	)
	(segment
		(start 221.473048 136.6)
		(end 221.673048 136.4)
		(width 0.1)
		(layer "In3.Cu")
		(net 1303)
	)
	(segment
		(start 215 136)
		(end 215.175 136.175)
		(width 0.1)
		(layer "In3.Cu")
		(net 1303)
	)
	(segment
		(start 230.1 132.848526)
		(end 230.1 107.399998)
		(width 0.1)
		(layer "In3.Cu")
		(net 1303)
	)
	(segment
		(start 226.548526 136.4)
		(end 230.1 132.848526)
		(width 0.1)
		(layer "In3.Cu")
		(net 1303)
	)
	(segment
		(start 254.5 94.1)
		(end 254.5 93.6)
		(width 0.1)
		(layer "In3.Cu")
		(net 1303)
	)
	(segment
		(start 215.175 136.175)
		(end 216.040684 136.175)
		(width 0.1)
		(layer "In3.Cu")
		(net 1303)
	)
	(segment
		(start 221.673048 136.4)
		(end 226.548526 136.4)
		(width 0.1)
		(layer "In3.Cu")
		(net 1303)
	)
	(segment
		(start 233.299998 104.2)
		(end 244 104.2)
		(width 0.1)
		(layer "In3.Cu")
		(net 1303)
	)
	(segment
		(start 258.235 95.15)
		(end 258.4 95.315)
		(width 0.1)
		(layer "F.Cu")
		(net 1304)
	)
	(segment
		(start 254.65 95.15)
		(end 257.45 95.15)
		(width 0.1)
		(layer "F.Cu")
		(net 1304)
	)
	(segment
		(start 257.45 95.15)
		(end 258.235 95.15)
		(width 0.1)
		(layer "F.Cu")
		(net 1304)
	)
	(segment
		(start 210.5 134.5)
		(end 211 135)
		(width 0.256)
		(layer "F.Cu")
		(net 1304)
	)
	(segment
		(start 252.9 93.4)
		(end 254.65 95.15)
		(width 0.1)
		(layer "F.Cu")
		(net 1304)
	)
	(via
		(at 252.9 93.4)
		(size 0.45)
		(drill 0.2)
		(layers "F.Cu" "B.Cu")
		(net 1304)
	)
	(via
		(at 211 135)
		(size 0.45)
		(drill 0.2)
		(layers "F.Cu" "B.Cu")
		(net 1304)
	)
	(via
		(at 258.4 95.315)
		(size 0.45)
		(drill 0.2)
		(layers "F.Cu" "B.Cu")
		(net 1304)
	)
	(segment
		(start 220.668632 135.05)
		(end 226.432842 135.05)
		(width 0.1)
		(layer "In3.Cu")
		(net 1304)
	)
	(segment
		(start 243.3 102.7)
		(end 252.6 93.4)
		(width 0.1)
		(layer "In3.Cu")
		(net 1304)
	)
	(segment
		(start 228.6 106.899998)
		(end 232.8 102.7)
		(width 0.1)
		(layer "In3.Cu")
		(net 1304)
	)
	(segment
		(start 211.575 134.425)
		(end 215.704894 134.425)
		(width 0.1)
		(layer "In3.Cu")
		(net 1304)
	)
	(segment
		(start 226.432842 135.05)
		(end 228.600001 132.882841)
		(width 0.1)
		(layer "In3.Cu")
		(net 1304)
	)
	(segment
		(start 220.468632 134.85)
		(end 220.668632 135.05)
		(width 0.1)
		(layer "In3.Cu")
		(net 1304)
	)
	(segment
		(start 228.600001 132.882841)
		(end 228.6 106.899998)
		(width 0.1)
		(layer "In3.Cu")
		(net 1304)
	)
	(segment
		(start 216.129894 134.85)
		(end 220.468632 134.85)
		(width 0.1)
		(layer "In3.Cu")
		(net 1304)
	)
	(segment
		(start 252.6 93.4)
		(end 252.9 93.4)
		(width 0.1)
		(layer "In3.Cu")
		(net 1304)
	)
	(segment
		(start 215.704894 134.425)
		(end 216.129894 134.85)
		(width 0.1)
		(layer "In3.Cu")
		(net 1304)
	)
	(segment
		(start 232.8 102.7)
		(end 243.3 102.7)
		(width 0.1)
		(layer "In3.Cu")
		(net 1304)
	)
	(segment
		(start 211 135)
		(end 211.575 134.425)
		(width 0.1)
		(layer "In3.Cu")
		(net 1304)
	)
	(segment
		(start 255.3 79.6)
		(end 256.55 78.35)
		(width 0.1)
		(layer "F.Cu")
		(net 1305)
	)
	(segment
		(start 257.45 78.35)
		(end 258.235 78.35)
		(width 0.1)
		(layer "F.Cu")
		(net 1305)
	)
	(segment
		(start 212.5 134.5)
		(end 213 135)
		(width 0.256)
		(layer "F.Cu")
		(net 1305)
	)
	(segment
		(start 255.3 80.8)
		(end 255.3 79.6)
		(width 0.1)
		(layer "F.Cu")
		(net 1305)
	)
	(segment
		(start 258.235 78.35)
		(end 258.4 78.515)
		(width 0.1)
		(layer "F.Cu")
		(net 1305)
	)
	(segment
		(start 256.55 78.35)
		(end 257.45 78.35)
		(width 0.1)
		(layer "F.Cu")
		(net 1305)
	)
	(via
		(at 258.4 78.515)
		(size 0.45)
		(drill 0.2)
		(layers "F.Cu" "B.Cu")
		(net 1305)
	)
	(via
		(at 255.3 80.8)
		(size 0.45)
		(drill 0.2)
		(layers "F.Cu" "B.Cu")
		(net 1305)
	)
	(via
		(at 213 135)
		(size 0.45)
		(drill 0.2)
		(layers "F.Cu" "B.Cu")
		(net 1305)
	)
	(segment
		(start 216.047052 135.05)
		(end 215.622052 134.625)
		(width 0.1)
		(layer "In3.Cu")
		(net 1305)
	)
	(segment
		(start 253.3 86.3)
		(end 253.3 93.7)
		(width 0.1)
		(layer "In3.Cu")
		(net 1305)
	)
	(segment
		(start 253.3 93.7)
		(end 253.1 93.9)
		(width 0.1)
		(layer "In3.Cu")
		(net 1305)
	)
	(segment
		(start 226.55 135.25)
		(end 220.58579 135.25)
		(width 0.1)
		(layer "In3.Cu")
		(net 1305)
	)
	(segment
		(start 213.375 134.625)
		(end 213 135)
		(width 0.1)
		(layer "In3.Cu")
		(net 1305)
	)
	(segment
		(start 220.38579 135.05)
		(end 216.047052 135.05)
		(width 0.1)
		(layer "In3.Cu")
		(net 1305)
	)
	(segment
		(start 228.9 132.9)
		(end 226.55 135.25)
		(width 0.1)
		(layer "In3.Cu")
		(net 1305)
	)
	(segment
		(start 220.58579 135.25)
		(end 220.38579 135.05)
		(width 0.1)
		(layer "In3.Cu")
		(net 1305)
	)
	(segment
		(start 255.3 84.3)
		(end 253.3 86.3)
		(width 0.1)
		(layer "In3.Cu")
		(net 1305)
	)
	(segment
		(start 232.899998 103)
		(end 228.9 106.999998)
		(width 0.1)
		(layer "In3.Cu")
		(net 1305)
	)
	(segment
		(start 253.1 93.9)
		(end 252.5 93.9)
		(width 0.1)
		(layer "In3.Cu")
		(net 1305)
	)
	(segment
		(start 252.5 93.9)
		(end 243.4 103)
		(width 0.1)
		(layer "In3.Cu")
		(net 1305)
	)
	(segment
		(start 243.4 103)
		(end 232.899998 103)
		(width 0.1)
		(layer "In3.Cu")
		(net 1305)
	)
	(segment
		(start 215.622052 134.625)
		(end 213.375 134.625)
		(width 0.1)
		(layer "In3.Cu")
		(net 1305)
	)
	(segment
		(start 255.3 80.8)
		(end 255.3 84.3)
		(width 0.1)
		(layer "In3.Cu")
		(net 1305)
	)
	(segment
		(start 228.9 106.999998)
		(end 228.9 132.9)
		(width 0.1)
		(layer "In3.Cu")
		(net 1305)
	)
	(segment
		(start 257.45 80.75)
		(end 258.235 80.75)
		(width 0.1)
		(layer "F.Cu")
		(net 1307)
	)
	(segment
		(start 212.5 136.5)
		(end 213 137)
		(width 0.256)
		(layer "F.Cu")
		(net 1307)
	)
	(segment
		(start 258.235 80.75)
		(end 258.4 80.915)
		(width 0.1)
		(layer "F.Cu")
		(net 1307)
	)
	(segment
		(start 256.55 80.75)
		(end 257.45 80.75)
		(width 0.1)
		(layer "F.Cu")
		(net 1307)
	)
	(segment
		(start 255.9 81.4)
		(end 256.55 80.75)
		(width 0.1)
		(layer "F.Cu")
		(net 1307)
	)
	(via
		(at 255.9 81.4)
		(size 0.45)
		(drill 0.2)
		(layers "F.Cu" "B.Cu")
		(net 1307)
	)
	(via
		(at 213 137)
		(size 0.45)
		(drill 0.2)
		(layers "F.Cu" "B.Cu")
		(net 1307)
	)
	(via
		(at 258.4 80.915)
		(size 0.45)
		(drill 0.2)
		(layers "F.Cu" "B.Cu")
		(net 1307)
	)
	(segment
		(start 255.3 87.9)
		(end 254.5 87.1)
		(width 0.1)
		(layer "In3.Cu")
		(net 1307)
	)
	(segment
		(start 226.882842 137.2)
		(end 231.3 132.782842)
		(width 0.1)
		(layer "In3.Cu")
		(net 1307)
	)
	(segment
		(start 256.1 84.1)
		(end 256.1 81.6)
		(width 0.1)
		(layer "In3.Cu")
		(net 1307)
	)
	(segment
		(start 254.5 85.7)
		(end 256.1 84.1)
		(width 0.1)
		(layer "In3.Cu")
		(net 1307)
	)
	(segment
		(start 253.5 96.4)
		(end 253.799998 96.4)
		(width 0.1)
		(layer "In3.Cu")
		(net 1307)
	)
	(segment
		(start 256.1 81.6)
		(end 255.9 81.4)
		(width 0.1)
		(layer "In3.Cu")
		(net 1307)
	)
	(segment
		(start 233.699998 105.4)
		(end 244.5 105.4)
		(width 0.1)
		(layer "In3.Cu")
		(net 1307)
	)
	(segment
		(start 231.3 107.799998)
		(end 233.699998 105.4)
		(width 0.1)
		(layer "In3.Cu")
		(net 1307)
	)
	(segment
		(start 254.5 87.1)
		(end 254.5 85.7)
		(width 0.1)
		(layer "In3.Cu")
		(net 1307)
	)
	(segment
		(start 222.004419 137.2)
		(end 226.882842 137.2)
		(width 0.1)
		(layer "In3.Cu")
		(net 1307)
	)
	(segment
		(start 244.5 105.4)
		(end 253.5 96.4)
		(width 0.1)
		(layer "In3.Cu")
		(net 1307)
	)
	(segment
		(start 213 137)
		(end 213.4 137.4)
		(width 0.1)
		(layer "In3.Cu")
		(net 1307)
	)
	(segment
		(start 253.799998 96.4)
		(end 255.3 94.899998)
		(width 0.1)
		(layer "In3.Cu")
		(net 1307)
	)
	(segment
		(start 255.3 94.899998)
		(end 255.3 87.9)
		(width 0.1)
		(layer "In3.Cu")
		(net 1307)
	)
	(segment
		(start 231.3 132.782842)
		(end 231.3 107.799998)
		(width 0.1)
		(layer "In3.Cu")
		(net 1307)
	)
	(segment
		(start 221.804419 137.4)
		(end 222.004419 137.2)
		(width 0.1)
		(layer "In3.Cu")
		(net 1307)
	)
	(segment
		(start 213.4 137.4)
		(end 221.804419 137.4)
		(width 0.1)
		(layer "In3.Cu")
		(net 1307)
	)
	(segment
		(start 256.675 76.925)
		(end 256.7 76.95)
		(width 0.1)
		(layer "F.Cu")
		(net 1308)
	)
	(segment
		(start 256.675 76.025)
		(end 256.675 76.925)
		(width 0.1)
		(layer "F.Cu")
		(net 1308)
	)
	(segment
		(start 193.01 137.99)
		(end 192.94 137.99)
		(width 0.256)
		(layer "F.Cu")
		(net 1308)
	)
	(segment
		(start 193.5 137.5)
		(end 193.01 137.99)
		(width 0.256)
		(layer "F.Cu")
		(net 1308)
	)
	(via
		(at 192.94 137.99)
		(size 0.45)
		(drill 0.2)
		(layers "F.Cu" "B.Cu")
		(net 1308)
	)
	(via
		(at 256.675 76.025)
		(size 0.45)
		(drill 0.2)
		(layers "F.Cu" "B.Cu")
		(net 1308)
	)
	(via
		(at 256.7 75.1)
		(size 0.45)
		(drill 0.2)
		(layers "F.Cu" "B.Cu")
		(net 1308)
	)
	(segment
		(start 256.2 75.795)
		(end 256.445 75.795)
		(width 0.1)
		(layer "B.Cu")
		(net 1308)
	)
	(segment
		(start 256.2 75.795)
		(end 256.2 75.025)
		(width 0.1)
		(layer "B.Cu")
		(net 1308)
	)
	(segment
		(start 256.625 75.025)
		(end 256.7 75.1)
		(width 0.1)
		(layer "B.Cu")
		(net 1308)
	)
	(segment
		(start 256.445 75.795)
		(end 256.675 76.025)
		(width 0.1)
		(layer "B.Cu")
		(net 1308)
	)
	(segment
		(start 256.2 75.025)
		(end 256.625 75.025)
		(width 0.1)
		(layer "B.Cu")
		(net 1308)
	)
	(segment
		(start 256.2 74.1)
		(end 256.2 75.025)
		(width 0.1)
		(layer "B.Cu")
		(net 1308)
	)
	(segment
		(start 255.8 73.7)
		(end 256.2 74.1)
		(width 0.1)
		(layer "B.Cu")
		(net 1308)
	)
	(segment
		(start 202.6 136.257842)
		(end 202.6 104.45)
		(width 0.1)
		(layer "In3.Cu")
		(net 1308)
	)
	(segment
		(start 193.33 137.6)
		(end 201.257842 137.6)
		(width 0.1)
		(layer "In3.Cu")
		(net 1308)
	)
	(segment
		(start 211.1 95.475)
		(end 211.1 75.7)
		(width 0.1)
		(layer "In3.Cu")
		(net 1308)
	)
	(segment
		(start 201.257842 137.6)
		(end 202.6 136.257842)
		(width 0.1)
		(layer "In3.Cu")
		(net 1308)
	)
	(segment
		(start 211.6 75.2)
		(end 252.7 75.2)
		(width 0.1)
		(layer "In3.Cu")
		(net 1308)
	)
	(segment
		(start 202.6 104.45)
		(end 203.725 103.325)
		(width 0.1)
		(layer "In3.Cu")
		(net 1308)
	)
	(segment
		(start 192.94 137.99)
		(end 193.33 137.6)
		(width 0.1)
		(layer "In3.Cu")
		(net 1308)
	)
	(segment
		(start 203.725 103.325)
		(end 204.75 103.325)
		(width 0.1)
		(layer "In3.Cu")
		(net 1308)
	)
	(segment
		(start 252.7 75.2)
		(end 253.1 75.6)
		(width 0.1)
		(layer "In3.Cu")
		(net 1308)
	)
	(segment
		(start 256.2 75.6)
		(end 256.7 75.1)
		(width 0.1)
		(layer "In3.Cu")
		(net 1308)
	)
	(segment
		(start 209.15 98.925)
		(end 209.15 97.425)
		(width 0.1)
		(layer "In3.Cu")
		(net 1308)
	)
	(segment
		(start 253.1 75.6)
		(end 256.2 75.6)
		(width 0.1)
		(layer "In3.Cu")
		(net 1308)
	)
	(segment
		(start 209.15 97.425)
		(end 211.1 95.475)
		(width 0.1)
		(layer "In3.Cu")
		(net 1308)
	)
	(segment
		(start 211.1 75.7)
		(end 211.6 75.2)
		(width 0.1)
		(layer "In3.Cu")
		(net 1308)
	)
	(segment
		(start 204.75 103.325)
		(end 209.15 98.925)
		(width 0.1)
		(layer "In3.Cu")
		(net 1308)
	)
	(segment
		(start 191 135.01)
		(end 192.01 135.01)
		(width 0.15)
		(layer "F.Cu")
		(net 1309)
	)
	(segment
		(start 192.01 135.01)
		(end 192.5 135.5)
		(width 0.15)
		(layer "F.Cu")
		(net 1309)
	)
	(via
		(at 191 135.01)
		(size 0.45)
		(drill 0.2)
		(layers "F.Cu" "B.Cu")
		(net 1309)
	)
	(via
		(at 255.525 74.225)
		(size 0.45)
		(drill 0.2)
		(layers "F.Cu" "B.Cu")
		(net 1309)
	)
	(via
		(at 255.7 76.95)
		(size 0.45)
		(drill 0.2)
		(layers "F.Cu" "B.Cu")
		(net 1309)
	)
	(segment
		(start 255.7 75.025)
		(end 255.7 74.4)
		(width 0.1)
		(layer "B.Cu")
		(net 1309)
	)
	(segment
		(start 255.7 75.795)
		(end 255.7 76.95)
		(width 0.1)
		(layer "B.Cu")
		(net 1309)
	)
	(segment
		(start 255.4 73.7)
		(end 255.4 74.1)
		(width 0.1)
		(layer "B.Cu")
		(net 1309)
	)
	(segment
		(start 255.7 74.4)
		(end 255.525 74.225)
		(width 0.1)
		(layer "B.Cu")
		(net 1309)
	)
	(segment
		(start 255.7 75.795)
		(end 255.7 75.025)
		(width 0.1)
		(layer "B.Cu")
		(net 1309)
	)
	(segment
		(start 255.4 74.1)
		(end 255.525 74.225)
		(width 0.1)
		(layer "B.Cu")
		(net 1309)
	)
	(segment
		(start 199.4 134.175)
		(end 199.4 105.181368)
		(width 0.1)
		(layer "In3.Cu")
		(net 1309)
	)
	(segment
		(start 192.607648 136.077317)
		(end 192.607648 136.4)
		(width 0.1)
		(layer "In3.Cu")
		(net 1309)
	)
	(segment
		(start 191 135.01)
		(end 191.540331 135.01)
		(width 0.1)
		(layer "In3.Cu")
		(net 1309)
	)
	(segment
		(start 255.1 73.8)
		(end 255.525 74.225)
		(width 0.1)
		(layer "In3.Cu")
		(net 1309)
	)
	(segment
		(start 195.15 136.4)
		(end 195.4 136.15)
		(width 0.1)
		(layer "In3.Cu")
		(net 1309)
	)
	(segment
		(start 209.65 75.16421)
		(end 211.01421 73.8)
		(width 0.1)
		(layer "In3.Cu")
		(net 1309)
	)
	(segment
		(start 208.85 95.731368)
		(end 208.85 88.171143)
		(width 0.1)
		(layer "In3.Cu")
		(net 1309)
	)
	(segment
		(start 192.607648 136.4)
		(end 195.15 136.4)
		(width 0.1)
		(layer "In3.Cu")
		(net 1309)
	)
	(segment
		(start 208.85 88.171143)
		(end 209.65 87.371143)
		(width 0.1)
		(layer "In3.Cu")
		(net 1309)
	)
	(segment
		(start 199.4 105.181368)
		(end 208.85 95.731368)
		(width 0.1)
		(layer "In3.Cu")
		(net 1309)
	)
	(segment
		(start 195.4 136.15)
		(end 195.4 134.742158)
		(width 0.1)
		(layer "In3.Cu")
		(net 1309)
	)
	(segment
		(start 199.175 134.4)
		(end 199.4 134.175)
		(width 0.1)
		(layer "In3.Cu")
		(net 1309)
	)
	(segment
		(start 195.4 134.742158)
		(end 195.742158 134.4)
		(width 0.1)
		(layer "In3.Cu")
		(net 1309)
	)
	(segment
		(start 195.742158 134.4)
		(end 199.175 134.4)
		(width 0.1)
		(layer "In3.Cu")
		(net 1309)
	)
	(segment
		(start 211.01421 73.8)
		(end 255.1 73.8)
		(width 0.1)
		(layer "In3.Cu")
		(net 1309)
	)
	(segment
		(start 191.540331 135.01)
		(end 192.607648 136.077317)
		(width 0.1)
		(layer "In3.Cu")
		(net 1309)
	)
	(segment
		(start 209.65 87.371143)
		(end 209.65 75.16421)
		(width 0.1)
		(layer "In3.Cu")
		(net 1309)
	)
	(segment
		(start 192.5 136.5)
		(end 192 137)
		(width 0.256)
		(layer "F.Cu")
		(net 1310)
	)
	(via
		(at 254.7 74.325)
		(size 0.45)
		(drill 0.2)
		(layers "F.Cu" "B.Cu")
		(net 1310)
	)
	(via
		(at 192 137)
		(size 0.45)
		(drill 0.2)
		(layers "F.Cu" "B.Cu")
		(net 1310)
	)
	(via
		(at 254.7 76.95)
		(size 0.45)
		(drill 0.2)
		(layers "F.Cu" "B.Cu")
		(net 1310)
	)
	(segment
		(start 254.7 74.325)
		(end 254.7 75.795)
		(width 0.1)
		(layer "B.Cu")
		(net 1310)
	)
	(segment
		(start 254.7 75.795)
		(end 254.7 76.95)
		(width 0.1)
		(layer "B.Cu")
		(net 1310)
	)
	(segment
		(start 255 74.025)
		(end 255 73.7)
		(width 0.1)
		(layer "B.Cu")
		(net 1310)
	)
	(segment
		(start 254.7 74.325)
		(end 255 74.025)
		(width 0.1)
		(layer "B.Cu")
		(net 1310)
	)
	(segment
		(start 199.257842 134.6)
		(end 195.825 134.6)
		(width 0.1)
		(layer "In3.Cu")
		(net 1310)
	)
	(segment
		(start 209.05 88.253985)
		(end 209.05 95.81421)
		(width 0.1)
		(layer "In3.Cu")
		(net 1310)
	)
	(segment
		(start 209.85 87.453985)
		(end 209.05 88.253985)
		(width 0.1)
		(layer "In3.Cu")
		(net 1310)
	)
	(segment
		(start 254.7 74.325)
		(end 254.375 74)
		(width 0.1)
		(layer "In3.Cu")
		(net 1310)
	)
	(segment
		(start 195.6 134.825)
		(end 195.6 136.25)
		(width 0.1)
		(layer "In3.Cu")
		(net 1310)
	)
	(segment
		(start 199.61079 105.26421)
		(end 199.6 105.26421)
		(width 0.1)
		(layer "In3.Cu")
		(net 1310)
	)
	(segment
		(start 209.85 75.247052)
		(end 209.85 87.453985)
		(width 0.1)
		(layer "In3.Cu")
		(net 1310)
	)
	(segment
		(start 254.375 74)
		(end 211.097052 74)
		(width 0.1)
		(layer "In3.Cu")
		(net 1310)
	)
	(segment
		(start 199.6 105.26421)
		(end 199.6 134.257842)
		(width 0.1)
		(layer "In3.Cu")
		(net 1310)
	)
	(segment
		(start 195.825 134.6)
		(end 195.6 134.825)
		(width 0.1)
		(layer "In3.Cu")
		(net 1310)
	)
	(segment
		(start 206.625 98.23921)
		(end 206.625 99.05)
		(width 0.1)
		(layer "In3.Cu")
		(net 1310)
	)
	(segment
		(start 209.05 95.81421)
		(end 206.625 98.23921)
		(width 0.1)
		(layer "In3.Cu")
		(net 1310)
	)
	(segment
		(start 192.4 136.6)
		(end 192 137)
		(width 0.1)
		(layer "In3.Cu")
		(net 1310)
	)
	(segment
		(start 205.1 100.575)
		(end 204.3 100.575)
		(width 0.1)
		(layer "In3.Cu")
		(net 1310)
	)
	(segment
		(start 195.6 136.25)
		(end 195.25 136.6)
		(width 0.1)
		(layer "In3.Cu")
		(net 1310)
	)
	(segment
		(start 195.25 136.6)
		(end 192.4 136.6)
		(width 0.1)
		(layer "In3.Cu")
		(net 1310)
	)
	(segment
		(start 199.6 134.257842)
		(end 199.257842 134.6)
		(width 0.1)
		(layer "In3.Cu")
		(net 1310)
	)
	(segment
		(start 206.625 99.05)
		(end 205.1 100.575)
		(width 0.1)
		(layer "In3.Cu")
		(net 1310)
	)
	(segment
		(start 204.3 100.575)
		(end 199.61079 105.26421)
		(width 0.1)
		(layer "In3.Cu")
		(net 1310)
	)
	(segment
		(start 211.097052 74)
		(end 209.85 75.247052)
		(width 0.1)
		(layer "In3.Cu")
		(net 1310)
	)
	(segment
		(start 253.7 76)
		(end 253.7 76.95)
		(width 0.1)
		(layer "F.Cu")
		(net 1311)
	)
	(segment
		(start 197.025 134.975)
		(end 196.984763 134.975)
		(width 0.256)
		(layer "F.Cu")
		(net 1311)
	)
	(segment
		(start 197.5 134.5)
		(end 197.025 134.975)
		(width 0.256)
		(layer "F.Cu")
		(net 1311)
	)
	(via
		(at 253.7 76)
		(size 0.45)
		(drill 0.2)
		(layers "F.Cu" "B.Cu")
		(net 1311)
	)
	(via
		(at 253.7 74.4)
		(size 0.45)
		(drill 0.2)
		(layers "F.Cu" "B.Cu")
		(net 1311)
	)
	(via
		(at 196.984763 134.975)
		(size 0.45)
		(drill 0.2)
		(layers "F.Cu" "B.Cu")
		(net 1311)
	)
	(segment
		(start 254.2 75.795)
		(end 253.905 75.795)
		(width 0.1)
		(layer "B.Cu")
		(net 1311)
	)
	(segment
		(start 254.6 73.7)
		(end 254.4 73.7)
		(width 0.1)
		(layer "B.Cu")
		(net 1311)
	)
	(segment
		(start 254.2 74.9)
		(end 253.7 74.4)
		(width 0.1)
		(layer "B.Cu")
		(net 1311)
	)
	(segment
		(start 253.905 75.795)
		(end 253.7 76)
		(width 0.1)
		(layer "B.Cu")
		(net 1311)
	)
	(segment
		(start 254.2 75.795)
		(end 254.2 75.025)
		(width 0.1)
		(layer "B.Cu")
		(net 1311)
	)
	(segment
		(start 254.4 73.7)
		(end 253.7 74.4)
		(width 0.1)
		(layer "B.Cu")
		(net 1311)
	)
	(segment
		(start 254.2 75.025)
		(end 254.2 74.9)
		(width 0.1)
		(layer "B.Cu")
		(net 1311)
	)
	(segment
		(start 200.175 135.4)
		(end 200.4 135.175)
		(width 0.1)
		(layer "In3.Cu")
		(net 1311)
	)
	(segment
		(start 210.05 87.536827)
		(end 210.05 75.329892)
		(width 0.1)
		(layer "In3.Cu")
		(net 1311)
	)
	(segment
		(start 196.984763 134.975)
		(end 197.409763 135.4)
		(width 0.1)
		(layer "In3.Cu")
		(net 1311)
	)
	(segment
		(start 210.05 75.329892)
		(end 211.179894 74.2)
		(width 0.1)
		(layer "In3.Cu")
		(net 1311)
	)
	(segment
		(start 197.409763 135.4)
		(end 200.175 135.4)
		(width 0.1)
		(layer "In3.Cu")
		(net 1311)
	)
	(segment
		(start 206.825 98.322052)
		(end 209.25 95.897052)
		(width 0.1)
		(layer "In3.Cu")
		(net 1311)
	)
	(segment
		(start 200.4 104.825)
		(end 204.45 100.775)
		(width 0.1)
		(layer "In3.Cu")
		(net 1311)
	)
	(segment
		(start 205.225 100.775)
		(end 206.825 99.175)
		(width 0.1)
		(layer "In3.Cu")
		(net 1311)
	)
	(segment
		(start 209.25 95.897052)
		(end 209.25 88.336827)
		(width 0.1)
		(layer "In3.Cu")
		(net 1311)
	)
	(segment
		(start 204.45 100.775)
		(end 205.225 100.775)
		(width 0.1)
		(layer "In3.Cu")
		(net 1311)
	)
	(segment
		(start 200.4 135.175)
		(end 200.4 104.825)
		(width 0.1)
		(layer "In3.Cu")
		(net 1311)
	)
	(segment
		(start 209.25 88.336827)
		(end 210.05 87.536827)
		(width 0.1)
		(layer "In3.Cu")
		(net 1311)
	)
	(segment
		(start 211.179894 74.2)
		(end 253.5 74.2)
		(width 0.1)
		(layer "In3.Cu")
		(net 1311)
	)
	(segment
		(start 253.5 74.2)
		(end 253.7 74.4)
		(width 0.1)
		(layer "In3.Cu")
		(net 1311)
	)
	(segment
		(start 206.825 99.175)
		(end 206.825 98.322052)
		(width 0.1)
		(layer "In3.Cu")
		(net 1311)
	)
	(segment
		(start 247.7 144)
		(end 247.7 143.727)
		(width 0.1)
		(layer "F.Cu")
		(net 1312)
	)
	(segment
		(start 249.3 144)
		(end 249.3 143.727)
		(width 0.1)
		(layer "F.Cu")
		(net 1313)
	)
	(segment
		(start 251.7 148.85)
		(end 251.7 148.527)
		(width 0.1)
		(layer "B.Cu")
		(net 1314)
	)
	(segment
		(start 249.3 148.85)
		(end 249.3 148.527)
		(width 0.1)
		(layer "B.Cu")
		(net 1315)
	)
	(segment
		(start 248.5 148.85)
		(end 248.5 148.527)
		(width 0.1)
		(layer "B.Cu")
		(net 1316)
	)
	(segment
		(start 249.7 148.85)
		(end 249.7 148.527)
		(width 0.1)
		(layer "B.Cu")
		(net 1317)
	)
	(segment
		(start 196.5 135.5)
		(end 196 136)
		(width 0.256)
		(layer "F.Cu")
		(net 1318)
	)
	(segment
		(start 260.7 76.025)
		(end 260.7 76.95)
		(width 0.1)
		(layer "F.Cu")
		(net 1318)
	)
	(via
		(at 260.7 76.025)
		(size 0.45)
		(drill 0.2)
		(layers "F.Cu" "B.Cu")
		(net 1318)
	)
	(via
		(at 196 136)
		(size 0.45)
		(drill 0.2)
		(layers "F.Cu" "B.Cu")
		(net 1318)
	)
	(via
		(at 260.685188 75.114812)
		(size 0.45)
		(drill 0.2)
		(layers "F.Cu" "B.Cu")
		(net 1318)
	)
	(segment
		(start 260.685188 74.590188)
		(end 260.685188 75.114812)
		(width 0.1)
		(layer "B.Cu")
		(net 1318)
	)
	(segment
		(start 260.195 75.795)
		(end 260.195 75.025)
		(width 0.1)
		(layer "B.Cu")
		(net 1318)
	)
	(segment
		(start 260.195 75.025)
		(end 260.595376 75.025)
		(width 0.1)
		(layer "B.Cu")
		(net 1318)
	)
	(segment
		(start 260.195 75.795)
		(end 260.47 75.795)
		(width 0.1)
		(layer "B.Cu")
		(net 1318)
	)
	(segment
		(start 260.47 75.795)
		(end 260.7 76.025)
		(width 0.1)
		(layer "B.Cu")
		(net 1318)
	)
	(segment
		(start 260.595376 75.025)
		(end 260.685188 75.114812)
		(width 0.1)
		(layer "B.Cu")
		(net 1318)
	)
	(segment
		(start 259.795 73.7)
		(end 260.685188 74.590188)
		(width 0.1)
		(layer "B.Cu")
		(net 1318)
	)
	(segment
		(start 209.45 95.979894)
		(end 209.45 88.419669)
		(width 0.1)
		(layer "In3.Cu")
		(net 1318)
	)
	(segment
		(start 205.325 100.975)
		(end 207.025 99.275)
		(width 0.1)
		(layer "In3.Cu")
		(net 1318)
	)
	(segment
		(start 207.025 99.275)
		(end 207.025 98.404894)
		(width 0.1)
		(layer "In3.Cu")
		(net 1318)
	)
	(segment
		(start 253.1 74.4)
		(end 253.5 74.8)
		(width 0.1)
		(layer "In3.Cu")
		(net 1318)
	)
	(segment
		(start 260.685188 74.95)
		(end 260.685188 75.114812)
		(width 0.1)
		(layer "In3.Cu")
		(net 1318)
	)
	(segment
		(start 210.25 75.412735)
		(end 211.262736 74.4)
		(width 0.1)
		(layer "In3.Cu")
		(net 1318)
	)
	(segment
		(start 255.5 74.8)
		(end 256.2 74.1)
		(width 0.1)
		(layer "In3.Cu")
		(net 1318)
	)
	(segment
		(start 200.6 135.257842)
		(end 200.6 104.925)
		(width 0.1)
		(layer "In3.Cu")
		(net 1318)
	)
	(segment
		(start 200.257842 135.6)
		(end 200.6 135.257842)
		(width 0.1)
		(layer "In3.Cu")
		(net 1318)
	)
	(segment
		(start 256.2 74.1)
		(end 259.835188 74.1)
		(width 0.1)
		(layer "In3.Cu")
		(net 1318)
	)
	(segment
		(start 211.262736 74.4)
		(end 253.1 74.4)
		(width 0.1)
		(layer "In3.Cu")
		(net 1318)
	)
	(segment
		(start 210.25 87.619669)
		(end 210.25 75.412735)
		(width 0.1)
		(layer "In3.Cu")
		(net 1318)
	)
	(segment
		(start 204.55 100.975)
		(end 205.325 100.975)
		(width 0.1)
		(layer "In3.Cu")
		(net 1318)
	)
	(segment
		(start 196 136)
		(end 196.4 135.6)
		(width 0.1)
		(layer "In3.Cu")
		(net 1318)
	)
	(segment
		(start 200.6 104.925)
		(end 204.55 100.975)
		(width 0.1)
		(layer "In3.Cu")
		(net 1318)
	)
	(segment
		(start 207.025 98.404894)
		(end 209.45 95.979894)
		(width 0.1)
		(layer "In3.Cu")
		(net 1318)
	)
	(segment
		(start 196.4 135.6)
		(end 200.257842 135.6)
		(width 0.1)
		(layer "In3.Cu")
		(net 1318)
	)
	(segment
		(start 209.45 88.419669)
		(end 210.25 87.619669)
		(width 0.1)
		(layer "In3.Cu")
		(net 1318)
	)
	(segment
		(start 253.5 74.8)
		(end 255.5 74.8)
		(width 0.1)
		(layer "In3.Cu")
		(net 1318)
	)
	(segment
		(start 259.835188 74.1)
		(end 260.685188 74.95)
		(width 0.1)
		(layer "In3.Cu")
		(net 1318)
	)
	(segment
		(start 253.3 148.527)
		(end 253.3 148.85)
		(width 0.1)
		(layer "B.Cu")
		(net 1319)
	)
	(segment
		(start 193.5 136.5)
		(end 193 137)
		(width 0.256)
		(layer "F.Cu")
		(net 1320)
	)
	(via
		(at 193 137)
		(size 0.45)
		(drill 0.2)
		(layers "F.Cu" "B.Cu")
		(net 1320)
	)
	(via
		(at 259.7 76.95)
		(size 0.45)
		(drill 0.2)
		(layers "F.Cu" "B.Cu")
		(net 1320)
	)
	(via
		(at 259.7 74.6)
		(size 0.45)
		(drill 0.2)
		(layers "F.Cu" "B.Cu")
		(net 1320)
	)
	(segment
		(start 259.395 74.295)
		(end 259.7 74.6)
		(width 0.1)
		(layer "B.Cu")
		(net 1320)
	)
	(segment
		(start 259.695 75.795)
		(end 259.7 75.8)
		(width 0.1)
		(layer "B.Cu")
		(net 1320)
	)
	(segment
		(start 259.395 73.7)
		(end 259.395 74.295)
		(width 0.1)
		(layer "B.Cu")
		(net 1320)
	)
	(segment
		(start 259.695 75.025)
		(end 259.695 74.605)
		(width 0.1)
		(layer "B.Cu")
		(net 1320)
	)
	(segment
		(start 259.7 75.8)
		(end 259.7 76.95)
		(width 0.1)
		(layer "B.Cu")
		(net 1320)
	)
	(segment
		(start 259.695 75.795)
		(end 259.695 75.025)
		(width 0.1)
		(layer "B.Cu")
		(net 1320)
	)
	(segment
		(start 259.695 74.605)
		(end 259.7 74.6)
		(width 0.1)
		(layer "B.Cu")
		(net 1320)
	)
	(segment
		(start 193.4 137.4)
		(end 201.175 137.4)
		(width 0.1)
		(layer "In3.Cu")
		(net 1320)
	)
	(segment
		(start 207.65 99.55)
		(end 207.65 98.632842)
		(width 0.1)
		(layer "In3.Cu")
		(net 1320)
	)
	(segment
		(start 204.875 101.6)
		(end 205.6 101.6)
		(width 0.1)
		(layer "In3.Cu")
		(net 1320)
	)
	(segment
		(start 207.65 98.632842)
		(end 210.9 95.382842)
		(width 0.1)
		(layer "In3.Cu")
		(net 1320)
	)
	(segment
		(start 256.5 74.7)
		(end 256.917158 74.7)
		(width 0.1)
		(layer "In3.Cu")
		(net 1320)
	)
	(segment
		(start 193 137)
		(end 193.4 137.4)
		(width 0.1)
		(layer "In3.Cu")
		(net 1320)
	)
	(segment
		(start 253.2 75.4)
		(end 255.8 75.4)
		(width 0.1)
		(layer "In3.Cu")
		(net 1320)
	)
	(segment
		(start 205.6 101.6)
		(end 207.65 99.55)
		(width 0.1)
		(layer "In3.Cu")
		(net 1320)
	)
	(segment
		(start 202.4 136.175)
		(end 202.4 104.075)
		(width 0.1)
		(layer "In3.Cu")
		(net 1320)
	)
	(segment
		(start 201.175 137.4)
		(end 202.4 136.175)
		(width 0.1)
		(layer "In3.Cu")
		(net 1320)
	)
	(segment
		(start 257.392158 75.175)
		(end 259.125 75.175)
		(width 0.1)
		(layer "In3.Cu")
		(net 1320)
	)
	(segment
		(start 259.125 75.175)
		(end 259.7 74.6)
		(width 0.1)
		(layer "In3.Cu")
		(net 1320)
	)
	(segment
		(start 252.8 75)
		(end 253.2 75.4)
		(width 0.1)
		(layer "In3.Cu")
		(net 1320)
	)
	(segment
		(start 202.4 104.075)
		(end 204.875 101.6)
		(width 0.1)
		(layer "In3.Cu")
		(net 1320)
	)
	(segment
		(start 210.9 95.382842)
		(end 210.9 75.611262)
		(width 0.1)
		(layer "In3.Cu")
		(net 1320)
	)
	(segment
		(start 255.8 75.4)
		(end 256.5 74.7)
		(width 0.1)
		(layer "In3.Cu")
		(net 1320)
	)
	(segment
		(start 256.917158 74.7)
		(end 257.392158 75.175)
		(width 0.1)
		(layer "In3.Cu")
		(net 1320)
	)
	(segment
		(start 211.511262 75)
		(end 252.8 75)
		(width 0.1)
		(layer "In3.Cu")
		(net 1320)
	)
	(segment
		(start 210.9 75.611262)
		(end 211.511262 75)
		(width 0.1)
		(layer "In3.Cu")
		(net 1320)
	)
	(segment
		(start 252.5 148.85)
		(end 252.5 148.527)
		(width 0.1)
		(layer "B.Cu")
		(net 1321)
	)
	(segment
		(start 197.5 136.5)
		(end 197 137)
		(width 0.256)
		(layer "F.Cu")
		(net 1322)
	)
	(via
		(at 197 137)
		(size 0.45)
		(drill 0.2)
		(layers "F.Cu" "B.Cu")
		(net 1322)
	)
	(via
		(at 258.7 76.95)
		(size 0.45)
		(drill 0.2)
		(layers "F.Cu" "B.Cu")
		(net 1322)
	)
	(via
		(at 258.7 74.6)
		(size 0.45)
		(drill 0.2)
		(layers "F.Cu" "B.Cu")
		(net 1322)
	)
	(segment
		(start 258.995 73.7)
		(end 258.995 74.305)
		(width 0.1)
		(layer "B.Cu")
		(net 1322)
	)
	(segment
		(start 258.695 76.945)
		(end 258.7 76.95)
		(width 0.1)
		(layer "B.Cu")
		(net 1322)
	)
	(segment
		(start 258.695 75.025)
		(end 258.695 74.605)
		(width 0.1)
		(layer "B.Cu")
		(net 1322)
	)
	(segment
		(start 258.695 75.795)
		(end 258.695 76.945)
		(width 0.1)
		(layer "B.Cu")
		(net 1322)
	)
	(segment
		(start 258.695 75.795)
		(end 258.695 75.025)
		(width 0.1)
		(layer "B.Cu")
		(net 1322)
	)
	(segment
		(start 258.995 74.305)
		(end 258.7 74.6)
		(width 0.1)
		(layer "B.Cu")
		(net 1322)
	)
	(segment
		(start 258.695 74.605)
		(end 258.7 74.6)
		(width 0.1)
		(layer "B.Cu")
		(net 1322)
	)
	(segment
		(start 207.45 98.55)
		(end 210.65 95.35)
		(width 0.1)
		(layer "In3.Cu")
		(net 1322)
	)
	(segment
		(start 252.9 74.8)
		(end 253.3 75.2)
		(width 0.1)
		(layer "In3.Cu")
		(net 1322)
	)
	(segment
		(start 258.325 74.975)
		(end 258.7 74.6)
		(width 0.1)
		(layer "In3.Cu")
		(net 1322)
	)
	(segment
		(start 197.4 136.6)
		(end 201.257842 136.6)
		(width 0.1)
		(layer "In3.Cu")
		(net 1322)
	)
	(segment
		(start 210.65 75.57842)
		(end 211.42842 74.8)
		(width 0.1)
		(layer "In3.Cu")
		(net 1322)
	)
	(segment
		(start 204.8 101.375)
		(end 205.525 101.375)
		(width 0.1)
		(layer "In3.Cu")
		(net 1322)
	)
	(segment
		(start 197 137)
		(end 197.4 136.6)
		(width 0.1)
		(layer "In3.Cu")
		(net 1322)
	)
	(segment
		(start 201.257842 136.6)
		(end 201.6 136.257842)
		(width 0.1)
		(layer "In3.Cu")
		(net 1322)
	)
	(segment
		(start 201.6 104.575)
		(end 204.8 101.375)
		(width 0.1)
		(layer "In3.Cu")
		(net 1322)
	)
	(segment
		(start 210.65 95.35)
		(end 210.65 75.57842)
		(width 0.1)
		(layer "In3.Cu")
		(net 1322)
	)
	(segment
		(start 255.717158 75.2)
		(end 256.417158 74.5)
		(width 0.1)
		(layer "In3.Cu")
		(net 1322)
	)
	(segment
		(start 201.6 136.257842)
		(end 201.6 104.575)
		(width 0.1)
		(layer "In3.Cu")
		(net 1322)
	)
	(segment
		(start 256.417158 74.5)
		(end 257 74.5)
		(width 0.1)
		(layer "In3.Cu")
		(net 1322)
	)
	(segment
		(start 253.3 75.2)
		(end 255.717158 75.2)
		(width 0.1)
		(layer "In3.Cu")
		(net 1322)
	)
	(segment
		(start 257.475 74.975)
		(end 258.325 74.975)
		(width 0.1)
		(layer "In3.Cu")
		(net 1322)
	)
	(segment
		(start 205.525 101.375)
		(end 207.45 99.45)
		(width 0.1)
		(layer "In3.Cu")
		(net 1322)
	)
	(segment
		(start 211.42842 74.8)
		(end 252.9 74.8)
		(width 0.1)
		(layer "In3.Cu")
		(net 1322)
	)
	(segment
		(start 257 74.5)
		(end 257.475 74.975)
		(width 0.1)
		(layer "In3.Cu")
		(net 1322)
	)
	(segment
		(start 207.45 99.45)
		(end 207.45 98.55)
		(width 0.1)
		(layer "In3.Cu")
		(net 1322)
	)
	(segment
		(start 254.1 148.527)
		(end 254.1 148.85)
		(width 0.1)
		(layer "B.Cu")
		(net 1323)
	)
	(segment
		(start 196.987192 136.012808)
		(end 196.987192 136.02401)
		(width 0.256)
		(layer "F.Cu")
		(net 1324)
	)
	(segment
		(start 197.5 135.5)
		(end 196.987192 136.012808)
		(width 0.256)
		(layer "F.Cu")
		(net 1324)
	)
	(segment
		(start 257.675 76.075)
		(end 257.675 76.925)
		(width 0.1)
		(layer "F.Cu")
		(net 1324)
	)
	(segment
		(start 257.675 76.925)
		(end 257.7 76.95)
		(width 0.1)
		(layer "F.Cu")
		(net 1324)
	)
	(via
		(at 257.7 74.6)
		(size 0.45)
		(drill 0.2)
		(layers "F.Cu" "B.Cu")
		(net 1324)
	)
	(via
		(at 196.987192 136.02401)
		(size 0.45)
		(drill 0.2)
		(layers "F.Cu" "B.Cu")
		(net 1324)
	)
	(via
		(at 257.675 76.075)
		(size 0.45)
		(drill 0.2)
		(layers "F.Cu" "B.Cu")
		(net 1324)
	)
	(segment
		(start 258.595 73.705)
		(end 257.7 74.6)
		(width 0.1)
		(layer "B.Cu")
		(net 1324)
	)
	(segment
		(start 258.595 73.7)
		(end 258.595 73.705)
		(width 0.1)
		(layer "B.Cu")
		(net 1324)
	)
	(segment
		(start 258.195 75.795)
		(end 257.955 75.795)
		(width 0.1)
		(layer "B.Cu")
		(net 1324)
	)
	(segment
		(start 258.125 75.025)
		(end 257.7 74.6)
		(width 0.1)
		(layer "B.Cu")
		(net 1324)
	)
	(segment
		(start 258.195 75.795)
		(end 258.195 75.025)
		(width 0.1)
		(layer "B.Cu")
		(net 1324)
	)
	(segment
		(start 258.195 75.025)
		(end 258.125 75.025)
		(width 0.1)
		(layer "B.Cu")
		(net 1324)
	)
	(segment
		(start 257.955 75.795)
		(end 257.675 76.075)
		(width 0.1)
		(layer "B.Cu")
		(net 1324)
	)
	(segment
		(start 207.25 98.462736)
		(end 210.45 95.262736)
		(width 0.1)
		(layer "In3.Cu")
		(net 1324)
	)
	(segment
		(start 207.25 99.35)
		(end 207.25 98.462736)
		(width 0.1)
		(layer "In3.Cu")
		(net 1324)
	)
	(segment
		(start 197.363182 136.4)
		(end 201.175 136.4)
		(width 0.1)
		(layer "In3.Cu")
		(net 1324)
	)
	(segment
		(start 211.345578 74.6)
		(end 253 74.6)
		(width 0.1)
		(layer "In3.Cu")
		(net 1324)
	)
	(segment
		(start 255.582842 75)
		(end 256.282842 74.3)
		(width 0.1)
		(layer "In3.Cu")
		(net 1324)
	)
	(segment
		(start 205.425 101.175)
		(end 207.25 99.35)
		(width 0.1)
		(layer "In3.Cu")
		(net 1324)
	)
	(segment
		(start 210.45 95.262736)
		(end 210.45 75.495578)
		(width 0.1)
		(layer "In3.Cu")
		(net 1324)
	)
	(segment
		(start 201.4 136.175)
		(end 201.4 104.475)
		(width 0.1)
		(layer "In3.Cu")
		(net 1324)
	)
	(segment
		(start 201.4 104.475)
		(end 204.7 101.175)
		(width 0.1)
		(layer "In3.Cu")
		(net 1324)
	)
	(segment
		(start 210.45 75.495578)
		(end 211.345578 74.6)
		(width 0.1)
		(layer "In3.Cu")
		(net 1324)
	)
	(segment
		(start 256.282842 74.3)
		(end 257.4 74.3)
		(width 0.1)
		(layer "In3.Cu")
		(net 1324)
	)
	(segment
		(start 253.4 75)
		(end 255.582842 75)
		(width 0.1)
		(layer "In3.Cu")
		(net 1324)
	)
	(segment
		(start 196.987192 136.02401)
		(end 197.363182 136.4)
		(width 0.1)
		(layer "In3.Cu")
		(net 1324)
	)
	(segment
		(start 257.4 74.3)
		(end 257.7 74.6)
		(width 0.1)
		(layer "In3.Cu")
		(net 1324)
	)
	(segment
		(start 204.7 101.175)
		(end 205.425 101.175)
		(width 0.1)
		(layer "In3.Cu")
		(net 1324)
	)
	(segment
		(start 253 74.6)
		(end 253.4 75)
		(width 0.1)
		(layer "In3.Cu")
		(net 1324)
	)
	(segment
		(start 201.175 136.4)
		(end 201.4 136.175)
		(width 0.1)
		(layer "In3.Cu")
		(net 1324)
	)
	(segment
		(start 253.7 148.527)
		(end 253.7 148.85)
		(width 0.1)
		(layer "B.Cu")
		(net 1325)
	)
	(segment
		(start 250.1 148.85)
		(end 250.1 148.527)
		(width 0.1)
		(layer "B.Cu")
		(net 1326)
	)
	(segment
		(start 252.1 144)
		(end 252.1 143.627)
		(width 0.1)
		(layer "F.Cu")
		(net 1327)
	)
	(segment
		(start 206.5 138.5)
		(end 207 139)
		(width 0.256)
		(layer "F.Cu")
		(net 1328)
	)
	(segment
		(start 251.075 121.575)
		(end 251.2 121.7)
		(width 0.1)
		(layer "F.Cu")
		(net 1328)
	)
	(segment
		(start 251.075 120.2)
		(end 251.075 121.575)
		(width 0.1)
		(layer "F.Cu")
		(net 1328)
	)
	(segment
		(start 239.385188 123.485188)
		(end 239.385188 123.931188)
		(width 0.1)
		(layer "F.Cu")
		(net 1328)
	)
	(segment
		(start 239.385188 123.931188)
		(end 239.4 123.946)
		(width 0.1)
		(layer "F.Cu")
		(net 1328)
	)
	(via
		(at 239.385188 123.485188)
		(size 0.45)
		(drill 0.2)
		(layers "F.Cu" "B.Cu")
		(net 1328)
	)
	(via
		(at 251.075 120.2)
		(size 0.45)
		(drill 0.2)
		(layers "F.Cu" "B.Cu")
		(net 1328)
	)
	(via
		(at 207 139)
		(size 0.45)
		(drill 0.2)
		(layers "F.Cu" "B.Cu")
		(net 1328)
	)
	(segment
		(start 239.170376 123.7)
		(end 238.712736 123.7)
		(width 0.1)
		(layer "In5.Cu")
		(net 1328)
	)
	(segment
		(start 242.375 122.775)
		(end 241.8 122.775)
		(width 0.1)
		(layer "In5.Cu")
		(net 1328)
	)
	(segment
		(start 251.025 120.25)
		(end 247.6 120.25)
		(width 0.1)
		(layer "In5.Cu")
		(net 1328)
	)
	(segment
		(start 224.012736 138.4)
		(end 207.6 138.4)
		(width 0.1)
		(layer "In5.Cu")
		(net 1328)
	)
	(segment
		(start 243.25 122.875)
		(end 243.2 122.925)
		(width 0.1)
		(layer "In5.Cu")
		(net 1328)
	)
	(segment
		(start 247.6 120.25)
		(end 244.975 122.875)
		(width 0.1)
		(layer "In5.Cu")
		(net 1328)
	)
	(segment
		(start 242.525 122.925)
		(end 242.375 122.775)
		(width 0.1)
		(layer "In5.Cu")
		(net 1328)
	)
	(segment
		(start 251.075 120.2)
		(end 251.025 120.25)
		(width 0.1)
		(layer "In5.Cu")
		(net 1328)
	)
	(segment
		(start 239.385188 123.485188)
		(end 239.170376 123.7)
		(width 0.1)
		(layer "In5.Cu")
		(net 1328)
	)
	(segment
		(start 243.2 122.925)
		(end 242.525 122.925)
		(width 0.1)
		(layer "In5.Cu")
		(net 1328)
	)
	(segment
		(start 207.6 138.4)
		(end 207 139)
		(width 0.1)
		(layer "In5.Cu")
		(net 1328)
	)
	(segment
		(start 241.8 122.775)
		(end 241.45 123.125)
		(width 0.1)
		(layer "In5.Cu")
		(net 1328)
	)
	(segment
		(start 239.464812 123.485188)
		(end 239.385188 123.485188)
		(width 0.1)
		(layer "In5.Cu")
		(net 1328)
	)
	(segment
		(start 244.975 122.875)
		(end 243.25 122.875)
		(width 0.1)
		(layer "In5.Cu")
		(net 1328)
	)
	(segment
		(start 239.825 123.125)
		(end 239.464812 123.485188)
		(width 0.1)
		(layer "In5.Cu")
		(net 1328)
	)
	(segment
		(start 241.45 123.125)
		(end 239.825 123.125)
		(width 0.1)
		(layer "In5.Cu")
		(net 1328)
	)
	(segment
		(start 238.712736 123.7)
		(end 224.012736 138.4)
		(width 0.1)
		(layer "In5.Cu")
		(net 1328)
	)
	(segment
		(start 240 124.297552)
		(end 239.986412 124.283964)
		(width 0.1)
		(layer "F.Cu")
		(net 1329)
	)
	(segment
		(start 250.55 121.45)
		(end 250.55 120.725)
		(width 0.1)
		(layer "F.Cu")
		(net 1329)
	)
	(segment
		(start 240 124.6)
		(end 240 124.297552)
		(width 0.1)
		(layer "F.Cu")
		(net 1329)
	)
	(segment
		(start 208.5 139.5)
		(end 209 140)
		(width 0.256)
		(layer "F.Cu")
		(net 1329)
	)
	(segment
		(start 250.8 121.7)
		(end 250.55 121.45)
		(width 0.1)
		(layer "F.Cu")
		(net 1329)
	)
	(via
		(at 250.55 120.725)
		(size 0.45)
		(drill 0.2)
		(layers "F.Cu" "B.Cu")
		(net 1329)
	)
	(via
		(at 239.986412 124.283964)
		(size 0.45)
		(drill 0.2)
		(layers "F.Cu" "B.Cu")
		(net 1329)
	)
	(via
		(at 209 140)
		(size 0.45)
		(drill 0.2)
		(layers "F.Cu" "B.Cu")
		(net 1329)
	)
	(segment
		(start 242.25 123)
		(end 241.8625 123)
		(width 0.1)
		(layer "In5.Cu")
		(net 1329)
	)
	(segment
		(start 241.8625 123)
		(end 241.6 123.2625)
		(width 0.1)
		(layer "In5.Cu")
		(net 1329)
	)
	(segment
		(start 241.6 123.6)
		(end 241.275 123.925)
		(width 0.1)
		(layer "In5.Cu")
		(net 1329)
	)
	(segment
		(start 240.575 123.925)
		(end 240.216036 124.283964)
		(width 0.1)
		(layer "In5.Cu")
		(net 1329)
	)
	(segment
		(start 249.125 120.525)
		(end 247.775 120.525)
		(width 0.1)
		(layer "In5.Cu")
		(net 1329)
	)
	(segment
		(start 249.625 121.025)
		(end 249.125 120.525)
		(width 0.1)
		(layer "In5.Cu")
		(net 1329)
	)
	(segment
		(start 242.4 123.15)
		(end 242.25 123)
		(width 0.1)
		(layer "In5.Cu")
		(net 1329)
	)
	(segment
		(start 247.775 120.525)
		(end 245.15 123.15)
		(width 0.1)
		(layer "In5.Cu")
		(net 1329)
	)
	(segment
		(start 209 140)
		(end 209.38 139.62)
		(width 0.1)
		(layer "In5.Cu")
		(net 1329)
	)
	(segment
		(start 250.55 121.3)
		(end 250.25 121.6)
		(width 0.1)
		(layer "In5.Cu")
		(net 1329)
	)
	(segment
		(start 218.240684 140.8)
		(end 222.461264 140.8)
		(width 0.1)
		(layer "In5.Cu")
		(net 1329)
	)
	(segment
		(start 217.060684 139.62)
		(end 218.240684 140.8)
		(width 0.1)
		(layer "In5.Cu")
		(net 1329)
	)
	(segment
		(start 241.6 123.2625)
		(end 241.6 123.6)
		(width 0.1)
		(layer "In5.Cu")
		(net 1329)
	)
	(segment
		(start 250.55 120.725)
		(end 250.55 121.3)
		(width 0.1)
		(layer "In5.Cu")
		(net 1329)
	)
	(segment
		(start 250.25 121.6)
		(end 250.05 121.6)
		(width 0.1)
		(layer "In5.Cu")
		(net 1329)
	)
	(segment
		(start 240.216036 124.283964)
		(end 239.986412 124.283964)
		(width 0.1)
		(layer "In5.Cu")
		(net 1329)
	)
	(segment
		(start 241.275 123.925)
		(end 240.575 123.925)
		(width 0.1)
		(layer "In5.Cu")
		(net 1329)
	)
	(segment
		(start 209.38 139.62)
		(end 217.060684 139.62)
		(width 0.1)
		(layer "In5.Cu")
		(net 1329)
	)
	(segment
		(start 239.798324 124.472052)
		(end 239.986412 124.283964)
		(width 0.1)
		(layer "In5.Cu")
		(net 1329)
	)
	(segment
		(start 245.15 123.15)
		(end 242.4 123.15)
		(width 0.1)
		(layer "In5.Cu")
		(net 1329)
	)
	(segment
		(start 250.05 121.6)
		(end 249.625 121.175)
		(width 0.1)
		(layer "In5.Cu")
		(net 1329)
	)
	(segment
		(start 238.78921 124.472052)
		(end 239.798324 124.472052)
		(width 0.1)
		(layer "In5.Cu")
		(net 1329)
	)
	(segment
		(start 249.625 121.175)
		(end 249.625 121.025)
		(width 0.1)
		(layer "In5.Cu")
		(net 1329)
	)
	(segment
		(start 222.461264 140.8)
		(end 238.78921 124.472052)
		(width 0.1)
		(layer "In5.Cu")
		(net 1329)
	)
	(segment
		(start 244.175 127)
		(end 244.725 126.45)
		(width 0.1)
		(layer "F.Cu")
		(net 1330)
	)
	(segment
		(start 243.7 128.45)
		(end 244.175 127.975)
		(width 0.1)
		(layer "F.Cu")
		(net 1330)
	)
	(segment
		(start 244.175 127.975)
		(end 244.175 127)
		(width 0.1)
		(layer "F.Cu")
		(net 1330)
	)
	(segment
		(start 242.65 129)
		(end 243.2 128.45)
		(width 0.1)
		(layer "F.Cu")
		(net 1330)
	)
	(segment
		(start 207.5 141.5)
		(end 207.979872 141.979872)
		(width 0.256)
		(layer "F.Cu")
		(net 1330)
	)
	(segment
		(start 240.225 129)
		(end 242.65 129)
		(width 0.1)
		(layer "F.Cu")
		(net 1330)
	)
	(segment
		(start 243.2 128.45)
		(end 243.7 128.45)
		(width 0.1)
		(layer "F.Cu")
		(net 1330)
	)
	(segment
		(start 246.94 126.17)
		(end 247.569502 126.17)
		(width 0.1)
		(layer "F.Cu")
		(net 1330)
	)
	(segment
		(start 246.66 126.45)
		(end 246.94 126.17)
		(width 0.1)
		(layer "F.Cu")
		(net 1330)
	)
	(segment
		(start 244.725 126.45)
		(end 246.66 126.45)
		(width 0.1)
		(layer "F.Cu")
		(net 1330)
	)
	(segment
		(start 239.2 125.5)
		(end 239.6 125.9)
		(width 0.1)
		(layer "F.Cu")
		(net 1330)
	)
	(segment
		(start 207.979872 141.979872)
		(end 207.979872 141.991572)
		(width 0.256)
		(layer "F.Cu")
		(net 1330)
	)
	(segment
		(start 239.6 128.375)
		(end 240.225 129)
		(width 0.1)
		(layer "F.Cu")
		(net 1330)
	)
	(segment
		(start 239.6 125.9)
		(end 239.6 128.375)
		(width 0.1)
		(layer "F.Cu")
		(net 1330)
	)
	(segment
		(start 247.569502 126.17)
		(end 248.1 126.700498)
		(width 0.1)
		(layer "F.Cu")
		(net 1330)
	)
	(via
		(at 248.1 126.700498)
		(size 0.45)
		(drill 0.2)
		(layers "F.Cu" "B.Cu")
		(net 1330)
	)
	(via
		(at 207.979872 141.991572)
		(size 0.45)
		(drill 0.2)
		(layers "F.Cu" "B.Cu")
		(net 1330)
	)
	(via
		(at 239.2 125.5)
		(size 0.45)
		(drill 0.2)
		(layers "F.Cu" "B.Cu")
		(net 1330)
	)
	(segment
		(start 248.101 127.602)
		(end 248.101 126.701498)
		(width 0.1)
		(layer "B.Cu")
		(net 1330)
	)
	(segment
		(start 248.1 126.59)
		(end 248.1 126.700498)
		(width 0.1)
		(layer "B.Cu")
		(net 1330)
	)
	(segment
		(start 248.101 126.701498)
		(end 248.1 126.700498)
		(width 0.1)
		(layer "B.Cu")
		(net 1330)
	)
	(segment
		(start 248.150197 126.539803)
		(end 248.1 126.59)
		(width 0.1)
		(layer "B.Cu")
		(net 1330)
	)
	(segment
		(start 238.692632 125.7)
		(end 239 125.7)
		(width 0.1)
		(layer "In5.Cu")
		(net 1330)
	)
	(segment
		(start 207.979872 141.991572)
		(end 208.371444 141.6)
		(width 0.1)
		(layer "In5.Cu")
		(net 1330)
	)
	(segment
		(start 208.371444 141.6)
		(end 222.792632 141.6)
		(width 0.1)
		(layer "In5.Cu")
		(net 1330)
	)
	(segment
		(start 222.792632 141.6)
		(end 238.692632 125.7)
		(width 0.1)
		(layer "In5.Cu")
		(net 1330)
	)
	(segment
		(start 239 125.7)
		(end 239.2 125.5)
		(width 0.1)
		(layer "In5.Cu")
		(net 1330)
	)
	(segment
		(start 240.4 128.246)
		(end 240.4 127.95)
		(width 0.1)
		(layer "F.Cu")
		(net 1331)
	)
	(segment
		(start 240.4 127.95)
		(end 240.5 127.85)
		(width 0.1)
		(layer "F.Cu")
		(net 1331)
	)
	(segment
		(start 251.6 121.1)
		(end 251.6 121.7)
		(width 0.1)
		(layer "F.Cu")
		(net 1331)
	)
	(segment
		(start 207.5 144.5)
		(end 208 145)
		(width 0.256)
		(layer "F.Cu")
		(net 1331)
	)
	(via
		(at 208 145)
		(size 0.45)
		(drill 0.2)
		(layers "F.Cu" "B.Cu")
		(net 1331)
	)
	(via
		(at 240.5 127.85)
		(size 0.45)
		(drill 0.2)
		(layers "F.Cu" "B.Cu")
		(net 1331)
	)
	(via
		(at 251.6 121.1)
		(size 0.45)
		(drill 0.2)
		(layers "F.Cu" "B.Cu")
		(net 1331)
	)
	(segment
		(start 241.675 126.275)
		(end 242.525 126.275)
		(width 0.1)
		(layer "In5.Cu")
		(net 1331)
	)
	(segment
		(start 240.525 127.85)
		(end 241.275 127.1)
		(width 0.1)
		(layer "In5.Cu")
		(net 1331)
	)
	(segment
		(start 240.5 127.85)
		(end 240.3 127.65)
		(width 0.1)
		(layer "In5.Cu")
		(net 1331)
	)
	(segment
		(start 241.275 127.1)
		(end 241.275 126.675)
		(width 0.1)
		(layer "In5.Cu")
		(net 1331)
	)
	(segment
		(start 241.275 126.675)
		(end 241.675 126.275)
		(width 0.1)
		(layer "In5.Cu")
		(net 1331)
	)
	(segment
		(start 238.722526 127.65)
		(end 222.772526 143.6)
		(width 0.1)
		(layer "In5.Cu")
		(net 1331)
	)
	(segment
		(start 247.05 125.65)
		(end 251.6 121.1)
		(width 0.1)
		(layer "In5.Cu")
		(net 1331)
	)
	(segment
		(start 208.4 145.4)
		(end 208 145)
		(width 0.1)
		(layer "In5.Cu")
		(net 1331)
	)
	(segment
		(start 240.3 127.65)
		(end 238.722526 127.65)
		(width 0.1)
		(layer "In5.Cu")
		(net 1331)
	)
	(segment
		(start 215.7 145.4)
		(end 208.4 145.4)
		(width 0.1)
		(layer "In5.Cu")
		(net 1331)
	)
	(segment
		(start 222.772526 143.6)
		(end 217.5 143.6)
		(width 0.1)
		(layer "In5.Cu")
		(net 1331)
	)
	(segment
		(start 242.525 126.275)
		(end 243.15 125.65)
		(width 0.1)
		(layer "In5.Cu")
		(net 1331)
	)
	(segment
		(start 217.5 143.6)
		(end 215.7 145.4)
		(width 0.1)
		(layer "In5.Cu")
		(net 1331)
	)
	(segment
		(start 240.5 127.85)
		(end 240.525 127.85)
		(width 0.1)
		(layer "In5.Cu")
		(net 1331)
	)
	(segment
		(start 243.15 125.65)
		(end 247.05 125.65)
		(width 0.1)
		(layer "In5.Cu")
		(net 1331)
	)
	(segment
		(start 251.7 127.6)
		(end 251.7 127.327)
		(width 0.1)
		(layer "B.Cu")
		(net 1332)
	)
	(segment
		(start 249.7 144)
		(end 249.7 143.727)
		(width 0.1)
		(layer "F.Cu")
		(net 1334)
	)
	(segment
		(start 247.3 144)
		(end 247.3 143.727)
		(width 0.1)
		(layer "F.Cu")
		(net 1335)
	)
	(segment
		(start 164.9758 171.0242)
		(end 165 171)
		(width 0.182)
		(layer "F.Cu")
		(net 1336)
	)
	(segment
		(start 227 137.025)
		(end 226.025 137.025)
		(width 0.1)
		(layer "F.Cu")
		(net 1336)
	)
	(segment
		(start 226.025 137.025)
		(end 225.9 136.9)
		(width 0.1)
		(layer "F.Cu")
		(net 1336)
	)
	(segment
		(start 218.25 161.95)
		(end 218.2175 161.9825)
		(width 0.1)
		(layer "F.Cu")
		(net 1336)
	)
	(segment
		(start 229.825 160.3)
		(end 229.5 160.3)
		(width 0.1)
		(layer "F.Cu")
		(net 1336)
	)
	(segment
		(start 181.8492 170.7492)
		(end 182 170.9)
		(width 0.182)
		(layer "F.Cu")
		(net 1336)
	)
	(segment
		(start 163.9625 171.0242)
		(end 164.9758 171.0242)
		(width 0.182)
		(layer "F.Cu")
		(net 1336)
	)
	(segment
		(start 235.515 136.4)
		(end 235.515 135.4)
		(width 0.177)
		(layer "F.Cu")
		(net 1336)
	)
	(segment
		(start 195.1 159.3)
		(end 195.099999 160.050001)
		(width 0.177)
		(layer "F.Cu")
		(net 1336)
	)
	(segment
		(start 218.2175 161.9825)
		(end 217.1457 161.9825)
		(width 0.1)
		(layer "F.Cu")
		(net 1336)
	)
	(segment
		(start 225.9 136.2)
		(end 226.1 136)
		(width 0.1)
		(layer "F.Cu")
		(net 1336)
	)
	(segment
		(start 163.2633 171.0242)
		(end 163.9625 171.0242)
		(width 0.182)
		(layer "F.Cu")
		(net 1336)
	)
	(segment
		(start 216.34 161.97)
		(end 217.1332 161.97)
		(width 0.1)
		(layer "F.Cu")
		(net 1336)
	)
	(segment
		(start 217.1332 161.97)
		(end 217.1457 161.9825)
		(width 0.1)
		(layer "F.Cu")
		(net 1336)
	)
	(segment
		(start 180.9 170.7492)
		(end 181.8492 170.7492)
		(width 0.182)
		(layer "F.Cu")
		(net 1336)
	)
	(segment
		(start 163.1375 171.15)
		(end 163.2633 171.0242)
		(width 0.182)
		(layer "F.Cu")
		(net 1336)
	)
	(segment
		(start 229.5 160.3)
		(end 229.15 160.65)
		(width 0.1)
		(layer "F.Cu")
		(net 1336)
	)
	(segment
		(start 234.7 135.6)
		(end 234.75 135.55)
		(width 0.1)
		(layer "F.Cu")
		(net 1336)
	)
	(segment
		(start 162.3 171.15)
		(end 163.1375 171.15)
		(width 0.182)
		(layer "F.Cu")
		(net 1336)
	)
	(segment
		(start 180.3125 171.15)
		(end 180.7133 170.7492)
		(width 0.182)
		(layer "F.Cu")
		(net 1336)
	)
	(segment
		(start 180.7133 170.7492)
		(end 180.9 170.7492)
		(width 0.182)
		(layer "F.Cu")
		(net 1336)
	)
	(segment
		(start 229.15 160.65)
		(end 229.15 161.5)
		(width 0.1)
		(layer "F.Cu")
		(net 1336)
	)
	(segment
		(start 226.1 136)
		(end 234.7 136)
		(width 0.1)
		(layer "F.Cu")
		(net 1336)
	)
	(segment
		(start 225.9 136.9)
		(end 225.9 136.2)
		(width 0.1)
		(layer "F.Cu")
		(net 1336)
	)
	(segment
		(start 234.7 136)
		(end 234.7 135.6)
		(width 0.1)
		(layer "F.Cu")
		(net 1336)
	)
	(segment
		(start 235.115 136)
		(end 235.515 136.4)
		(width 0.1)
		(layer "F.Cu")
		(net 1336)
	)
	(segment
		(start 179.25 171.15)
		(end 180.3125 171.15)
		(width 0.182)
		(layer "F.Cu")
		(net 1336)
	)
	(segment
		(start 234.7 136)
		(end 235.115 136)
		(width 0.1)
		(layer "F.Cu")
		(net 1336)
	)
	(segment
		(start 226.1 133.25)
		(end 226.075 133.225)
		(width 0.1)
		(layer "F.Cu")
		(net 1336)
	)
	(segment
		(start 226.1 136)
		(end 226.1 133.25)
		(width 0.1)
		(layer "F.Cu")
		(net 1336)
	)
	(via
		(at 195.1 159.3)
		(size 0.45)
		(drill 0.2)
		(layers "F.Cu" "B.Cu")
		(net 1336)
	)
	(via
		(at 234.75 135.55)
		(size 0.45)
		(drill 0.2)
		(layers "F.Cu" "B.Cu")
		(net 1336)
	)
	(via
		(at 218.25 161.95)
		(size 0.45)
		(drill 0.2)
		(layers "F.Cu" "B.Cu")
		(net 1336)
	)
	(via
		(at 254.1 126.7)
		(size 0.45)
		(drill 0.2)
		(layers "F.Cu" "B.Cu")
		(net 1336)
	)
	(via
		(at 182 170.9)
		(size 0.45)
		(drill 0.2)
		(layers "F.Cu" "B.Cu")
		(net 1336)
	)
	(via
		(at 216.34 161.97)
		(size 0.45)
		(drill 0.2)
		(layers "F.Cu" "B.Cu")
		(net 1336)
	)
	(via
		(at 165 171)
		(size 0.45)
		(drill 0.2)
		(layers "F.Cu" "B.Cu")
		(net 1336)
	)
	(via
		(at 229.825 160.3)
		(size 0.45)
		(drill 0.2)
		(layers "F.Cu" "B.Cu")
		(net 1336)
	)
	(via
		(at 226.075 133.225)
		(size 0.45)
		(drill 0.2)
		(layers "F.Cu" "B.Cu")
		(net 1336)
	)
	(segment
		(start 215.55 148.74)
		(end 215.55 152.57)
		(width 0.1)
		(layer "B.Cu")
		(net 1336)
	)
	(segment
		(start 226.075 133.225)
		(end 226.075 138.215)
		(width 0.1)
		(layer "B.Cu")
		(net 1336)
	)
	(segment
		(start 254.1 127.073)
		(end 254.1 126.7)
		(width 0.1)
		(layer "B.Cu")
		(net 1336)
	)
	(segment
		(start 226.075 138.215)
		(end 215.55 148.74)
		(width 0.1)
		(layer "B.Cu")
		(net 1336)
	)
	(segment
		(start 217.37 161.07)
		(end 218.25 161.95)
		(width 0.1)
		(layer "B.Cu")
		(net 1336)
	)
	(segment
		(start 217.37 154.39)
		(end 217.37 161.07)
		(width 0.1)
		(layer "B.Cu")
		(net 1336)
	)
	(segment
		(start 215.55 152.57)
		(end 217.37 154.39)
		(width 0.1)
		(layer "B.Cu")
		(net 1336)
	)
	(segment
		(start 195.45 158.81)
		(end 207.53 158.81)
		(width 0.1)
		(layer "In3.Cu")
		(net 1336)
	)
	(segment
		(start 215.66 161.97)
		(end 216.34 161.97)
		(width 0.1)
		(layer "In3.Cu")
		(net 1336)
	)
	(segment
		(start 186.475 166.625)
		(end 189.55 163.55)
		(width 0.1)
		(layer "In3.Cu")
		(net 1336)
	)
	(segment
		(start 225.55 160.3)
		(end 223.9 161.95)
		(width 0.1)
		(layer "In3.Cu")
		(net 1336)
	)
	(segment
		(start 195.1 159.75)
		(end 195.1 159.3)
		(width 0.1)
		(layer "In3.Cu")
		(net 1336)
	)
	(segment
		(start 214.61 163.02)
		(end 215.66 161.97)
		(width 0.1)
		(layer "In3.Cu")
		(net 1336)
	)
	(segment
		(start 223.9 161.95)
		(end 218.25 161.95)
		(width 0.1)
		(layer "In3.Cu")
		(net 1336)
	)
	(segment
		(start 184.2 173.5)
		(end 184.2 178.63)
		(width 0.1)
		(layer "In3.Cu")
		(net 1336)
	)
	(segment
		(start 211.74 163.02)
		(end 214.61 163.02)
		(width 0.1)
		(layer "In3.Cu")
		(net 1336)
	)
	(segment
		(start 189.55 163.55)
		(end 189.55 162.125)
		(width 0.1)
		(layer "In3.Cu")
		(net 1336)
	)
	(segment
		(start 182.01 170.89)
		(end 182.01 168.64)
		(width 0.1)
		(layer "In3.Cu")
		(net 1336)
	)
	(segment
		(start 207.53 158.81)
		(end 211.74 163.02)
		(width 0.1)
		(layer "In3.Cu")
		(net 1336)
	)
	(segment
		(start 168.52 180.21)
		(end 165 176.69)
		(width 0.1)
		(layer "In3.Cu")
		(net 1336)
	)
	(segment
		(start 229.825 160.3)
		(end 225.55 160.3)
		(width 0.1)
		(layer "In3.Cu")
		(net 1336)
	)
	(segment
		(start 182.62 180.21)
		(end 168.52 180.21)
		(width 0.1)
		(layer "In3.Cu")
		(net 1336)
	)
	(segment
		(start 182 170.9)
		(end 182 171.3)
		(width 0.1)
		(layer "In3.Cu")
		(net 1336)
	)
	(segment
		(start 191.6 160.075)
		(end 194.775 160.075)
		(width 0.1)
		(layer "In3.Cu")
		(net 1336)
	)
	(segment
		(start 165 176.69)
		(end 165 171)
		(width 0.1)
		(layer "In3.Cu")
		(net 1336)
	)
	(segment
		(start 182 170.9)
		(end 182.01 170.89)
		(width 0.1)
		(layer "In3.Cu")
		(net 1336)
	)
	(segment
		(start 184.025 166.625)
		(end 186.475 166.625)
		(width 0.1)
		(layer "In3.Cu")
		(net 1336)
	)
	(segment
		(start 195.1 159.16)
		(end 195.43 158.83)
		(width 0.1)
		(layer "In3.Cu")
		(net 1336)
	)
	(segment
		(start 182 171.3)
		(end 184.2 173.5)
		(width 0.1)
		(layer "In3.Cu")
		(net 1336)
	)
	(segment
		(start 189.55 162.125)
		(end 191.6 160.075)
		(width 0.1)
		(layer "In3.Cu")
		(net 1336)
	)
	(segment
		(start 182.01 168.64)
		(end 184.025 166.625)
		(width 0.1)
		(layer "In3.Cu")
		(net 1336)
	)
	(segment
		(start 195.43 158.83)
		(end 195.45 158.81)
		(width 0.1)
		(layer "In3.Cu")
		(net 1336)
	)
	(segment
		(start 184.2 178.63)
		(end 182.62 180.21)
		(width 0.1)
		(layer "In3.Cu")
		(net 1336)
	)
	(segment
		(start 194.775 160.075)
		(end 195.1 159.75)
		(width 0.1)
		(layer "In3.Cu")
		(net 1336)
	)
	(segment
		(start 195.1 159.3)
		(end 195.1 159.16)
		(width 0.1)
		(layer "In3.Cu")
		(net 1336)
	)
	(segment
		(start 252.75 128.05)
		(end 254.1 126.7)
		(width 0.1)
		(layer "In5.Cu")
		(net 1336)
	)
	(segment
		(start 234.75 135.55)
		(end 234.75 134.65)
		(width 0.1)
		(layer "In5.Cu")
		(net 1336)
	)
	(segment
		(start 244.1 129.25)
		(end 245.3 128.05)
		(width 0.1)
		(layer "In5.Cu")
		(net 1336)
	)
	(segment
		(start 235.69 132.717842)
		(end 239.157842 129.25)
		(width 0.1)
		(layer "In5.Cu")
		(net 1336)
	)
	(segment
		(start 234.75 134.65)
		(end 235.69 133.71)
		(width 0.1)
		(layer "In5.Cu")
		(net 1336)
	)
	(segment
		(start 239.157842 129.25)
		(end 244.1 129.25)
		(width 0.1)
		(layer "In5.Cu")
		(net 1336)
	)
	(segment
		(start 245.3 128.05)
		(end 252.75 128.05)
		(width 0.1)
		(layer "In5.Cu")
		(net 1336)
	)
	(segment
		(start 235.69 133.71)
		(end 235.69 132.717842)
		(width 0.1)
		(layer "In5.Cu")
		(net 1336)
	)
	(segment
		(start 254.1 127.6)
		(end 254.1 127.327)
		(width 0.1)
		(layer "B.Cu")
		(net 1337)
	)
	(segment
		(start 216.1575 163.2525)
		(end 217.1457 163.2525)
		(width 0.1)
		(layer "F.Cu")
		(net 1338)
	)
	(segment
		(start 218.2475 163.2525)
		(end 217.1457 163.2525)
		(width 0.1)
		(layer "F.Cu")
		(net 1338)
	)
	(segment
		(start 180.27 188.64)
		(end 180.27 184.03)
		(width 0.1)
		(layer "F.Cu")
		(net 1338)
	)
	(segment
		(start 180.77 188.64)
		(end 180.27 188.64)
		(width 0.1)
		(layer "F.Cu")
		(net 1338)
	)
	(segment
		(start 235.515 140.565)
		(end 235.515 140)
		(width 0.1)
		(layer "F.Cu")
		(net 1338)
	)
	(segment
		(start 216.15 163.26)
		(end 216.1575 163.2525)
		(width 0.1)
		(layer "F.Cu")
		(net 1338)
	)
	(segment
		(start 235.515 139)
		(end 235.515 140)
		(width 0.177)
		(layer "F.Cu")
		(net 1338)
	)
	(segment
		(start 235.75 140.8)
		(end 235.515 140.565)
		(width 0.1)
		(layer "F.Cu")
		(net 1338)
	)
	(segment
		(start 246.5 143.473)
		(end 246.5 143.25)
		(width 0.1)
		(layer "F.Cu")
		(net 1338)
	)
	(segment
		(start 230.21 160.9)
		(end 229.75 160.9)
		(width 0.1)
		(layer "F.Cu")
		(net 1338)
	)
	(segment
		(start 229.65 161)
		(end 229.65 161.5)
		(width 0.1)
		(layer "F.Cu")
		(net 1338)
	)
	(segment
		(start 179.77 188.64)
		(end 180.27 188.64)
		(width 0.1)
		(layer "F.Cu")
		(net 1338)
	)
	(segment
		(start 236.5 140.8)
		(end 235.75 140.8)
		(width 0.1)
		(layer "F.Cu")
		(net 1338)
	)
	(segment
		(start 235.515 138.415)
		(end 235 137.9)
		(width 0.1)
		(layer "F.Cu")
		(net 1338)
	)
	(segment
		(start 218.25 163.25)
		(end 218.2475 163.2525)
		(width 0.1)
		(layer "F.Cu")
		(net 1338)
	)
	(segment
		(start 195.600001 160.050001)
		(end 195.600001 159.499999)
		(width 0.177)
		(layer "F.Cu")
		(net 1338)
	)
	(segment
		(start 235 136.7)
		(end 235 137.9)
		(width 0.1)
		(layer "F.Cu")
		(net 1338)
	)
	(segment
		(start 195.600001 159.499999)
		(end 195.8 159.3)
		(width 0.177)
		(layer "F.Cu")
		(net 1338)
	)
	(segment
		(start 227 136.375)
		(end 227.075 136.3)
		(width 0.1)
		(layer "F.Cu")
		(net 1338)
	)
	(segment
		(start 235.515 139)
		(end 235.515 138.415)
		(width 0.1)
		(layer "F.Cu")
		(net 1338)
	)
	(segment
		(start 234.6 136.3)
		(end 235 136.7)
		(width 0.1)
		(layer "F.Cu")
		(net 1338)
	)
	(segment
		(start 227.075 136.3)
		(end 234.6 136.3)
		(width 0.1)
		(layer "F.Cu")
		(net 1338)
	)
	(segment
		(start 229.75 160.9)
		(end 229.65 161)
		(width 0.1)
		(layer "F.Cu")
		(net 1338)
	)
	(via
		(at 246.5 143.25)
		(size 0.45)
		(drill 0.2)
		(layers "F.Cu" "B.Cu")
		(net 1338)
	)
	(via
		(at 230.21 160.9)
		(size 0.45)
		(drill 0.2)
		(layers "F.Cu" "B.Cu")
		(net 1338)
	)
	(via
		(at 216.15 163.26)
		(size 0.45)
		(drill 0.2)
		(layers "F.Cu" "B.Cu")
		(net 1338)
	)
	(via
		(at 236.5 140.8)
		(size 0.45)
		(drill 0.2)
		(layers "F.Cu" "B.Cu")
		(net 1338)
	)
	(via
		(at 180.27 184.03)
		(size 0.45)
		(drill 0.2)
		(layers "F.Cu" "B.Cu")
		(net 1338)
	)
	(via
		(at 195.8 159.3)
		(size 0.45)
		(drill 0.2)
		(layers "F.Cu" "B.Cu")
		(net 1338)
	)
	(via
		(at 218.25 163.25)
		(size 0.45)
		(drill 0.2)
		(layers "F.Cu" "B.Cu")
		(net 1338)
	)
	(segment
		(start 207.32 159.3)
		(end 211.67 163.65)
		(width 0.1)
		(layer "In3.Cu")
		(net 1338)
	)
	(segment
		(start 181.36 182.11)
		(end 180.57 182.11)
		(width 0.1)
		(layer "In3.Cu")
		(net 1338)
	)
	(segment
		(start 195.8 159.3)
		(end 207.32 159.3)
		(width 0.1)
		(layer "In3.Cu")
		(net 1338)
	)
	(segment
		(start 195.8 159.85)
		(end 195.175 160.475)
		(width 0.1)
		(layer "In3.Cu")
		(net 1338)
	)
	(segment
		(start 182.475 171.325)
		(end 184.6 173.45)
		(width 0.1)
		(layer "In3.Cu")
		(net 1338)
	)
	(segment
		(start 189.975 163.775)
		(end 186.75 167)
		(width 0.1)
		(layer "In3.Cu")
		(net 1338)
	)
	(segment
		(start 184.6 178.87)
		(end 181.36 182.11)
		(width 0.1)
		(layer "In3.Cu")
		(net 1338)
	)
	(segment
		(start 184.125 167)
		(end 182.475 168.65)
		(width 0.1)
		(layer "In3.Cu")
		(net 1338)
	)
	(segment
		(start 211.67 163.65)
		(end 215.76 163.65)
		(width 0.1)
		(layer "In3.Cu")
		(net 1338)
	)
	(segment
		(start 191.775 160.475)
		(end 189.975 162.275)
		(width 0.1)
		(layer "In3.Cu")
		(net 1338)
	)
	(segment
		(start 180.27 182.41)
		(end 180.27 184.03)
		(width 0.1)
		(layer "In3.Cu")
		(net 1338)
	)
	(segment
		(start 244.85 141.25)
		(end 240.77 141.25)
		(width 0.1)
		(layer "In3.Cu")
		(net 1338)
	)
	(segment
		(start 246.5 143.25)
		(end 246.475 143.225)
		(width 0.1)
		(layer "In3.Cu")
		(net 1338)
	)
	(segment
		(start 240.52 141)
		(end 236.7 141)
		(width 0.1)
		(layer "In3.Cu")
		(net 1338)
	)
	(segment
		(start 184.6 173.45)
		(end 184.6 178.87)
		(width 0.1)
		(layer "In3.Cu")
		(net 1338)
	)
	(segment
		(start 246.475 142.875)
		(end 244.85 141.25)
		(width 0.1)
		(layer "In3.Cu")
		(net 1338)
	)
	(segment
		(start 189.975 162.275)
		(end 189.975 163.775)
		(width 0.1)
		(layer "In3.Cu")
		(net 1338)
	)
	(segment
		(start 195.8 159.3)
		(end 195.8 159.85)
		(width 0.1)
		(layer "In3.Cu")
		(net 1338)
	)
	(segment
		(start 228.6 163.25)
		(end 218.25 163.25)
		(width 0.1)
		(layer "In3.Cu")
		(net 1338)
	)
	(segment
		(start 180.57 182.11)
		(end 180.27 182.41)
		(width 0.1)
		(layer "In3.Cu")
		(net 1338)
	)
	(segment
		(start 215.76 163.65)
		(end 216.15 163.26)
		(width 0.1)
		(layer "In3.Cu")
		(net 1338)
	)
	(segment
		(start 186.75 167)
		(end 184.125 167)
		(width 0.1)
		(layer "In3.Cu")
		(net 1338)
	)
	(segment
		(start 182.475 168.65)
		(end 182.475 171.325)
		(width 0.1)
		(layer "In3.Cu")
		(net 1338)
	)
	(segment
		(start 246.475 143.225)
		(end 246.475 142.875)
		(width 0.1)
		(layer "In3.Cu")
		(net 1338)
	)
	(segment
		(start 230.21 161.64)
		(end 228.6 163.25)
		(width 0.1)
		(layer "In3.Cu")
		(net 1338)
	)
	(segment
		(start 236.7 141)
		(end 236.5 140.8)
		(width 0.1)
		(layer "In3.Cu")
		(net 1338)
	)
	(segment
		(start 195.175 160.475)
		(end 191.775 160.475)
		(width 0.1)
		(layer "In3.Cu")
		(net 1338)
	)
	(segment
		(start 230.21 160.9)
		(end 230.21 161.64)
		(width 0.1)
		(layer "In3.Cu")
		(net 1338)
	)
	(segment
		(start 240.77 141.25)
		(end 240.52 141)
		(width 0.1)
		(layer "In3.Cu")
		(net 1338)
	)
	(segment
		(start 230.21 160.9)
		(end 229.594669 160.9)
		(width 0.1)
		(layer "In5.Cu")
		(net 1338)
	)
	(segment
		(start 233.11 144.48)
		(end 235.75 141.84)
		(width 0.1)
		(layer "In5.Cu")
		(net 1338)
	)
	(segment
		(start 243.98 141.84)
		(end 244.33 141.49)
		(width 0.1)
		(layer "In5.Cu")
		(net 1338)
	)
	(segment
		(start 233.11 145.43)
		(end 233.11 144.48)
		(width 0.1)
		(layer "In5.Cu")
		(net 1338)
	)
	(segment
		(start 231.39 150.88)
		(end 231.39 147.15)
		(width 0.1)
		(layer "In5.Cu")
		(net 1338)
	)
	(segment
		(start 229.594669 160.9)
		(end 229.394099 160.69943)
		(width 0.1)
		(layer "In5.Cu")
		(net 1338)
	)
	(segment
		(start 229.394099 160.69943)
		(end 229.394099 152.875901)
		(width 0.1)
		(layer "In5.Cu")
		(net 1338)
	)
	(segment
		(start 246.18 142.29)
		(end 246.18 142.93)
		(width 0.1)
		(layer "In5.Cu")
		(net 1338)
	)
	(segment
		(start 231.39 147.15)
		(end 233.11 145.43)
		(width 0.1)
		(layer "In5.Cu")
		(net 1338)
	)
	(segment
		(start 235.75 141.84)
		(end 243.98 141.84)
		(width 0.1)
		(layer "In5.Cu")
		(net 1338)
	)
	(segment
		(start 245.38 141.49)
		(end 246.18 142.29)
		(width 0.1)
		(layer "In5.Cu")
		(net 1338)
	)
	(segment
		(start 246.18 142.93)
		(end 246.5 143.25)
		(width 0.1)
		(layer "In5.Cu")
		(net 1338)
	)
	(segment
		(start 244.33 141.49)
		(end 245.38 141.49)
		(width 0.1)
		(layer "In5.Cu")
		(net 1338)
	)
	(segment
		(start 229.394099 152.875901)
		(end 231.39 150.88)
		(width 0.1)
		(layer "In5.Cu")
		(net 1338)
	)
	(segment
		(start 246.5 144)
		(end 246.5 143.727)
		(width 0.1)
		(layer "F.Cu")
		(net 1339)
	)
	(segment
		(start 161 183.515)
		(end 160.515 184)
		(width 0.1)
		(layer "F.Cu")
		(net 1340)
	)
	(segment
		(start 159.5 184.15)
		(end 159.5 185.04)
		(width 0.1)
		(layer "F.Cu")
		(net 1340)
	)
	(segment
		(start 159.5 185.04)
		(end 159.125 185.415)
		(width 0.1)
		(layer "F.Cu")
		(net 1340)
	)
	(segment
		(start 160.515 184)
		(end 159.65 184)
		(width 0.1)
		(layer "F.Cu")
		(net 1340)
	)
	(segment
		(start 159.125 185.415)
		(end 159 185.415)
		(width 0.1)
		(layer "F.Cu")
		(net 1340)
	)
	(segment
		(start 158.625 185.415)
		(end 158.5 185.29)
		(width 0.1)
		(layer "F.Cu")
		(net 1340)
	)
	(segment
		(start 158.5 185.29)
		(end 158.5 185.137)
		(width 0.1)
		(layer "F.Cu")
		(net 1340)
	)
	(segment
		(start 159 185.75)
		(end 159 185.415)
		(width 0.107)
		(layer "F.Cu")
		(net 1340)
	)
	(segment
		(start 159.65 184)
		(end 159.5 184.15)
		(width 0.1)
		(layer "F.Cu")
		(net 1340)
	)
	(segment
		(start 159 185.415)
		(end 158.625 185.415)
		(width 0.1)
		(layer "F.Cu")
		(net 1340)
	)
	(via
		(at 251.35 126.025)
		(size 0.45)
		(drill 0.2)
		(layers "F.Cu" "B.Cu")
		(net 1340)
	)
	(via
		(at 159 185.415)
		(size 0.45)
		(drill 0.2)
		(layers "F.Cu" "B.Cu")
		(net 1340)
	)
	(segment
		(start 251.3 127.6)
		(end 251.3 126.075)
		(width 0.1)
		(layer "B.Cu")
		(net 1340)
	)
	(segment
		(start 251.3 126.075)
		(end 251.35 126.025)
		(width 0.1)
		(layer "B.Cu")
		(net 1340)
	)
	(segment
		(start 159 185.415)
		(end 159.005 185.415)
		(width 0.1)
		(layer "In3.Cu")
		(net 1340)
	)
	(segment
		(start 258.95 187.65)
		(end 267.9 178.7)
		(width 0.1)
		(layer "In3.Cu")
		(net 1340)
	)
	(segment
		(start 267.9 151.975)
		(end 266.325 150.4)
		(width 0.1)
		(layer "In3.Cu")
		(net 1340)
	)
	(segment
		(start 266.325 150.4)
		(end 266.325 134.3)
		(width 0.1)
		(layer "In3.Cu")
		(net 1340)
	)
	(segment
		(start 193.1 184.4)
		(end 196.35 187.65)
		(width 0.1)
		(layer "In3.Cu")
		(net 1340)
	)
	(segment
		(start 254.575 126.025)
		(end 251.35 126.025)
		(width 0.1)
		(layer "In3.Cu")
		(net 1340)
	)
	(segment
		(start 258.025 131.475)
		(end 255.7 129.15)
		(width 0.1)
		(layer "In3.Cu")
		(net 1340)
	)
	(segment
		(start 167.6 187.65)
		(end 184.55 187.65)
		(width 0.1)
		(layer "In3.Cu")
		(net 1340)
	)
	(segment
		(start 262.1 131.475)
		(end 258.025 131.475)
		(width 0.1)
		(layer "In3.Cu")
		(net 1340)
	)
	(segment
		(start 160.04 186.45)
		(end 166.4 186.45)
		(width 0.1)
		(layer "In3.Cu")
		(net 1340)
	)
	(segment
		(start 255.7 127.15)
		(end 254.575 126.025)
		(width 0.1)
		(layer "In3.Cu")
		(net 1340)
	)
	(segment
		(start 159.005 185.415)
		(end 160.04 186.45)
		(width 0.1)
		(layer "In3.Cu")
		(net 1340)
	)
	(segment
		(start 196.35 187.65)
		(end 258.95 187.65)
		(width 0.1)
		(layer "In3.Cu")
		(net 1340)
	)
	(segment
		(start 264.675 132.65)
		(end 263.275 132.65)
		(width 0.1)
		(layer "In3.Cu")
		(net 1340)
	)
	(segment
		(start 267.9 178.7)
		(end 267.9 151.975)
		(width 0.1)
		(layer "In3.Cu")
		(net 1340)
	)
	(segment
		(start 266.325 134.3)
		(end 264.675 132.65)
		(width 0.1)
		(layer "In3.Cu")
		(net 1340)
	)
	(segment
		(start 184.55 187.65)
		(end 187.8 184.4)
		(width 0.1)
		(layer "In3.Cu")
		(net 1340)
	)
	(segment
		(start 187.8 184.4)
		(end 193.1 184.4)
		(width 0.1)
		(layer "In3.Cu")
		(net 1340)
	)
	(segment
		(start 166.4 186.45)
		(end 167.6 187.65)
		(width 0.1)
		(layer "In3.Cu")
		(net 1340)
	)
	(segment
		(start 255.7 129.15)
		(end 255.7 127.15)
		(width 0.1)
		(layer "In3.Cu")
		(net 1340)
	)
	(segment
		(start 263.275 132.65)
		(end 262.1 131.475)
		(width 0.1)
		(layer "In3.Cu")
		(net 1340)
	)
	(segment
		(start 233.1 161.75)
		(end 232.05 161.75)
		(width 0.1)
		(layer "F.Cu")
		(net 1349)
	)
	(segment
		(start 233.55 160.185452)
		(end 233.55 161.3)
		(width 0.1)
		(layer "F.Cu")
		(net 1349)
	)
	(segment
		(start 234.642726 159.092726)
		(end 233.55 160.185452)
		(width 0.1)
		(layer "F.Cu")
		(net 1349)
	)
	(segment
		(start 251.7 144)
		(end 251.7 143.25)
		(width 0.1)
		(layer "F.Cu")
		(net 1349)
	)
	(segment
		(start 233.55 161.3)
		(end 233.1 161.75)
		(width 0.1)
		(layer "F.Cu")
		(net 1349)
	)
	(segment
		(start 232.05 161.75)
		(end 231.580275 161.280275)
		(width 0.1)
		(layer "F.Cu")
		(net 1349)
	)
	(segment
		(start 231.580275 161.280275)
		(end 231.580275 161.27212)
		(width 0.1)
		(layer "F.Cu")
		(net 1349)
	)
	(via
		(at 251.7 143.25)
		(size 0.45)
		(drill 0.2)
		(layers "F.Cu" "B.Cu")
		(net 1349)
	)
	(via
		(at 234.642726 159.092726)
		(size 0.45)
		(drill 0.2)
		(layers "F.Cu" "B.Cu")
		(net 1349)
	)
	(segment
		(start 258.75 150.45)
		(end 258.75 146.15)
		(width 0.1)
		(layer "In3.Cu")
		(net 1349)
	)
	(segment
		(start 249.034316 151.05)
		(end 258.15 151.05)
		(width 0.1)
		(layer "In3.Cu")
		(net 1349)
	)
	(segment
		(start 251.7 142.625)
		(end 251.7 143.25)
		(width 0.1)
		(layer "In3.Cu")
		(net 1349)
	)
	(segment
		(start 239.701474 154.89)
		(end 245.194316 154.89)
		(width 0.1)
		(layer "In3.Cu")
		(net 1349)
	)
	(segment
		(start 251.9 142.425)
		(end 251.7 142.625)
		(width 0.1)
		(layer "In3.Cu")
		(net 1349)
	)
	(segment
		(start 245.194316 154.89)
		(end 249.034316 151.05)
		(width 0.1)
		(layer "In3.Cu")
		(net 1349)
	)
	(segment
		(start 258.75 146.15)
		(end 256.25 143.65)
		(width 0.1)
		(layer "In3.Cu")
		(net 1349)
	)
	(segment
		(start 256.25 143.2)
		(end 255.1 142.05)
		(width 0.1)
		(layer "In3.Cu")
		(net 1349)
	)
	(segment
		(start 235.498748 159.092726)
		(end 239.701474 154.89)
		(width 0.1)
		(layer "In3.Cu")
		(net 1349)
	)
	(segment
		(start 258.15 151.05)
		(end 258.75 150.45)
		(width 0.1)
		(layer "In3.Cu")
		(net 1349)
	)
	(segment
		(start 252.825 142.05)
		(end 252.45 142.425)
		(width 0.1)
		(layer "In3.Cu")
		(net 1349)
	)
	(segment
		(start 256.25 143.65)
		(end 256.25 143.2)
		(width 0.1)
		(layer "In3.Cu")
		(net 1349)
	)
	(segment
		(start 234.642726 159.092726)
		(end 235.498748 159.092726)
		(width 0.1)
		(layer "In3.Cu")
		(net 1349)
	)
	(segment
		(start 252.45 142.425)
		(end 251.9 142.425)
		(width 0.1)
		(layer "In3.Cu")
		(net 1349)
	)
	(segment
		(start 255.1 142.05)
		(end 252.825 142.05)
		(width 0.1)
		(layer "In3.Cu")
		(net 1349)
	)
	(segment
		(start 248.8 121.7)
		(end 248.8 121.55)
		(width 0.1)
		(layer "F.Cu")
		(net 1350)
	)
	(segment
		(start 248.8 121.55)
		(end 248.475 121.225)
		(width 0.1)
		(layer "F.Cu")
		(net 1350)
	)
	(via
		(at 219.45 124.85)
		(size 0.45)
		(drill 0.2)
		(layers "F.Cu" "B.Cu")
		(net 1350)
	)
	(via
		(at 248.475 121.225)
		(size 0.45)
		(drill 0.2)
		(layers "F.Cu" "B.Cu")
		(net 1350)
	)
	(segment
		(start 220.115 124.8)
		(end 219.5 124.8)
		(width 0.1)
		(layer "B.Cu")
		(net 1350)
	)
	(segment
		(start 219.5 124.8)
		(end 219.45 124.85)
		(width 0.1)
		(layer "B.Cu")
		(net 1350)
	)
	(segment
		(start 251.125 121.1)
		(end 251.125 120.925)
		(width 0.1)
		(layer "In5.Cu")
		(net 1350)
	)
	(segment
		(start 251.125 120.925)
		(end 251.45 120.6)
		(width 0.1)
		(layer "In5.Cu")
		(net 1350)
	)
	(segment
		(start 244.225 120.7)
		(end 245.475 119.45)
		(width 0.1)
		(layer "In5.Cu")
		(net 1350)
	)
	(segment
		(start 250.225 122)
		(end 251.125 121.1)
		(width 0.1)
		(layer "In5.Cu")
		(net 1350)
	)
	(segment
		(start 230.55 124.85)
		(end 234.7 120.7)
		(width 0.1)
		(layer "In5.Cu")
		(net 1350)
	)
	(segment
		(start 230.55 124.85)
		(end 219.45 124.85)
		(width 0.1)
		(layer "In5.Cu")
		(net 1350)
	)
	(segment
		(start 245.475 119.45)
		(end 250.975 119.45)
		(width 0.1)
		(layer "In5.Cu")
		(net 1350)
	)
	(segment
		(start 234.7 120.7)
		(end 244.225 120.7)
		(width 0.1)
		(layer "In5.Cu")
		(net 1350)
	)
	(segment
		(start 250.175 122)
		(end 250.225 122)
		(width 0.1)
		(layer "In5.Cu")
		(net 1350)
	)
	(segment
		(start 249.25 122)
		(end 250.175 122)
		(width 0.1)
		(layer "In5.Cu")
		(net 1350)
	)
	(segment
		(start 251.45 120.6)
		(end 251.45 119.925)
		(width 0.1)
		(layer "In5.Cu")
		(net 1350)
	)
	(segment
		(start 251.45 119.925)
		(end 250.975 119.45)
		(width 0.1)
		(layer "In5.Cu")
		(net 1350)
	)
	(segment
		(start 248.475 121.225)
		(end 249.25 122)
		(width 0.1)
		(layer "In5.Cu")
		(net 1350)
	)
	(segment
		(start 208.5 138.5)
		(end 209 139)
		(width 0.256)
		(layer "F.Cu")
		(net 1351)
	)
	(via
		(at 209 139)
		(size 0.45)
		(drill 0.2)
		(layers "F.Cu" "B.Cu")
		(net 1351)
	)
	(via
		(at 241.1 123.5)
		(size 0.45)
		(drill 0.2)
		(layers "F.Cu" "B.Cu")
		(net 1351)
	)
	(segment
		(start 247.4495 126.1495)
		(end 247.7 126.4)
		(width 0.1)
		(layer "B.Cu")
		(net 1351)
	)
	(segment
		(start 241.7005 126.1495)
		(end 247.4495 126.1495)
		(width 0.1)
		(layer "B.Cu")
		(net 1351)
	)
	(segment
		(start 241.1495 125.5985)
		(end 241.7005 126.1495)
		(width 0.1)
		(layer "B.Cu")
		(net 1351)
	)
	(segment
		(start 241.1 123.5)
		(end 241.1495 123.5495)
		(width 0.1)
		(layer "B.Cu")
		(net 1351)
	)
	(segment
		(start 247.7 126.4)
		(end 247.7 127.6)
		(width 0.1)
		(layer "B.Cu")
		(net 1351)
	)
	(segment
		(start 241.1495 123.5495)
		(end 241.1495 125.5985)
		(width 0.1)
		(layer "B.Cu")
		(net 1351)
	)
	(segment
		(start 238.878421 124.1)
		(end 222.378421 140.6)
		(width 0.1)
		(layer "In5.Cu")
		(net 1351)
	)
	(segment
		(start 239.825 123.875)
		(end 239.6 124.1)
		(width 0.1)
		(layer "In5.Cu")
		(net 1351)
	)
	(segment
		(start 240.65 123.5)
		(end 240.275 123.875)
		(width 0.1)
		(layer "In5.Cu")
		(net 1351)
	)
	(segment
		(start 218.325 140.6)
		(end 217.145 139.42)
		(width 0.1)
		(layer "In5.Cu")
		(net 1351)
	)
	(segment
		(start 217.145 139.42)
		(end 209.42 139.42)
		(width 0.1)
		(layer "In5.Cu")
		(net 1351)
	)
	(segment
		(start 209.42 139.42)
		(end 209 139)
		(width 0.1)
		(layer "In5.Cu")
		(net 1351)
	)
	(segment
		(start 239.6 124.1)
		(end 238.878421 124.1)
		(width 0.1)
		(layer "In5.Cu")
		(net 1351)
	)
	(segment
		(start 241.1 123.5)
		(end 240.65 123.5)
		(width 0.1)
		(layer "In5.Cu")
		(net 1351)
	)
	(segment
		(start 240.275 123.875)
		(end 239.825 123.875)
		(width 0.1)
		(layer "In5.Cu")
		(net 1351)
	)
	(segment
		(start 222.378421 140.6)
		(end 218.325 140.6)
		(width 0.1)
		(layer "In5.Cu")
		(net 1351)
	)
	(segment
		(start 205.5 134.5)
		(end 206 135)
		(width 0.256)
		(layer "F.Cu")
		(net 1352)
	)
	(via
		(at 206 135)
		(size 0.45)
		(drill 0.2)
		(layers "F.Cu" "B.Cu")
		(net 1352)
	)
	(via
		(at 241.3 121.5)
		(size 0.45)
		(drill 0.2)
		(layers "F.Cu" "B.Cu")
		(net 1352)
	)
	(segment
		(start 249.2 126.12)
		(end 249.2 126.9)
		(width 0.1)
		(layer "B.Cu")
		(net 1352)
	)
	(segment
		(start 241.6 121.8)
		(end 241.6 125.7)
		(width 0.1)
		(layer "B.Cu")
		(net 1352)
	)
	(segment
		(start 241.8495 125.9495)
		(end 249.0295 125.9495)
		(width 0.1)
		(layer "B.Cu")
		(net 1352)
	)
	(segment
		(start 249.2 126.9)
		(end 248.5 127.6)
		(width 0.1)
		(layer "B.Cu")
		(net 1352)
	)
	(segment
		(start 241.6 125.7)
		(end 241.8495 125.9495)
		(width 0.1)
		(layer "B.Cu")
		(net 1352)
	)
	(segment
		(start 249.0295 125.9495)
		(end 249.2 126.12)
		(width 0.1)
		(layer "B.Cu")
		(net 1352)
	)
	(segment
		(start 241.3 121.5)
		(end 241.6 121.8)
		(width 0.1)
		(layer "B.Cu")
		(net 1352)
	)
	(segment
		(start 225.315684 135.4)
		(end 206.4 135.4)
		(width 0.1)
		(layer "In5.Cu")
		(net 1352)
	)
	(segment
		(start 206.4 135.4)
		(end 206 135)
		(width 0.1)
		(layer "In5.Cu")
		(net 1352)
	)
	(segment
		(start 239.015684 121.7)
		(end 225.315684 135.4)
		(width 0.1)
		(layer "In5.Cu")
		(net 1352)
	)
	(segment
		(start 241.1 121.7)
		(end 239.015684 121.7)
		(width 0.1)
		(layer "In5.Cu")
		(net 1352)
	)
	(segment
		(start 241.3 121.5)
		(end 241.1 121.7)
		(width 0.1)
		(layer "In5.Cu")
		(net 1352)
	)
	(segment
		(start 206.5 143.5)
		(end 207 144)
		(width 0.256)
		(layer "F.Cu")
		(net 1353)
	)
	(via
		(at 242.1 125.575)
		(size 0.45)
		(drill 0.2)
		(layers "F.Cu" "B.Cu")
		(net 1353)
	)
	(via
		(at 207 144)
		(size 0.45)
		(drill 0.2)
		(layers "F.Cu" "B.Cu")
		(net 1353)
	)
	(segment
		(start 249.3 127.32)
		(end 249.3 127.6)
		(width 0.1)
		(layer "B.Cu")
		(net 1353)
	)
	(segment
		(start 242.1 125.575)
		(end 242.225 125.7)
		(width 0.1)
		(layer "B.Cu")
		(net 1353)
	)
	(segment
		(start 249.46 125.93)
		(end 249.46 127.16)
		(width 0.1)
		(layer "B.Cu")
		(net 1353)
	)
	(segment
		(start 242.225 125.7)
		(end 249.23 125.7)
		(width 0.1)
		(layer "B.Cu")
		(net 1353)
	)
	(segment
		(start 249.23 125.7)
		(end 249.46 125.93)
		(width 0.1)
		(layer "B.Cu")
		(net 1353)
	)
	(segment
		(start 249.46 127.16)
		(end 249.3 127.32)
		(width 0.1)
		(layer "B.Cu")
		(net 1353)
	)
	(segment
		(start 241.448526 125.8)
		(end 240.8 126.448526)
		(width 0.1)
		(layer "In5.Cu")
		(net 1353)
	)
	(segment
		(start 238.556842 127.25)
		(end 222.606842 143.2)
		(width 0.1)
		(layer "In5.Cu")
		(net 1353)
	)
	(segment
		(start 242.1 125.575)
		(end 241.875 125.8)
		(width 0.1)
		(layer "In5.Cu")
		(net 1353)
	)
	(segment
		(start 240.8 126.448526)
		(end 240.8 126.9)
		(width 0.1)
		(layer "In5.Cu")
		(net 1353)
	)
	(segment
		(start 215.790684 144.375)
		(end 207.375 144.375)
		(width 0.1)
		(layer "In5.Cu")
		(net 1353)
	)
	(segment
		(start 207.375 144.375)
		(end 207 144)
		(width 0.1)
		(layer "In5.Cu")
		(net 1353)
	)
	(segment
		(start 222.606842 143.2)
		(end 216.965684 143.2)
		(width 0.1)
		(layer "In5.Cu")
		(net 1353)
	)
	(segment
		(start 240.45 127.25)
		(end 238.556842 127.25)
		(width 0.1)
		(layer "In5.Cu")
		(net 1353)
	)
	(segment
		(start 216.965684 143.2)
		(end 215.790684 144.375)
		(width 0.1)
		(layer "In5.Cu")
		(net 1353)
	)
	(segment
		(start 241.875 125.8)
		(end 241.448526 125.8)
		(width 0.1)
		(layer "In5.Cu")
		(net 1353)
	)
	(segment
		(start 240.8 126.9)
		(end 240.45 127.25)
		(width 0.1)
		(layer "In5.Cu")
		(net 1353)
	)
	(segment
		(start 209.5 139.5)
		(end 210 140)
		(width 0.256)
		(layer "F.Cu")
		(net 1354)
	)
	(via
		(at 242.025 123.375)
		(size 0.45)
		(drill 0.2)
		(layers "F.Cu" "B.Cu")
		(net 1354)
	)
	(via
		(at 210 140)
		(size 0.45)
		(drill 0.2)
		(layers "F.Cu" "B.Cu")
		(net 1354)
	)
	(segment
		(start 242.025 124.925)
		(end 242.55 125.45)
		(width 0.1)
		(layer "B.Cu")
		(net 1354)
	)
	(segment
		(start 249.7 125.7)
		(end 249.7 127.6)
		(width 0.1)
		(layer "B.Cu")
		(net 1354)
	)
	(segment
		(start 242.025 123.375)
		(end 242.025 124.925)
		(width 0.1)
		(layer "B.Cu")
		(net 1354)
	)
	(segment
		(start 242.55 125.45)
		(end 249.45 125.45)
		(width 0.1)
		(layer "B.Cu")
		(net 1354)
	)
	(segment
		(start 249.45 125.45)
		(end 249.7 125.7)
		(width 0.1)
		(layer "B.Cu")
		(net 1354)
	)
	(segment
		(start 240.127948 124.672052)
		(end 238.872052 124.672052)
		(width 0.1)
		(layer "In5.Cu")
		(net 1354)
	)
	(segment
		(start 241.375 124.175)
		(end 240.625 124.175)
		(width 0.1)
		(layer "In5.Cu")
		(net 1354)
	)
	(segment
		(start 242.025 123.375)
		(end 242.025 123.525)
		(width 0.1)
		(layer "In5.Cu")
		(net 1354)
	)
	(segment
		(start 238.872052 124.672052)
		(end 222.544104 141)
		(width 0.1)
		(layer "In5.Cu")
		(net 1354)
	)
	(segment
		(start 217.582842 140.425)
		(end 210.425 140.425)
		(width 0.1)
		(layer "In5.Cu")
		(net 1354)
	)
	(segment
		(start 218.157842 141)
		(end 217.582842 140.425)
		(width 0.1)
		(layer "In5.Cu")
		(net 1354)
	)
	(segment
		(start 242.025 123.525)
		(end 241.375 124.175)
		(width 0.1)
		(layer "In5.Cu")
		(net 1354)
	)
	(segment
		(start 222.544104 141)
		(end 218.157842 141)
		(width 0.1)
		(layer "In5.Cu")
		(net 1354)
	)
	(segment
		(start 210.425 140.425)
		(end 210 140)
		(width 0.1)
		(layer "In5.Cu")
		(net 1354)
	)
	(segment
		(start 240.625 124.175)
		(end 240.127948 124.672052)
		(width 0.1)
		(layer "In5.Cu")
		(net 1354)
	)
	(segment
		(start 204.5 134.5)
		(end 205 135)
		(width 0.256)
		(layer "F.Cu")
		(net 1355)
	)
	(via
		(at 205 135)
		(size 0.45)
		(drill 0.2)
		(layers "F.Cu" "B.Cu")
		(net 1355)
	)
	(via
		(at 242 121.7)
		(size 0.45)
		(drill 0.2)
		(layers "F.Cu" "B.Cu")
		(net 1355)
	)
	(segment
		(start 250.1 125.5)
		(end 249.8 125.2)
		(width 0.1)
		(layer "B.Cu")
		(net 1355)
	)
	(segment
		(start 242 121.7)
		(end 242.4 122.1)
		(width 0.1)
		(layer "B.Cu")
		(net 1355)
	)
	(segment
		(start 242.4 122.1)
		(end 242.4 124.9)
		(width 0.1)
		(layer "B.Cu")
		(net 1355)
	)
	(segment
		(start 242.4 124.9)
		(end 242.7 125.2)
		(width 0.1)
		(layer "B.Cu")
		(net 1355)
	)
	(segment
		(start 250.1 127.6)
		(end 250.1 125.5)
		(width 0.1)
		(layer "B.Cu")
		(net 1355)
	)
	(segment
		(start 242.7 125.2)
		(end 249.8 125.2)
		(width 0.1)
		(layer "B.Cu")
		(net 1355)
	)
	(segment
		(start 205 135)
		(end 205.6 135.6)
		(width 0.1)
		(layer "In5.Cu")
		(net 1355)
	)
	(segment
		(start 225.398526 135.6)
		(end 239.098526 121.9)
		(width 0.1)
		(layer "In5.Cu")
		(net 1355)
	)
	(segment
		(start 241.8 121.9)
		(end 242 121.7)
		(width 0.1)
		(layer "In5.Cu")
		(net 1355)
	)
	(segment
		(start 205.6 135.6)
		(end 225.398526 135.6)
		(width 0.1)
		(layer "In5.Cu")
		(net 1355)
	)
	(segment
		(start 239.098526 121.9)
		(end 241.8 121.9)
		(width 0.1)
		(layer "In5.Cu")
		(net 1355)
	)
	(segment
		(start 204.5 136.5)
		(end 205 137)
		(width 0.256)
		(layer "F.Cu")
		(net 1356)
	)
	(via
		(at 205 137)
		(size 0.45)
		(drill 0.2)
		(layers "F.Cu" "B.Cu")
		(net 1356)
	)
	(via
		(at 242.8 122.3)
		(size 0.45)
		(drill 0.2)
		(layers "F.Cu" "B.Cu")
		(net 1356)
	)
	(segment
		(start 250.2005 125.0005)
		(end 250.5 125.3)
		(width 0.1)
		(layer "B.Cu")
		(net 1356)
	)
	(segment
		(start 242.6 122.5)
		(end 242.6 124.71)
		(width 0.1)
		(layer "B.Cu")
		(net 1356)
	)
	(segment
		(start 242.6 124.71)
		(end 242.8905 125.0005)
		(width 0.1)
		(layer "B.Cu")
		(net 1356)
	)
	(segment
		(start 242.8 122.3)
		(end 242.6 122.5)
		(width 0.1)
		(layer "B.Cu")
		(net 1356)
	)
	(segment
		(start 242.8905 125.0005)
		(end 250.2005 125.0005)
		(width 0.1)
		(layer "B.Cu")
		(net 1356)
	)
	(segment
		(start 250.5 125.3)
		(end 250.5 127.6)
		(width 0.1)
		(layer "B.Cu")
		(net 1356)
	)
	(segment
		(start 241.325 122.65)
		(end 240.551 122.65)
		(width 0.1)
		(layer "In5.Cu")
		(net 1356)
	)
	(segment
		(start 224.56421 137)
		(end 216.2 137)
		(width 0.1)
		(layer "In5.Cu")
		(net 1356)
	)
	(segment
		(start 205.375 136.625)
		(end 205 137)
		(width 0.1)
		(layer "In5.Cu")
		(net 1356)
	)
	(segment
		(start 215.825 136.625)
		(end 205.375 136.625)
		(width 0.1)
		(layer "In5.Cu")
		(net 1356)
	)
	(segment
		(start 240.201 122.3)
		(end 239.26421 122.3)
		(width 0.1)
		(layer "In5.Cu")
		(net 1356)
	)
	(segment
		(start 242.8 122.3)
		(end 241.675 122.3)
		(width 0.1)
		(layer "In5.Cu")
		(net 1356)
	)
	(segment
		(start 239.26421 122.3)
		(end 224.56421 137)
		(width 0.1)
		(layer "In5.Cu")
		(net 1356)
	)
	(segment
		(start 240.551 122.65)
		(end 240.201 122.3)
		(width 0.1)
		(layer "In5.Cu")
		(net 1356)
	)
	(segment
		(start 241.675 122.3)
		(end 241.325 122.65)
		(width 0.1)
		(layer "In5.Cu")
		(net 1356)
	)
	(segment
		(start 216.2 137)
		(end 215.825 136.625)
		(width 0.1)
		(layer "In5.Cu")
		(net 1356)
	)
	(segment
		(start 205.5 142.5)
		(end 206 143)
		(width 0.256)
		(layer "F.Cu")
		(net 1358)
	)
	(via
		(at 206 143)
		(size 0.45)
		(drill 0.2)
		(layers "F.Cu" "B.Cu")
		(net 1358)
	)
	(via
		(at 243.406233 124.593767)
		(size 0.45)
		(drill 0.2)
		(layers "F.Cu" "B.Cu")
		(net 1358)
	)
	(segment
		(start 244.2995 124.8005)
		(end 244.5 124.6)
		(width 0.1)
		(layer "B.Cu")
		(net 1358)
	)
	(segment
		(start 251.4 124.6)
		(end 252.5 125.7)
		(width 0.1)
		(layer "B.Cu")
		(net 1358)
	)
	(segment
		(start 243.612966 124.8005)
		(end 244.2995 124.8005)
		(width 0.1)
		(layer "B.Cu")
		(net 1358)
	)
	(segment
		(start 244.5 124.6)
		(end 251.4 124.6)
		(width 0.1)
		(layer "B.Cu")
		(net 1358)
	)
	(segment
		(start 252.5 125.7)
		(end 252.5 127.6)
		(width 0.1)
		(layer "B.Cu")
		(net 1358)
	)
	(segment
		(start 243.406233 124.593767)
		(end 243.612966 124.8005)
		(width 0.1)
		(layer "B.Cu")
		(net 1358)
	)
	(segment
		(start 222.275474 142.4)
		(end 206.6 142.4)
		(width 0.1)
		(layer "In5.Cu")
		(net 1358)
	)
	(segment
		(start 240.5 125.9)
		(end 238.775474 125.9)
		(width 0.1)
		(layer "In5.Cu")
		(net 1358)
	)
	(segment
		(start 243.406233 124.593767)
		(end 241.806233 124.593767)
		(width 0.1)
		(layer "In5.Cu")
		(net 1358)
	)
	(segment
		(start 241.806233 124.593767)
		(end 240.5 125.9)
		(width 0.1)
		(layer "In5.Cu")
		(net 1358)
	)
	(segment
		(start 238.775474 125.9)
		(end 222.275474 142.4)
		(width 0.1)
		(layer "In5.Cu")
		(net 1358)
	)
	(segment
		(start 206.6 142.4)
		(end 206 143)
		(width 0.1)
		(layer "In5.Cu")
		(net 1358)
	)
	(segment
		(start 208.5 142.5)
		(end 209 143)
		(width 0.256)
		(layer "F.Cu")
		(net 1359)
	)
	(via
		(at 209 143)
		(size 0.45)
		(drill 0.2)
		(layers "F.Cu" "B.Cu")
		(net 1359)
	)
	(via
		(at 243.99 124.4255)
		(size 0.45)
		(drill 0.2)
		(layers "F.Cu" "B.Cu")
		(net 1359)
	)
	(segment
		(start 243.99 124.4255)
		(end 244.1155 124.3)
		(width 0.1)
		(layer "B.Cu")
		(net 1359)
	)
	(segment
		(start 252 124.3)
		(end 253.3 125.6)
		(width 0.1)
		(layer "B.Cu")
		(net 1359)
	)
	(segment
		(start 244.1155 124.3)
		(end 252 124.3)
		(width 0.1)
		(layer "B.Cu")
		(net 1359)
	)
	(segment
		(start 253.3 125.6)
		(end 253.3 127.6)
		(width 0.1)
		(layer "B.Cu")
		(net 1359)
	)
	(segment
		(start 238.858316 126.1)
		(end 222.358316 142.6)
		(width 0.1)
		(layer "In5.Cu")
		(net 1359)
	)
	(segment
		(start 209.4 142.6)
		(end 209 143)
		(width 0.1)
		(layer "In5.Cu")
		(net 1359)
	)
	(segment
		(start 243.99 124.4255)
		(end 243.99 124.71)
		(width 0.1)
		(layer "In5.Cu")
		(net 1359)
	)
	(segment
		(start 243.7 125)
		(end 241.682842 125)
		(width 0.1)
		(layer "In5.Cu")
		(net 1359)
	)
	(segment
		(start 241.682842 125)
		(end 240.582842 126.1)
		(width 0.1)
		(layer "In5.Cu")
		(net 1359)
	)
	(segment
		(start 243.99 124.71)
		(end 243.7 125)
		(width 0.1)
		(layer "In5.Cu")
		(net 1359)
	)
	(segment
		(start 222.358316 142.6)
		(end 209.4 142.6)
		(width 0.1)
		(layer "In5.Cu")
		(net 1359)
	)
	(segment
		(start 240.582842 126.1)
		(end 238.858316 126.1)
		(width 0.1)
		(layer "In5.Cu")
		(net 1359)
	)
	(segment
		(start 207.5 143.5)
		(end 208 144)
		(width 0.256)
		(layer "F.Cu")
		(net 1360)
	)
	(via
		(at 242.99 124.09)
		(size 0.45)
		(drill 0.2)
		(layers "F.Cu" "B.Cu")
		(net 1360)
	)
	(via
		(at 208 144)
		(size 0.45)
		(drill 0.2)
		(layers "F.Cu" "B.Cu")
		(net 1360)
	)
	(segment
		(start 252.2 123.9)
		(end 243.701 123.9)
		(width 0.1)
		(layer "B.Cu")
		(net 1360)
	)
	(segment
		(start 253.7 127.6)
		(end 253.7 125.4)
		(width 0.1)
		(layer "B.Cu")
		(net 1360)
	)
	(segment
		(start 243.21952 124.0505)
		(end 243.1745 124.09552)
		(width 0.1)
		(layer "B.Cu")
		(net 1360)
	)
	(segment
		(start 243.5505 124.0505)
		(end 243.21952 124.0505)
		(width 0.1)
		(layer "B.Cu")
		(net 1360)
	)
	(segment
		(start 243.701 123.9)
		(end 243.5505 124.0505)
		(width 0.1)
		(layer "B.Cu")
		(net 1360)
	)
	(segment
		(start 253.7 125.4)
		(end 252.2 123.9)
		(width 0.1)
		(layer "B.Cu")
		(net 1360)
	)
	(segment
		(start 241.765684 125.2)
		(end 243.9 125.2)
		(width 0.1)
		(layer "In5.Cu")
		(net 1360)
	)
	(segment
		(start 238.941158 126.3)
		(end 240.665684 126.3)
		(width 0.1)
		(layer "In5.Cu")
		(net 1360)
	)
	(segment
		(start 244.2 124)
		(end 243.08 124)
		(width 0.1)
		(layer "In5.Cu")
		(net 1360)
	)
	(segment
		(start 222.441158 142.8)
		(end 238.941158 126.3)
		(width 0.1)
		(layer "In5.Cu")
		(net 1360)
	)
	(segment
		(start 208.6 143.4)
		(end 216.2 143.4)
		(width 0.1)
		(layer "In5.Cu")
		(net 1360)
	)
	(segment
		(start 208 144)
		(end 208.6 143.4)
		(width 0.1)
		(layer "In5.Cu")
		(net 1360)
	)
	(segment
		(start 244.4 124.2)
		(end 244.2 124)
		(width 0.1)
		(layer "In5.Cu")
		(net 1360)
	)
	(segment
		(start 244.4 124.7)
		(end 244.4 124.2)
		(width 0.1)
		(layer "In5.Cu")
		(net 1360)
	)
	(segment
		(start 240.665684 126.3)
		(end 241.765684 125.2)
		(width 0.1)
		(layer "In5.Cu")
		(net 1360)
	)
	(segment
		(start 243.08 124)
		(end 242.99 124.09)
		(width 0.1)
		(layer "In5.Cu")
		(net 1360)
	)
	(segment
		(start 243.9 125.2)
		(end 244.4 124.7)
		(width 0.1)
		(layer "In5.Cu")
		(net 1360)
	)
	(segment
		(start 216.8 142.8)
		(end 222.441158 142.8)
		(width 0.1)
		(layer "In5.Cu")
		(net 1360)
	)
	(segment
		(start 216.2 143.4)
		(end 216.8 142.8)
		(width 0.1)
		(layer "In5.Cu")
		(net 1360)
	)
	(segment
		(start 207.5 140.5)
		(end 208 141)
		(width 0.256)
		(layer "F.Cu")
		(net 1361)
	)
	(via
		(at 243.309412 123.562836)
		(size 0.45)
		(drill 0.2)
		(layers "F.Cu" "B.Cu")
		(net 1361)
	)
	(via
		(at 208 141)
		(size 0.45)
		(drill 0.2)
		(layers "F.Cu" "B.Cu")
		(net 1361)
	)
	(segment
		(start 254.5 124.9)
		(end 253.2 123.6)
		(width 0.1)
		(layer "B.Cu")
		(net 1361)
	)
	(segment
		(start 243.346576 123.6)
		(end 243.309412 123.562836)
		(width 0.1)
		(layer "B.Cu")
		(net 1361)
	)
	(segment
		(start 253.2 123.6)
		(end 243.346576 123.6)
		(width 0.1)
		(layer "B.Cu")
		(net 1361)
	)
	(segment
		(start 254.5 127.6)
		(end 254.5 124.9)
		(width 0.1)
		(layer "B.Cu")
		(net 1361)
	)
	(segment
		(start 239.00979 125.1)
		(end 222.70979 141.4)
		(width 0.1)
		(layer "In5.Cu")
		(net 1361)
	)
	(segment
		(start 222.70979 141.4)
		(end 208.4 141.4)
		(width 0.1)
		(layer "In5.Cu")
		(net 1361)
	)
	(segment
		(start 243.309412 123.562836)
		(end 242.437164 123.562836)
		(width 0.1)
		(layer "In5.Cu")
		(net 1361)
	)
	(segment
		(start 240.9 125.1)
		(end 239.00979 125.1)
		(width 0.1)
		(layer "In5.Cu")
		(net 1361)
	)
	(segment
		(start 242.437164 123.562836)
		(end 240.9 125.1)
		(width 0.1)
		(layer "In5.Cu")
		(net 1361)
	)
	(segment
		(start 208.4 141.4)
		(end 208 141)
		(width 0.1)
		(layer "In5.Cu")
		(net 1361)
	)
	(segment
		(start 240.7 124.6)
		(end 240.7745 124.6745)
		(width 0.1)
		(layer "F.Cu")
		(net 1362)
	)
	(segment
		(start 246 121.7)
		(end 246 121.1)
		(width 0.1)
		(layer "F.Cu")
		(net 1362)
	)
	(segment
		(start 241 120.9)
		(end 240.7 121.2)
		(width 0.1)
		(layer "F.Cu")
		(net 1362)
	)
	(segment
		(start 240.7 121.2)
		(end 240.7 124.6)
		(width 0.1)
		(layer "F.Cu")
		(net 1362)
	)
	(segment
		(start 209.5 140.5)
		(end 210 141)
		(width 0.256)
		(layer "F.Cu")
		(net 1362)
	)
	(segment
		(start 245.8 120.9)
		(end 241 120.9)
		(width 0.1)
		(layer "F.Cu")
		(net 1362)
	)
	(segment
		(start 246 121.1)
		(end 245.8 120.9)
		(width 0.1)
		(layer "F.Cu")
		(net 1362)
	)
	(via
		(at 210 141)
		(size 0.45)
		(drill 0.2)
		(layers "F.Cu" "B.Cu")
		(net 1362)
	)
	(via
		(at 240.7745 124.6745)
		(size 0.45)
		(drill 0.2)
		(layers "F.Cu" "B.Cu")
		(net 1362)
	)
	(segment
		(start 238.926948 124.9)
		(end 222.626948 141.2)
		(width 0.1)
		(layer "In5.Cu")
		(net 1362)
	)
	(segment
		(start 217.5 140.625)
		(end 210.375 140.625)
		(width 0.1)
		(layer "In5.Cu")
		(net 1362)
	)
	(segment
		(start 218.075 141.2)
		(end 217.5 140.625)
		(width 0.1)
		(layer "In5.Cu")
		(net 1362)
	)
	(segment
		(start 210.375 140.625)
		(end 210 141)
		(width 0.1)
		(layer "In5.Cu")
		(net 1362)
	)
	(segment
		(start 222.626948 141.2)
		(end 218.075 141.2)
		(width 0.1)
		(layer "In5.Cu")
		(net 1362)
	)
	(segment
		(start 240.7745 124.6745)
		(end 240.549 124.9)
		(width 0.1)
		(layer "In5.Cu")
		(net 1362)
	)
	(segment
		(start 240.549 124.9)
		(end 238.926948 124.9)
		(width 0.1)
		(layer "In5.Cu")
		(net 1362)
	)
	(segment
		(start 241.075 122.275)
		(end 240.9 122.1)
		(width 0.1)
		(layer "F.Cu")
		(net 1363)
	)
	(segment
		(start 240.9 121.3)
		(end 241.1 121.1)
		(width 0.1)
		(layer "F.Cu")
		(net 1363)
	)
	(segment
		(start 245.6 121.3)
		(end 245.6 121.7)
		(width 0.1)
		(layer "F.Cu")
		(net 1363)
	)
	(segment
		(start 240.9 122.1)
		(end 240.9 121.3)
		(width 0.1)
		(layer "F.Cu")
		(net 1363)
	)
	(segment
		(start 204.5 135.5)
		(end 205 136)
		(width 0.256)
		(layer "F.Cu")
		(net 1363)
	)
	(segment
		(start 245.4 121.1)
		(end 245.6 121.3)
		(width 0.1)
		(layer "F.Cu")
		(net 1363)
	)
	(segment
		(start 241.1 121.1)
		(end 245.4 121.1)
		(width 0.1)
		(layer "F.Cu")
		(net 1363)
	)
	(via
		(at 241.075 122.275)
		(size 0.45)
		(drill 0.2)
		(layers "F.Cu" "B.Cu")
		(net 1363)
	)
	(via
		(at 205 136)
		(size 0.45)
		(drill 0.2)
		(layers "F.Cu" "B.Cu")
		(net 1363)
	)
	(segment
		(start 241.075 122.275)
		(end 240.9 122.1)
		(width 0.1)
		(layer "In5.Cu")
		(net 1363)
	)
	(segment
		(start 205.425 136.425)
		(end 205 136)
		(width 0.1)
		(layer "In5.Cu")
		(net 1363)
	)
	(segment
		(start 239.181368 122.1)
		(end 224.481368 136.8)
		(width 0.1)
		(layer "In5.Cu")
		(net 1363)
	)
	(segment
		(start 240.9 122.1)
		(end 239.181368 122.1)
		(width 0.1)
		(layer "In5.Cu")
		(net 1363)
	)
	(segment
		(start 216.3 136.8)
		(end 215.925 136.425)
		(width 0.1)
		(layer "In5.Cu")
		(net 1363)
	)
	(segment
		(start 224.481368 136.8)
		(end 216.3 136.8)
		(width 0.1)
		(layer "In5.Cu")
		(net 1363)
	)
	(segment
		(start 215.925 136.425)
		(end 205.425 136.425)
		(width 0.1)
		(layer "In5.Cu")
		(net 1363)
	)
	(segment
		(start 208.5 134.5)
		(end 209 135)
		(width 0.256)
		(layer "F.Cu")
		(net 1364)
	)
	(segment
		(start 245.1 121.3)
		(end 245.2 121.4)
		(width 0.1)
		(layer "F.Cu")
		(net 1364)
	)
	(segment
		(start 243 121.3)
		(end 245.1 121.3)
		(width 0.1)
		(layer "F.Cu")
		(net 1364)
	)
	(segment
		(start 245.2 121.4)
		(end 245.2 121.7)
		(width 0.1)
		(layer "F.Cu")
		(net 1364)
	)
	(segment
		(start 242.8 121.5)
		(end 243 121.3)
		(width 0.1)
		(layer "F.Cu")
		(net 1364)
	)
	(via
		(at 242.8 121.5)
		(size 0.45)
		(drill 0.2)
		(layers "F.Cu" "B.Cu")
		(net 1364)
	)
	(via
		(at 209 135)
		(size 0.45)
		(drill 0.2)
		(layers "F.Cu" "B.Cu")
		(net 1364)
	)
	(segment
		(start 242.8 121.5)
		(end 242.4 121.1)
		(width 0.1)
		(layer "In5.Cu")
		(net 1364)
	)
	(segment
		(start 241 121.1)
		(end 240.6 121.5)
		(width 0.1)
		(layer "In5.Cu")
		(net 1364)
	)
	(segment
		(start 209.4 135)
		(end 209 135)
		(width 0.1)
		(layer "In5.Cu")
		(net 1364)
	)
	(segment
		(start 238.932842 121.5)
		(end 225.832842 134.6)
		(width 0.1)
		(layer "In5.Cu")
		(net 1364)
	)
	(segment
		(start 242.4 121.1)
		(end 241 121.1)
		(width 0.1)
		(layer "In5.Cu")
		(net 1364)
	)
	(segment
		(start 225.832842 134.6)
		(end 209.8 134.6)
		(width 0.1)
		(layer "In5.Cu")
		(net 1364)
	)
	(segment
		(start 240.6 121.5)
		(end 238.932842 121.5)
		(width 0.1)
		(layer "In5.Cu")
		(net 1364)
	)
	(segment
		(start 209.8 134.6)
		(end 209.4 135)
		(width 0.1)
		(layer "In5.Cu")
		(net 1364)
	)
	(segment
		(start 240 123.5)
		(end 240.2 123.3)
		(width 0.1)
		(layer "F.Cu")
		(net 1365)
	)
	(segment
		(start 239.6 120.7)
		(end 240.2 120.1)
		(width 0.1)
		(layer "F.Cu")
		(net 1365)
	)
	(segment
		(start 240.2 120.1)
		(end 247.6 120.1)
		(width 0.1)
		(layer "F.Cu")
		(net 1365)
	)
	(segment
		(start 248 120.5)
		(end 248 121.7)
		(width 0.1)
		(layer "F.Cu")
		(net 1365)
	)
	(segment
		(start 247.6 120.1)
		(end 248 120.5)
		(width 0.1)
		(layer "F.Cu")
		(net 1365)
	)
	(segment
		(start 207.5 138.5)
		(end 208 139)
		(width 0.256)
		(layer "F.Cu")
		(net 1365)
	)
	(segment
		(start 239.6 121.3)
		(end 239.6 120.7)
		(width 0.1)
		(layer "F.Cu")
		(net 1365)
	)
	(segment
		(start 240.2 123.3)
		(end 240.2 121.9)
		(width 0.1)
		(layer "F.Cu")
		(net 1365)
	)
	(segment
		(start 240.2 121.9)
		(end 239.6 121.3)
		(width 0.1)
		(layer "F.Cu")
		(net 1365)
	)
	(via
		(at 240 123.5)
		(size 0.45)
		(drill 0.2)
		(layers "F.Cu" "B.Cu")
		(net 1365)
	)
	(via
		(at 208 139)
		(size 0.45)
		(drill 0.2)
		(layers "F.Cu" "B.Cu")
		(net 1365)
	)
	(segment
		(start 239.5 123.9)
		(end 239.9 123.5)
		(width 0.1)
		(layer "In5.Cu")
		(net 1365)
	)
	(segment
		(start 208.4 138.6)
		(end 224.095578 138.6)
		(width 0.1)
		(layer "In5.Cu")
		(net 1365)
	)
	(segment
		(start 238.795578 123.9)
		(end 239.5 123.9)
		(width 0.1)
		(layer "In5.Cu")
		(net 1365)
	)
	(segment
		(start 224.095578 138.6)
		(end 238.795578 123.9)
		(width 0.1)
		(layer "In5.Cu")
		(net 1365)
	)
	(segment
		(start 208 139)
		(end 208.4 138.6)
		(width 0.1)
		(layer "In5.Cu")
		(net 1365)
	)
	(segment
		(start 239.9 123.5)
		(end 240 123.5)
		(width 0.1)
		(layer "In5.Cu")
		(net 1365)
	)
	(segment
		(start 240 121.1)
		(end 240 120.582842)
		(width 0.1)
		(layer "F.Cu")
		(net 1366)
	)
	(segment
		(start 240.282842 120.3)
		(end 247.4 120.3)
		(width 0.1)
		(layer "F.Cu")
		(net 1366)
	)
	(segment
		(start 247.6 120.5)
		(end 247.6 121.7)
		(width 0.1)
		(layer "F.Cu")
		(net 1366)
	)
	(segment
		(start 207.5 134.5)
		(end 207.987698 134.987698)
		(width 0.256)
		(layer "F.Cu")
		(net 1366)
	)
	(segment
		(start 247.4 120.3)
		(end 247.6 120.5)
		(width 0.1)
		(layer "F.Cu")
		(net 1366)
	)
	(segment
		(start 207.987698 134.987698)
		(end 207.999944 134.987698)
		(width 0.256)
		(layer "F.Cu")
		(net 1366)
	)
	(segment
		(start 240 120.582842)
		(end 240.282842 120.3)
		(width 0.1)
		(layer "F.Cu")
		(net 1366)
	)
	(via
		(at 207.999944 134.987698)
		(size 0.45)
		(drill 0.2)
		(layers "F.Cu" "B.Cu")
		(net 1366)
	)
	(via
		(at 240 121.1)
		(size 0.45)
		(drill 0.2)
		(layers "F.Cu" "B.Cu")
		(net 1366)
	)
	(segment
		(start 208.387642 134.6)
		(end 209.5 134.6)
		(width 0.1)
		(layer "In5.Cu")
		(net 1366)
	)
	(segment
		(start 209.7 134.4)
		(end 225.75 134.4)
		(width 0.1)
		(layer "In5.Cu")
		(net 1366)
	)
	(segment
		(start 239.8 121.3)
		(end 240 121.1)
		(width 0.1)
		(layer "In5.Cu")
		(net 1366)
	)
	(segment
		(start 238.85 121.3)
		(end 239.8 121.3)
		(width 0.1)
		(layer "In5.Cu")
		(net 1366)
	)
	(segment
		(start 225.75 134.4)
		(end 238.85 121.3)
		(width 0.1)
		(layer "In5.Cu")
		(net 1366)
	)
	(segment
		(start 209.5 134.6)
		(end 209.7 134.4)
		(width 0.1)
		(layer "In5.Cu")
		(net 1366)
	)
	(segment
		(start 207.999944 134.987698)
		(end 208.387642 134.6)
		(width 0.1)
		(layer "In5.Cu")
		(net 1366)
	)
	(segment
		(start 240.4 121)
		(end 240.4 126.7)
		(width 0.1)
		(layer "F.Cu")
		(net 1367)
	)
	(segment
		(start 240.9 120.5)
		(end 240.4 121)
		(width 0.1)
		(layer "F.Cu")
		(net 1367)
	)
	(segment
		(start 247 120.5)
		(end 240.9 120.5)
		(width 0.1)
		(layer "F.Cu")
		(net 1367)
	)
	(segment
		(start 247.2 121.7)
		(end 247.2 120.7)
		(width 0.1)
		(layer "F.Cu")
		(net 1367)
	)
	(segment
		(start 247.2 120.7)
		(end 247 120.5)
		(width 0.1)
		(layer "F.Cu")
		(net 1367)
	)
	(segment
		(start 208.5 143.5)
		(end 209 144)
		(width 0.256)
		(layer "F.Cu")
		(net 1367)
	)
	(via
		(at 240.4 126.7)
		(size 0.45)
		(drill 0.2)
		(layers "F.Cu" "B.Cu")
		(net 1367)
	)
	(via
		(at 209 144)
		(size 0.45)
		(drill 0.2)
		(layers "F.Cu" "B.Cu")
		(net 1367)
	)
	(segment
		(start 238.474 127.05)
		(end 222.524 143)
		(width 0.1)
		(layer "In5.Cu")
		(net 1367)
	)
	(segment
		(start 240.05 127.05)
		(end 238.474 127.05)
		(width 0.1)
		(layer "In5.Cu")
		(net 1367)
	)
	(segment
		(start 240.4 126.7)
		(end 240.05 127.05)
		(width 0.1)
		(layer "In5.Cu")
		(net 1367)
	)
	(segment
		(start 222.524 143)
		(end 216.882842 143)
		(width 0.1)
		(layer "In5.Cu")
		(net 1367)
	)
	(segment
		(start 216.882842 143)
		(end 216.282842 143.6)
		(width 0.1)
		(layer "In5.Cu")
		(net 1367)
	)
	(segment
		(start 209.4 143.6)
		(end 209 144)
		(width 0.1)
		(layer "In5.Cu")
		(net 1367)
	)
	(segment
		(start 216.282842 143.6)
		(end 209.4 143.6)
		(width 0.1)
		(layer "In5.Cu")
		(net 1367)
	)
	(segment
		(start 207.01 138.01)
		(end 206.5 137.5)
		(width 0.256)
		(layer "F.Cu")
		(net 1369)
	)
	(segment
		(start 250.025 119.85)
		(end 250 119.875)
		(width 0.1)
		(layer "F.Cu")
		(net 1369)
	)
	(segment
		(start 250 119.875)
		(end 250 121.7)
		(width 0.1)
		(layer "F.Cu")
		(net 1369)
	)
	(segment
		(start 207.01 138.06)
		(end 207.01 138.01)
		(width 0.256)
		(layer "F.Cu")
		(net 1369)
	)
	(via
		(at 207.01 138.06)
		(size 0.45)
		(drill 0.2)
		(layers "F.Cu" "B.Cu")
		(net 1369)
	)
	(via
		(at 250.025 119.85)
		(size 0.45)
		(drill 0.2)
		(layers "F.Cu" "B.Cu")
		(net 1369)
	)
	(segment
		(start 224.529894 137.6)
		(end 239.029894 123.1)
		(width 0.1)
		(layer "In5.Cu")
		(net 1369)
	)
	(segment
		(start 241.775 122.5)
		(end 242.425 122.5)
		(width 0.1)
		(layer "In5.Cu")
		(net 1369)
	)
	(segment
		(start 207.01 138.06)
		(end 207.47 137.6)
		(width 0.1)
		(layer "In5.Cu")
		(net 1369)
	)
	(segment
		(start 245.85 119.825)
		(end 250 119.825)
		(width 0.1)
		(layer "In5.Cu")
		(net 1369)
	)
	(segment
		(start 241.4 122.875)
		(end 241.775 122.5)
		(width 0.1)
		(layer "In5.Cu")
		(net 1369)
	)
	(segment
		(start 242.425 122.5)
		(end 242.625 122.7)
		(width 0.1)
		(layer "In5.Cu")
		(net 1369)
	)
	(segment
		(start 250 119.825)
		(end 250.025 119.85)
		(width 0.1)
		(layer "In5.Cu")
		(net 1369)
	)
	(segment
		(start 207.47 137.6)
		(end 224.529894 137.6)
		(width 0.1)
		(layer "In5.Cu")
		(net 1369)
	)
	(segment
		(start 239.55 123.1)
		(end 239.775 122.875)
		(width 0.1)
		(layer "In5.Cu")
		(net 1369)
	)
	(segment
		(start 242.625 122.7)
		(end 242.975 122.7)
		(width 0.1)
		(layer "In5.Cu")
		(net 1369)
	)
	(segment
		(start 242.975 122.7)
		(end 245.85 119.825)
		(width 0.1)
		(layer "In5.Cu")
		(net 1369)
	)
	(segment
		(start 239.775 122.875)
		(end 241.4 122.875)
		(width 0.1)
		(layer "In5.Cu")
		(net 1369)
	)
	(segment
		(start 239.029894 123.1)
		(end 239.55 123.1)
		(width 0.1)
		(layer "In5.Cu")
		(net 1369)
	)
	(segment
		(start 240.117158 119.9)
		(end 248.430331 119.9)
		(width 0.1)
		(layer "F.Cu")
		(net 1370)
	)
	(segment
		(start 239.4 121.5)
		(end 239.4 120.617158)
		(width 0.1)
		(layer "F.Cu")
		(net 1370)
	)
	(segment
		(start 248.430331 119.9)
		(end 249.6 121.069669)
		(width 0.1)
		(layer "F.Cu")
		(net 1370)
	)
	(segment
		(start 239.4 120.617158)
		(end 240.117158 119.9)
		(width 0.1)
		(layer "F.Cu")
		(net 1370)
	)
	(segment
		(start 239.425 122.675)
		(end 239.6 122.5)
		(width 0.1)
		(layer "F.Cu")
		(net 1370)
	)
	(segment
		(start 239.6 122.5)
		(end 239.6 121.7)
		(width 0.1)
		(layer "F.Cu")
		(net 1370)
	)
	(segment
		(start 239.6 121.7)
		(end 239.4 121.5)
		(width 0.1)
		(layer "F.Cu")
		(net 1370)
	)
	(segment
		(start 206.5 136.5)
		(end 207 137)
		(width 0.256)
		(layer "F.Cu")
		(net 1370)
	)
	(segment
		(start 249.6 121.069669)
		(end 249.6 121.7)
		(width 0.1)
		(layer "F.Cu")
		(net 1370)
	)
	(via
		(at 207 137)
		(size 0.45)
		(drill 0.2)
		(layers "F.Cu" "B.Cu")
		(net 1370)
	)
	(via
		(at 239.425 122.675)
		(size 0.45)
		(drill 0.2)
		(layers "F.Cu" "B.Cu")
		(net 1370)
	)
	(segment
		(start 207.4 137.4)
		(end 207 137)
		(width 0.1)
		(layer "In5.Cu")
		(net 1370)
	)
	(segment
		(start 238.947052 122.9)
		(end 224.447052 137.4)
		(width 0.1)
		(layer "In5.Cu")
		(net 1370)
	)
	(segment
		(start 224.447052 137.4)
		(end 207.4 137.4)
		(width 0.1)
		(layer "In5.Cu")
		(net 1370)
	)
	(segment
		(start 239.2 122.9)
		(end 238.947052 122.9)
		(width 0.1)
		(layer "In5.Cu")
		(net 1370)
	)
	(segment
		(start 239.425 122.675)
		(end 239.2 122.9)
		(width 0.1)
		(layer "In5.Cu")
		(net 1370)
	)
	(segment
		(start 209.5 144.5)
		(end 210 145)
		(width 0.256)
		(layer "F.Cu")
		(net 1371)
	)
	(segment
		(start 249.2 121.2)
		(end 249.2 121.7)
		(width 0.1)
		(layer "F.Cu")
		(net 1371)
	)
	(via
		(at 210 145)
		(size 0.45)
		(drill 0.2)
		(layers "F.Cu" "B.Cu")
		(net 1371)
	)
	(via
		(at 249.2 121.2)
		(size 0.45)
		(drill 0.2)
		(layers "F.Cu" "B.Cu")
		(net 1371)
	)
	(segment
		(start 244.875 124.775)
		(end 244.25 125.4)
		(width 0.1)
		(layer "In5.Cu")
		(net 1371)
	)
	(segment
		(start 243 125.4)
		(end 242.4 126)
		(width 0.1)
		(layer "In5.Cu")
		(net 1371)
	)
	(segment
		(start 247.925 120.75)
		(end 244.875 123.8)
		(width 0.1)
		(layer "In5.Cu")
		(net 1371)
	)
	(segment
		(start 249.2 121.2)
		(end 248.75 120.75)
		(width 0.1)
		(layer "In5.Cu")
		(net 1371)
	)
	(segment
		(start 222.689684 143.4)
		(end 217.048526 143.4)
		(width 0.1)
		(layer "In5.Cu")
		(net 1371)
	)
	(segment
		(start 238.639684 127.45)
		(end 222.689684 143.4)
		(width 0.1)
		(layer "In5.Cu")
		(net 1371)
	)
	(segment
		(start 240.532842 127.45)
		(end 238.639684 127.45)
		(width 0.1)
		(layer "In5.Cu")
		(net 1371)
	)
	(segment
		(start 241 126.982842)
		(end 240.532842 127.45)
		(width 0.1)
		(layer "In5.Cu")
		(net 1371)
	)
	(segment
		(start 241 126.531368)
		(end 241 126.982842)
		(width 0.1)
		(layer "In5.Cu")
		(net 1371)
	)
	(segment
		(start 241.531368 126)
		(end 241 126.531368)
		(width 0.1)
		(layer "In5.Cu")
		(net 1371)
	)
	(segment
		(start 242.4 126)
		(end 241.531368 126)
		(width 0.1)
		(layer "In5.Cu")
		(net 1371)
	)
	(segment
		(start 217.048526 143.4)
		(end 215.873527 144.575)
		(width 0.1)
		(layer "In5.Cu")
		(net 1371)
	)
	(segment
		(start 210.425 144.575)
		(end 210 145)
		(width 0.1)
		(layer "In5.Cu")
		(net 1371)
	)
	(segment
		(start 244.25 125.4)
		(end 243 125.4)
		(width 0.1)
		(layer "In5.Cu")
		(net 1371)
	)
	(segment
		(start 248.75 120.75)
		(end 247.925 120.75)
		(width 0.1)
		(layer "In5.Cu")
		(net 1371)
	)
	(segment
		(start 244.875 123.8)
		(end 244.875 124.775)
		(width 0.1)
		(layer "In5.Cu")
		(net 1371)
	)
	(segment
		(start 215.873527 144.575)
		(end 210.425 144.575)
		(width 0.1)
		(layer "In5.Cu")
		(net 1371)
	)
	(segment
		(start 205.5 135.5)
		(end 206 136)
		(width 0.256)
		(layer "F.Cu")
		(net 1372)
	)
	(via
		(at 246.1 148.3)
		(size 0.45)
		(drill 0.2)
		(layers "F.Cu" "B.Cu")
		(net 1372)
	)
	(via
		(at 206 136)
		(size 0.45)
		(drill 0.2)
		(layers "F.Cu" "B.Cu")
		(net 1372)
	)
	(segment
		(start 246.1 148.85)
		(end 246.1 148.3)
		(width 0.1)
		(layer "B.Cu")
		(net 1372)
	)
	(segment
		(start 215.9 143.8)
		(end 215.3 144.4)
		(width 0.1)
		(layer "In3.Cu")
		(net 1372)
	)
	(segment
		(start 208.575 140.04467)
		(end 207.930331 139.4)
		(width 0.1)
		(layer "In3.Cu")
		(net 1372)
	)
	(segment
		(start 207.130331 136.6)
		(end 207 136.6)
		(width 0.1)
		(layer "In3.Cu")
		(net 1372)
	)
	(segment
		(start 207.7 139.4)
		(end 207.4 139.1)
		(width 0.1)
		(layer "In3.Cu")
		(net 1372)
	)
	(segment
		(start 237.922052 147.5)
		(end 234.722052 144.3)
		(width 0.1)
		(layer "In3.Cu")
		(net 1372)
	)
	(segment
		(start 207.4 139.1)
		(end 207.4 136.869669)
		(width 0.1)
		(layer "In3.Cu")
		(net 1372)
	)
	(segment
		(start 227.18 144.3)
		(end 226.68 143.8)
		(width 0.1)
		(layer "In3.Cu")
		(net 1372)
	)
	(segment
		(start 207.930331 139.4)
		(end 207.7 139.4)
		(width 0.1)
		(layer "In3.Cu")
		(net 1372)
	)
	(segment
		(start 206.4 136)
		(end 206 136)
		(width 0.1)
		(layer "In3.Cu")
		(net 1372)
	)
	(segment
		(start 226.68 143.8)
		(end 215.9 143.8)
		(width 0.1)
		(layer "In3.Cu")
		(net 1372)
	)
	(segment
		(start 207.4 136.869669)
		(end 207.130331 136.6)
		(width 0.1)
		(layer "In3.Cu")
		(net 1372)
	)
	(segment
		(start 246.1 148.3)
		(end 245.3 147.5)
		(width 0.1)
		(layer "In3.Cu")
		(net 1372)
	)
	(segment
		(start 207 136.6)
		(end 206.4 136)
		(width 0.1)
		(layer "In3.Cu")
		(net 1372)
	)
	(segment
		(start 208.575 144.175)
		(end 208.575 140.04467)
		(width 0.1)
		(layer "In3.Cu")
		(net 1372)
	)
	(segment
		(start 208.8 144.4)
		(end 208.575 144.175)
		(width 0.1)
		(layer "In3.Cu")
		(net 1372)
	)
	(segment
		(start 234.722052 144.3)
		(end 227.18 144.3)
		(width 0.1)
		(layer "In3.Cu")
		(net 1372)
	)
	(segment
		(start 245.3 147.5)
		(end 237.922052 147.5)
		(width 0.1)
		(layer "In3.Cu")
		(net 1372)
	)
	(segment
		(start 215.3 144.4)
		(end 208.8 144.4)
		(width 0.1)
		(layer "In3.Cu")
		(net 1372)
	)
	(segment
		(start 208 137)
		(end 207.5 136.5)
		(width 0.256)
		(layer "F.Cu")
		(net 1373)
	)
	(via
		(at 246.5 147.25)
		(size 0.45)
		(drill 0.2)
		(layers "F.Cu" "B.Cu")
		(net 1373)
	)
	(via
		(at 208 137)
		(size 0.45)
		(drill 0.2)
		(layers "F.Cu" "B.Cu")
		(net 1373)
	)
	(segment
		(start 246.5 148.85)
		(end 246.5 147.25)
		(width 0.1)
		(layer "B.Cu")
		(net 1373)
	)
	(segment
		(start 208.4 137.4)
		(end 208 137)
		(width 0.1)
		(layer "In3.Cu")
		(net 1373)
	)
	(segment
		(start 215.3 142.6)
		(end 209.7 142.6)
		(width 0.1)
		(layer "In3.Cu")
		(net 1373)
	)
	(segment
		(start 208.4 139.213173)
		(end 208.4 137.4)
		(width 0.1)
		(layer "In3.Cu")
		(net 1373)
	)
	(segment
		(start 209.425 142.325)
		(end 209.425 139.894669)
		(width 0.1)
		(layer "In3.Cu")
		(net 1373)
	)
	(segment
		(start 227.31 143.2)
		(end 215.9 143.2)
		(width 0.1)
		(layer "In3.Cu")
		(net 1373)
	)
	(segment
		(start 238.145578 146.875)
		(end 234.950578 143.68)
		(width 0.1)
		(layer "In3.Cu")
		(net 1373)
	)
	(segment
		(start 208.786827 139.6)
		(end 208.4 139.213173)
		(width 0.1)
		(layer "In3.Cu")
		(net 1373)
	)
	(segment
		(start 234.950578 143.68)
		(end 227.79 143.68)
		(width 0.1)
		(layer "In3.Cu")
		(net 1373)
	)
	(segment
		(start 246.5 147.25)
		(end 246.1 147.25)
		(width 0.1)
		(layer "In3.Cu")
		(net 1373)
	)
	(segment
		(start 246.1 147.25)
		(end 245.725 146.875)
		(width 0.1)
		(layer "In3.Cu")
		(net 1373)
	)
	(segment
		(start 209.425 139.894669)
		(end 209.130331 139.6)
		(width 0.1)
		(layer "In3.Cu")
		(net 1373)
	)
	(segment
		(start 209.130331 139.6)
		(end 208.786827 139.6)
		(width 0.1)
		(layer "In3.Cu")
		(net 1373)
	)
	(segment
		(start 209.7 142.6)
		(end 209.425 142.325)
		(width 0.1)
		(layer "In3.Cu")
		(net 1373)
	)
	(segment
		(start 215.9 143.2)
		(end 215.3 142.6)
		(width 0.1)
		(layer "In3.Cu")
		(net 1373)
	)
	(segment
		(start 227.79 143.68)
		(end 227.31 143.2)
		(width 0.1)
		(layer "In3.Cu")
		(net 1373)
	)
	(segment
		(start 245.725 146.875)
		(end 238.145578 146.875)
		(width 0.1)
		(layer "In3.Cu")
		(net 1373)
	)
	(segment
		(start 204.5 137.5)
		(end 205 138)
		(width 0.256)
		(layer "F.Cu")
		(net 1374)
	)
	(via
		(at 205 138)
		(size 0.45)
		(drill 0.2)
		(layers "F.Cu" "B.Cu")
		(net 1374)
	)
	(via
		(at 225 145)
		(size 0.45)
		(drill 0.2)
		(layers "F.Cu" "B.Cu")
		(net 1374)
	)
	(via
		(at 247.575 147.325)
		(size 0.45)
		(drill 0.2)
		(layers "F.Cu" "B.Cu")
		(net 1374)
	)
	(segment
		(start 247.125 148.675)
		(end 247.125 147.775)
		(width 0.1)
		(layer "B.Cu")
		(net 1374)
	)
	(segment
		(start 247.3 148.85)
		(end 247.125 148.675)
		(width 0.1)
		(layer "B.Cu")
		(net 1374)
	)
	(segment
		(start 247.125 147.775)
		(end 247.575 147.325)
		(width 0.1)
		(layer "B.Cu")
		(net 1374)
	)
	(segment
		(start 242.475 150.575)
		(end 240.6 148.7)
		(width 0.1)
		(layer "In3.Cu")
		(net 1374)
	)
	(segment
		(start 237.425 148.7)
		(end 234.835 146.11)
		(width 0.1)
		(layer "In3.Cu")
		(net 1374)
	)
	(segment
		(start 246 149.5)
		(end 244.925 150.575)
		(width 0.1)
		(layer "In3.Cu")
		(net 1374)
	)
	(segment
		(start 247.575 146.975)
		(end 247.71 146.84)
		(width 0.1)
		(layer "In3.Cu")
		(net 1374)
	)
	(segment
		(start 226.11 146.11)
		(end 225 145)
		(width 0.1)
		(layer "In3.Cu")
		(net 1374)
	)
	(segment
		(start 251 149.2)
		(end 250.7 149.5)
		(width 0.1)
		(layer "In3.Cu")
		(net 1374)
	)
	(segment
		(start 247.575 147.325)
		(end 247.575 146.975)
		(width 0.1)
		(layer "In3.Cu")
		(net 1374)
	)
	(segment
		(start 247.71 146.84)
		(end 248.6 146.84)
		(width 0.1)
		(layer "In3.Cu")
		(net 1374)
	)
	(segment
		(start 250.63 148.13)
		(end 251 148.5)
		(width 0.1)
		(layer "In3.Cu")
		(net 1374)
	)
	(segment
		(start 250.7 149.5)
		(end 246 149.5)
		(width 0.1)
		(layer "In3.Cu")
		(net 1374)
	)
	(segment
		(start 240.6 148.7)
		(end 237.425 148.7)
		(width 0.1)
		(layer "In3.Cu")
		(net 1374)
	)
	(segment
		(start 248.6 146.84)
		(end 249.89 148.13)
		(width 0.1)
		(layer "In3.Cu")
		(net 1374)
	)
	(segment
		(start 251 148.5)
		(end 251 149.2)
		(width 0.1)
		(layer "In3.Cu")
		(net 1374)
	)
	(segment
		(start 234.835 146.11)
		(end 226.11 146.11)
		(width 0.1)
		(layer "In3.Cu")
		(net 1374)
	)
	(segment
		(start 249.89 148.13)
		(end 250.63 148.13)
		(width 0.1)
		(layer "In3.Cu")
		(net 1374)
	)
	(segment
		(start 244.925 150.575)
		(end 242.475 150.575)
		(width 0.1)
		(layer "In3.Cu")
		(net 1374)
	)
	(segment
		(start 205.8 145.8)
		(end 205.4 145.4)
		(width 0.1)
		(layer "In5.Cu")
		(net 1374)
	)
	(segment
		(start 224 144)
		(end 217.665684 144)
		(width 0.1)
		(layer "In5.Cu")
		(net 1374)
	)
	(segment
		(start 205.4 138.4)
		(end 205 138)
		(width 0.1)
		(layer "In5.Cu")
		(net 1374)
	)
	(segment
		(start 215.865684 145.8)
		(end 205.8 145.8)
		(width 0.1)
		(layer "In5.Cu")
		(net 1374)
	)
	(segment
		(start 205.4 145.4)
		(end 205.4 138.4)
		(width 0.1)
		(layer "In5.Cu")
		(net 1374)
	)
	(segment
		(start 225 145)
		(end 224 144)
		(width 0.1)
		(layer "In5.Cu")
		(net 1374)
	)
	(segment
		(start 217.665684 144)
		(end 215.865684 145.8)
		(width 0.1)
		(layer "In5.Cu")
		(net 1374)
	)
	(segment
		(start 206.025 140.025)
		(end 206.025 140.051391)
		(width 0.256)
		(layer "F.Cu")
		(net 1375)
	)
	(segment
		(start 205.5 139.5)
		(end 206.025 140.025)
		(width 0.256)
		(layer "F.Cu")
		(net 1375)
	)
	(via
		(at 206.025 140.051391)
		(size 0.45)
		(drill 0.2)
		(layers "F.Cu" "B.Cu")
		(net 1375)
	)
	(via
		(at 247.7 148.55)
		(size 0.45)
		(drill 0.2)
		(layers "F.Cu" "B.Cu")
		(net 1375)
	)
	(segment
		(start 247.7 148.85)
		(end 247.7 148.55)
		(width 0.1)
		(layer "B.Cu")
		(net 1375)
	)
	(segment
		(start 245.06 149.29)
		(end 246.96 149.29)
		(width 0.1)
		(layer "In3.Cu")
		(net 1375)
	)
	(segment
		(start 206.3 140.6)
		(end 207.3 140.6)
		(width 0.1)
		(layer "In3.Cu")
		(net 1375)
	)
	(segment
		(start 206.025 140.051391)
		(end 206.025 140.325)
		(width 0.1)
		(layer "In3.Cu")
		(net 1375)
	)
	(segment
		(start 226.985 145.71)
		(end 235.000684 145.71)
		(width 0.1)
		(layer "In3.Cu")
		(net 1375)
	)
	(segment
		(start 235.000684 145.71)
		(end 237.590684 148.3)
		(width 0.1)
		(layer "In3.Cu")
		(net 1375)
	)
	(segment
		(start 216.3 144.6)
		(end 225.875 144.6)
		(width 0.1)
		(layer "In3.Cu")
		(net 1375)
	)
	(segment
		(start 237.590684 148.3)
		(end 244.07 148.3)
		(width 0.1)
		(layer "In3.Cu")
		(net 1375)
	)
	(segment
		(start 207.4 140.7)
		(end 207.4 145.3)
		(width 0.1)
		(layer "In3.Cu")
		(net 1375)
	)
	(segment
		(start 225.875 144.6)
		(end 226.985 145.71)
		(width 0.1)
		(layer "In3.Cu")
		(net 1375)
	)
	(segment
		(start 215.2 145.7)
		(end 216.3 144.6)
		(width 0.1)
		(layer "In3.Cu")
		(net 1375)
	)
	(segment
		(start 207.8 145.7)
		(end 215.2 145.7)
		(width 0.1)
		(layer "In3.Cu")
		(net 1375)
	)
	(segment
		(start 244.07 148.3)
		(end 245.06 149.29)
		(width 0.1)
		(layer "In3.Cu")
		(net 1375)
	)
	(segment
		(start 207.4 145.3)
		(end 207.8 145.7)
		(width 0.1)
		(layer "In3.Cu")
		(net 1375)
	)
	(segment
		(start 206.025 140.325)
		(end 206.3 140.6)
		(width 0.1)
		(layer "In3.Cu")
		(net 1375)
	)
	(segment
		(start 246.96 149.29)
		(end 247.7 148.55)
		(width 0.1)
		(layer "In3.Cu")
		(net 1375)
	)
	(segment
		(start 207.3 140.6)
		(end 207.4 140.7)
		(width 0.1)
		(layer "In3.Cu")
		(net 1375)
	)
	(segment
		(start 208 140)
		(end 207.5 139.5)
		(width 0.256)
		(layer "F.Cu")
		(net 1376)
	)
	(via
		(at 248.12 147.4)
		(size 0.45)
		(drill 0.2)
		(layers "F.Cu" "B.Cu")
		(net 1376)
	)
	(via
		(at 208 140)
		(size 0.45)
		(drill 0.2)
		(layers "F.Cu" "B.Cu")
		(net 1376)
	)
	(segment
		(start 248.1 148.85)
		(end 248.1 147.42)
		(width 0.1)
		(layer "B.Cu")
		(net 1376)
	)
	(segment
		(start 248.1 147.42)
		(end 248.12 147.4)
		(width 0.1)
		(layer "B.Cu")
		(net 1376)
	)
	(segment
		(start 244.969669 147.7)
		(end 245.944669 148.675)
		(width 0.1)
		(layer "In3.Cu")
		(net 1376)
	)
	(segment
		(start 208.375 144.275)
		(end 208.7 144.6)
		(width 0.1)
		(layer "In3.Cu")
		(net 1376)
	)
	(segment
		(start 215.417158 144.6)
		(end 216.017158 144)
		(width 0.1)
		(layer "In3.Cu")
		(net 1376)
	)
	(segment
		(start 246.275 148.675)
		(end 247.2 147.75)
		(width 0.1)
		(layer "In3.Cu")
		(net 1376)
	)
	(segment
		(start 216.017158 144)
		(end 226.52 144)
		(width 0.1)
		(layer "In3.Cu")
		(net 1376)
	)
	(segment
		(start 237.83921 147.7)
		(end 244.969669 147.7)
		(width 0.1)
		(layer "In3.Cu")
		(net 1376)
	)
	(segment
		(start 234.64921 144.51)
		(end 237.83921 147.7)
		(width 0.1)
		(layer "In3.Cu")
		(net 1376)
	)
	(segment
		(start 245.944669 148.675)
		(end 246.275 148.675)
		(width 0.1)
		(layer "In3.Cu")
		(net 1376)
	)
	(segment
		(start 247.77 147.75)
		(end 248.12 147.4)
		(width 0.1)
		(layer "In3.Cu")
		(net 1376)
	)
	(segment
		(start 227.03 144.51)
		(end 234.64921 144.51)
		(width 0.1)
		(layer "In3.Cu")
		(net 1376)
	)
	(segment
		(start 208 140)
		(end 208.375 140.375)
		(width 0.1)
		(layer "In3.Cu")
		(net 1376)
	)
	(segment
		(start 247.2 147.75)
		(end 247.77 147.75)
		(width 0.1)
		(layer "In3.Cu")
		(net 1376)
	)
	(segment
		(start 208.375 140.375)
		(end 208.375 144.275)
		(width 0.1)
		(layer "In3.Cu")
		(net 1376)
	)
	(segment
		(start 208.7 144.6)
		(end 215.417158 144.6)
		(width 0.1)
		(layer "In3.Cu")
		(net 1376)
	)
	(segment
		(start 226.52 144)
		(end 227.03 144.51)
		(width 0.1)
		(layer "In3.Cu")
		(net 1376)
	)
	(segment
		(start 214.5 144.5)
		(end 215 145)
		(width 0.256)
		(layer "F.Cu")
		(net 1377)
	)
	(via
		(at 250.495188 148.524812)
		(size 0.45)
		(drill 0.2)
		(layers "F.Cu" "B.Cu")
		(net 1377)
	)
	(via
		(at 215 145)
		(size 0.45)
		(drill 0.2)
		(layers "F.Cu" "B.Cu")
		(net 1377)
	)
	(segment
		(start 250.5 148.85)
		(end 250.5 148.529624)
		(width 0.1)
		(layer "B.Cu")
		(net 1377)
	)
	(segment
		(start 250.5 148.529624)
		(end 250.495188 148.524812)
		(width 0.1)
		(layer "B.Cu")
		(net 1377)
	)
	(segment
		(start 215.3 145)
		(end 215 145)
		(width 0.1)
		(layer "In3.Cu")
		(net 1377)
	)
	(segment
		(start 246.365 148.875)
		(end 245.861827 148.875)
		(width 0.1)
		(layer "In3.Cu")
		(net 1377)
	)
	(segment
		(start 250.495188 148.524812)
		(end 250.27 148.75)
		(width 0.1)
		(layer "In3.Cu")
		(net 1377)
	)
	(segment
		(start 249.32 147.96)
		(end 247.28 147.96)
		(width 0.1)
		(layer "In3.Cu")
		(net 1377)
	)
	(segment
		(start 226.91 144.71)
		(end 226.4 144.2)
		(width 0.1)
		(layer "In3.Cu")
		(net 1377)
	)
	(segment
		(start 247.28 147.96)
		(end 246.365 148.875)
		(width 0.1)
		(layer "In3.Cu")
		(net 1377)
	)
	(segment
		(start 216.1 144.2)
		(end 215.3 145)
		(width 0.1)
		(layer "In3.Cu")
		(net 1377)
	)
	(segment
		(start 226.4 144.2)
		(end 216.1 144.2)
		(width 0.1)
		(layer "In3.Cu")
		(net 1377)
	)
	(segment
		(start 234.566368 144.71)
		(end 226.91 144.71)
		(width 0.1)
		(layer "In3.Cu")
		(net 1377)
	)
	(segment
		(start 237.756368 147.9)
		(end 234.566368 144.71)
		(width 0.1)
		(layer "In3.Cu")
		(net 1377)
	)
	(segment
		(start 250.11 148.75)
		(end 249.32 147.96)
		(width 0.1)
		(layer "In3.Cu")
		(net 1377)
	)
	(segment
		(start 244.886827 147.9)
		(end 237.756368 147.9)
		(width 0.1)
		(layer "In3.Cu")
		(net 1377)
	)
	(segment
		(start 245.861827 148.875)
		(end 244.886827 147.9)
		(width 0.1)
		(layer "In3.Cu")
		(net 1377)
	)
	(segment
		(start 250.27 148.75)
		(end 250.11 148.75)
		(width 0.1)
		(layer "In3.Cu")
		(net 1377)
	)
	(segment
		(start 208.5 137.5)
		(end 209 138)
		(width 0.256)
		(layer "F.Cu")
		(net 1378)
	)
	(via
		(at 252.1 147.3)
		(size 0.45)
		(drill 0.2)
		(layers "F.Cu" "B.Cu")
		(net 1378)
	)
	(via
		(at 209 138)
		(size 0.45)
		(drill 0.2)
		(layers "F.Cu" "B.Cu")
		(net 1378)
	)
	(segment
		(start 252.1 147.3)
		(end 252.1 148.85)
		(width 0.1)
		(layer "B.Cu")
		(net 1378)
	)
	(segment
		(start 239.882264 142.625)
		(end 240.107264 142.85)
		(width 0.1)
		(layer "In3.Cu")
		(net 1378)
	)
	(segment
		(start 251.8 145.1)
		(end 252.1 145.4)
		(width 0.1)
		(layer "In3.Cu")
		(net 1378)
	)
	(segment
		(start 243.175 143.022052)
		(end 243.175 143.571015)
		(width 0.1)
		(layer "In3.Cu")
		(net 1378)
	)
	(segment
		(start 226.720585 142.625)
		(end 239.882264 142.625)
		(width 0.1)
		(layer "In3.Cu")
		(net 1378)
	)
	(segment
		(start 216.082842 142.8)
		(end 226.545586 142.8)
		(width 0.1)
		(layer "In3.Cu")
		(net 1378)
	)
	(segment
		(start 226.545586 142.8)
		(end 226.720585 142.625)
		(width 0.1)
		(layer "In3.Cu")
		(net 1378)
	)
	(segment
		(start 240.107264 142.85)
		(end 243.002948 142.85)
		(width 0.1)
		(layer "In3.Cu")
		(net 1378)
	)
	(segment
		(start 245.15 144.45)
		(end 245.8 145.1)
		(width 0.1)
		(layer "In3.Cu")
		(net 1378)
	)
	(segment
		(start 214.882842 141.6)
		(end 216.082842 142.8)
		(width 0.1)
		(layer "In3.Cu")
		(net 1378)
	)
	(segment
		(start 210.130331 138.6)
		(end 210.375 138.844669)
		(width 0.1)
		(layer "In3.Cu")
		(net 1378)
	)
	(segment
		(start 209.6 138.6)
		(end 210.130331 138.6)
		(width 0.1)
		(layer "In3.Cu")
		(net 1378)
	)
	(segment
		(start 209 138)
		(end 209.6 138.6)
		(width 0.1)
		(layer "In3.Cu")
		(net 1378)
	)
	(segment
		(start 243.175 143.571015)
		(end 244.053985 144.45)
		(width 0.1)
		(layer "In3.Cu")
		(net 1378)
	)
	(segment
		(start 252.1 145.4)
		(end 252.1 147.3)
		(width 0.1)
		(layer "In3.Cu")
		(net 1378)
	)
	(segment
		(start 244.053985 144.45)
		(end 245.15 144.45)
		(width 0.1)
		(layer "In3.Cu")
		(net 1378)
	)
	(segment
		(start 210.7 141.6)
		(end 214.882842 141.6)
		(width 0.1)
		(layer "In3.Cu")
		(net 1378)
	)
	(segment
		(start 210.375 141.275)
		(end 210.7 141.6)
		(width 0.1)
		(layer "In3.Cu")
		(net 1378)
	)
	(segment
		(start 245.8 145.1)
		(end 251.8 145.1)
		(width 0.1)
		(layer "In3.Cu")
		(net 1378)
	)
	(segment
		(start 243.002948 142.85)
		(end 243.175 143.022052)
		(width 0.1)
		(layer "In3.Cu")
		(net 1378)
	)
	(segment
		(start 210.375 138.844669)
		(end 210.375 141.275)
		(width 0.1)
		(layer "In3.Cu")
		(net 1378)
	)
	(segment
		(start 209.5 142.5)
		(end 210 143)
		(width 0.256)
		(layer "F.Cu")
		(net 1379)
	)
	(via
		(at 254.5 147.7)
		(size 0.45)
		(drill 0.2)
		(layers "F.Cu" "B.Cu")
		(net 1379)
	)
	(via
		(at 210 143)
		(size 0.45)
		(drill 0.2)
		(layers "F.Cu" "B.Cu")
		(net 1379)
	)
	(segment
		(start 254.5 148.85)
		(end 254.5 147.7)
		(width 0.1)
		(layer "B.Cu")
		(net 1379)
	)
	(segment
		(start 251.725 145.675)
		(end 251.4 145.35)
		(width 0.1)
		(layer "In3.Cu")
		(net 1379)
	)
	(segment
		(start 227.09 143.4)
		(end 210.4 143.4)
		(width 0.1)
		(layer "In3.Cu")
		(net 1379)
	)
	(segment
		(start 246.875 145.625)
		(end 246.875 147.405331)
		(width 0.1)
		(layer "In3.Cu")
		(net 1379)
	)
	(segment
		(start 246.875 147.405331)
		(end 246.580331 147.7)
		(width 0.1)
		(layer "In3.Cu")
		(net 1379)
	)
	(segment
		(start 234.877736 143.89)
		(end 227.58 143.89)
		(width 0.1)
		(layer "In3.Cu")
		(net 1379)
	)
	(segment
		(start 251.4 145.35)
		(end 247.15 145.35)
		(width 0.1)
		(layer "In3.Cu")
		(net 1379)
	)
	(segment
		(start 238.062736 147.075)
		(end 234.877736 143.89)
		(width 0.1)
		(layer "In3.Cu")
		(net 1379)
	)
	(segment
		(start 210.4 143.4)
		(end 210 143)
		(width 0.1)
		(layer "In3.Cu")
		(net 1379)
	)
	(segment
		(start 251.969669 147.7)
		(end 251.725 147.455331)
		(width 0.1)
		(layer "In3.Cu")
		(net 1379)
	)
	(segment
		(start 246.25 147.7)
		(end 245.625001 147.075)
		(width 0.1)
		(layer "In3.Cu")
		(net 1379)
	)
	(segment
		(start 227.58 143.89)
		(end 227.09 143.4)
		(width 0.1)
		(layer "In3.Cu")
		(net 1379)
	)
	(segment
		(start 254.5 147.7)
		(end 251.969669 147.7)
		(width 0.1)
		(layer "In3.Cu")
		(net 1379)
	)
	(segment
		(start 251.725 147.455331)
		(end 251.725 145.675)
		(width 0.1)
		(layer "In3.Cu")
		(net 1379)
	)
	(segment
		(start 246.580331 147.7)
		(end 246.25 147.7)
		(width 0.1)
		(layer "In3.Cu")
		(net 1379)
	)
	(segment
		(start 245.625001 147.075)
		(end 238.062736 147.075)
		(width 0.1)
		(layer "In3.Cu")
		(net 1379)
	)
	(segment
		(start 247.15 145.35)
		(end 246.875 145.625)
		(width 0.1)
		(layer "In3.Cu")
		(net 1379)
	)
	(segment
		(start 245.725 143.2)
		(end 246.1 143.575)
		(width 0.1)
		(layer "F.Cu")
		(net 1380)
	)
	(segment
		(start 246.1 143.575)
		(end 246.1 144)
		(width 0.1)
		(layer "F.Cu")
		(net 1380)
	)
	(segment
		(start 205.5 137.5)
		(end 206 138)
		(width 0.256)
		(layer "F.Cu")
		(net 1380)
	)
	(via
		(at 225.625 144.975)
		(size 0.45)
		(drill 0.2)
		(layers "F.Cu" "B.Cu")
		(net 1380)
	)
	(via
		(at 206 138)
		(size 0.45)
		(drill 0.2)
		(layers "F.Cu" "B.Cu")
		(net 1380)
	)
	(via
		(at 245.725 143.2)
		(size 0.45)
		(drill 0.2)
		(layers "F.Cu" "B.Cu")
		(net 1380)
	)
	(via
		(at 244.225 149.125)
		(size 0.45)
		(drill 0.2)
		(layers "F.Cu" "B.Cu")
		(net 1380)
	)
	(segment
		(start 246.975 142.225)
		(end 246.55 142.225)
		(width 0.1)
		(layer "B.Cu")
		(net 1380)
	)
	(segment
		(start 248.125 142.375)
		(end 247.125 142.375)
		(width 0.1)
		(layer "B.Cu")
		(net 1380)
	)
	(segment
		(start 248.325 141.85)
		(end 248.275 141.9)
		(width 0.1)
		(layer "B.Cu")
		(net 1380)
	)
	(segment
		(start 248.075 141)
		(end 248.325 141.25)
		(width 0.1)
		(layer "B.Cu")
		(net 1380)
	)
	(segment
		(start 245.725 143.05)
		(end 245.725 143.2)
		(width 0.1)
		(layer "B.Cu")
		(net 1380)
	)
	(segment
		(start 247.625 141)
		(end 248.075 141)
		(width 0.1)
		(layer "B.Cu")
		(net 1380)
	)
	(segment
		(start 248.275 141.9)
		(end 248.275 142.225)
		(width 0.1)
		(layer "B.Cu")
		(net 1380)
	)
	(segment
		(start 248.275 142.225)
		(end 248.125 142.375)
		(width 0.1)
		(layer "B.Cu")
		(net 1380)
	)
	(segment
		(start 246.55 142.225)
		(end 245.725 143.05)
		(width 0.1)
		(layer "B.Cu")
		(net 1380)
	)
	(segment
		(start 247.125 142.375)
		(end 246.975 142.225)
		(width 0.1)
		(layer "B.Cu")
		(net 1380)
	)
	(segment
		(start 242.975 142.15)
		(end 243.825 141.3)
		(width 0.1)
		(layer "B.Cu")
		(net 1380)
	)
	(segment
		(start 242.975 147.875)
		(end 242.975 142.15)
		(width 0.1)
		(layer "B.Cu")
		(net 1380)
	)
	(segment
		(start 247.325 141.3)
		(end 247.625 141)
		(width 0.1)
		(layer "B.Cu")
		(net 1380)
	)
	(segment
		(start 248.325 141.25)
		(end 248.325 141.85)
		(width 0.1)
		(layer "B.Cu")
		(net 1380)
	)
	(segment
		(start 243.825 141.3)
		(end 247.325 141.3)
		(width 0.1)
		(layer "B.Cu")
		(net 1380)
	)
	(segment
		(start 244.225 149.125)
		(end 242.975 147.875)
		(width 0.1)
		(layer "B.Cu")
		(net 1380)
	)
	(segment
		(start 226.56 145.91)
		(end 225.625 144.975)
		(width 0.1)
		(layer "In3.Cu")
		(net 1380)
	)
	(segment
		(start 234.917842 145.91)
		(end 226.56 145.91)
		(width 0.1)
		(layer "In3.Cu")
		(net 1380)
	)
	(segment
		(start 243.6 148.5)
		(end 237.507842 148.5)
		(width 0.1)
		(layer "In3.Cu")
		(net 1380)
	)
	(segment
		(start 244.225 149.125)
		(end 243.6 148.5)
		(width 0.1)
		(layer "In3.Cu")
		(net 1380)
	)
	(segment
		(start 237.507842 148.5)
		(end 234.917842 145.91)
		(width 0.1)
		(layer "In3.Cu")
		(net 1380)
	)
	(segment
		(start 224.45 143.8)
		(end 217.582842 143.8)
		(width 0.1)
		(layer "In5.Cu")
		(net 1380)
	)
	(segment
		(start 205.6 145.317158)
		(end 205.6 138.4)
		(width 0.1)
		(layer "In5.Cu")
		(net 1380)
	)
	(segment
		(start 205.882842 145.6)
		(end 205.6 145.317158)
		(width 0.1)
		(layer "In5.Cu")
		(net 1380)
	)
	(segment
		(start 215.782842 145.6)
		(end 205.882842 145.6)
		(width 0.1)
		(layer "In5.Cu")
		(net 1380)
	)
	(segment
		(start 217.582842 143.8)
		(end 215.782842 145.6)
		(width 0.1)
		(layer "In5.Cu")
		(net 1380)
	)
	(segment
		(start 205.6 138.4)
		(end 206 138)
		(width 0.1)
		(layer "In5.Cu")
		(net 1380)
	)
	(segment
		(start 225.625 144.975)
		(end 224.45 143.8)
		(width 0.1)
		(layer "In5.Cu")
		(net 1380)
	)
	(segment
		(start 207.98 136.05)
		(end 207.98 135.98)
		(width 0.256)
		(layer "F.Cu")
		(net 1381)
	)
	(segment
		(start 245.3 142.85)
		(end 245.3 143.35)
		(width 0.1)
		(layer "F.Cu")
		(net 1381)
	)
	(segment
		(start 245.7 143.75)
		(end 245.7 144)
		(width 0.1)
		(layer "F.Cu")
		(net 1381)
	)
	(segment
		(start 207.98 135.98)
		(end 207.5 135.5)
		(width 0.256)
		(layer "F.Cu")
		(net 1381)
	)
	(segment
		(start 245.3 143.35)
		(end 245.7 143.75)
		(width 0.1)
		(layer "F.Cu")
		(net 1381)
	)
	(via
		(at 207.98 136.05)
		(size 0.45)
		(drill 0.2)
		(layers "F.Cu" "B.Cu")
		(net 1381)
	)
	(via
		(at 243.95 143.25)
		(size 0.45)
		(drill 0.2)
		(layers "F.Cu" "B.Cu")
		(net 1381)
	)
	(via
		(at 245.3 142.85)
		(size 0.45)
		(drill 0.2)
		(layers "F.Cu" "B.Cu")
		(net 1381)
	)
	(segment
		(start 245.3 142.85)
		(end 244.9 143.25)
		(width 0.1)
		(layer "B.Cu")
		(net 1381)
	)
	(segment
		(start 244.9 143.25)
		(end 243.95 143.25)
		(width 0.1)
		(layer "B.Cu")
		(net 1381)
	)
	(segment
		(start 209.5 137.1)
		(end 209.8 137.4)
		(width 0.1)
		(layer "In3.Cu")
		(net 1381)
	)
	(segment
		(start 216.331368 142.2)
		(end 226.297057 142.2)
		(width 0.1)
		(layer "In3.Cu")
		(net 1381)
	)
	(segment
		(start 209.5 136.9)
		(end 209.5 137.1)
		(width 0.1)
		(layer "In3.Cu")
		(net 1381)
	)
	(segment
		(start 240.35579 142.25)
		(end 243.251474 142.25)
		(width 0.1)
		(layer "In3.Cu")
		(net 1381)
	)
	(segment
		(start 211.625 139.721016)
		(end 211.625 140.225)
		(width 0.1)
		(layer "In3.Cu")
		(net 1381)
	)
	(segment
		(start 209.8 137.4)
		(end 210.9 137.4)
		(width 0.1)
		(layer "In3.Cu")
		(net 1381)
	)
	(segment
		(start 207.98 136.05)
		(end 208.53 136.6)
		(width 0.1)
		(layer "In3.Cu")
		(net 1381)
	)
	(segment
		(start 240.10579 142)
		(end 240.35579 142.25)
		(width 0.1)
		(layer "In3.Cu")
		(net 1381)
	)
	(segment
		(start 210.9 137.4)
		(end 211.1 137.6)
		(width 0.1)
		(layer "In3.Cu")
		(net 1381)
	)
	(segment
		(start 226.297057 142.2)
		(end 226.497056 142)
		(width 0.1)
		(layer "In3.Cu")
		(net 1381)
	)
	(segment
		(start 211.1 137.6)
		(end 211.1 139.196016)
		(width 0.1)
		(layer "In3.Cu")
		(net 1381)
	)
	(segment
		(start 208.53 136.6)
		(end 209.2 136.6)
		(width 0.1)
		(layer "In3.Cu")
		(net 1381)
	)
	(segment
		(start 209.2 136.6)
		(end 209.5 136.9)
		(width 0.1)
		(layer "In3.Cu")
		(net 1381)
	)
	(segment
		(start 214.531368 140.4)
		(end 216.331368 142.2)
		(width 0.1)
		(layer "In3.Cu")
		(net 1381)
	)
	(segment
		(start 243.95 142.948526)
		(end 243.95 143.25)
		(width 0.1)
		(layer "In3.Cu")
		(net 1381)
	)
	(segment
		(start 211.1 139.196016)
		(end 211.625 139.721016)
		(width 0.1)
		(layer "In3.Cu")
		(net 1381)
	)
	(segment
		(start 211.8 140.4)
		(end 214.531368 140.4)
		(width 0.1)
		(layer "In3.Cu")
		(net 1381)
	)
	(segment
		(start 243.251474 142.25)
		(end 243.95 142.948526)
		(width 0.1)
		(layer "In3.Cu")
		(net 1381)
	)
	(segment
		(start 226.497056 142)
		(end 240.10579 142)
		(width 0.1)
		(layer "In3.Cu")
		(net 1381)
	)
	(segment
		(start 211.625 140.225)
		(end 211.8 140.4)
		(width 0.1)
		(layer "In3.Cu")
		(net 1381)
	)
	(segment
		(start 244.7 144.6)
		(end 245.3 144)
		(width 0.1)
		(layer "F.Cu")
		(net 1382)
	)
	(segment
		(start 207 136)
		(end 206.5 135.5)
		(width 0.256)
		(layer "F.Cu")
		(net 1382)
	)
	(segment
		(start 244.7 144.8245)
		(end 244.7 144.6)
		(width 0.1)
		(layer "F.Cu")
		(net 1382)
	)
	(via
		(at 244.7 144.8245)
		(size 0.45)
		(drill 0.2)
		(layers "F.Cu" "B.Cu")
		(net 1382)
	)
	(via
		(at 207 136)
		(size 0.45)
		(drill 0.2)
		(layers "F.Cu" "B.Cu")
		(net 1382)
	)
	(segment
		(start 208.1 136.5)
		(end 208.625 137.025)
		(width 0.1)
		(layer "In3.Cu")
		(net 1382)
	)
	(segment
		(start 209.4 139.4)
		(end 209.625 139.625)
		(width 0.1)
		(layer "In3.Cu")
		(net 1382)
	)
	(segment
		(start 215.4 142.4)
		(end 216 143)
		(width 0.1)
		(layer "In3.Cu")
		(net 1382)
	)
	(segment
		(start 238.228421 146.675)
		(end 242.85 146.675)
		(width 0.1)
		(layer "In3.Cu")
		(net 1382)
	)
	(segment
		(start 244.7 144.825)
		(end 244.7 144.8245)
		(width 0.1)
		(layer "In3.Cu")
		(net 1382)
	)
	(segment
		(start 207.5 136.5)
		(end 208.1 136.5)
		(width 0.1)
		(layer "In3.Cu")
		(net 1382)
	)
	(segment
		(start 209.625 142.155331)
		(end 209.869669 142.4)
		(width 0.1)
		(layer "In3.Cu")
		(net 1382)
	)
	(segment
		(start 227.92 143.48)
		(end 235.033421 143.48)
		(width 0.1)
		(layer "In3.Cu")
		(net 1382)
	)
	(segment
		(start 208.869669 139.4)
		(end 209.4 139.4)
		(width 0.1)
		(layer "In3.Cu")
		(net 1382)
	)
	(segment
		(start 227.44 143)
		(end 227.92 143.48)
		(width 0.1)
		(layer "In3.Cu")
		(net 1382)
	)
	(segment
		(start 216 143)
		(end 227.44 143)
		(width 0.1)
		(layer "In3.Cu")
		(net 1382)
	)
	(segment
		(start 242.85 146.675)
		(end 244.7 144.825)
		(width 0.1)
		(layer "In3.Cu")
		(net 1382)
	)
	(segment
		(start 235.033421 143.48)
		(end 238.228421 146.675)
		(width 0.1)
		(layer "In3.Cu")
		(net 1382)
	)
	(segment
		(start 208.625 137.025)
		(end 208.625 139.155331)
		(width 0.1)
		(layer "In3.Cu")
		(net 1382)
	)
	(segment
		(start 209.869669 142.4)
		(end 215.4 142.4)
		(width 0.1)
		(layer "In3.Cu")
		(net 1382)
	)
	(segment
		(start 208.625 139.155331)
		(end 208.869669 139.4)
		(width 0.1)
		(layer "In3.Cu")
		(net 1382)
	)
	(segment
		(start 207 136)
		(end 207.5 136.5)
		(width 0.1)
		(layer "In3.Cu")
		(net 1382)
	)
	(segment
		(start 209.625 139.625)
		(end 209.625 142.155331)
		(width 0.1)
		(layer "In3.Cu")
		(net 1382)
	)
	(segment
		(start 210.999974 132.999974)
		(end 211.012273 132.999974)
		(width 0.256)
		(layer "F.Cu")
		(net 1383)
	)
	(segment
		(start 248.5 144)
		(end 248.5 143.25)
		(width 0.1)
		(layer "F.Cu")
		(net 1383)
	)
	(segment
		(start 210.5 132.5)
		(end 210.999974 132.999974)
		(width 0.256)
		(layer "F.Cu")
		(net 1383)
	)
	(via
		(at 216.4 141)
		(size 0.45)
		(drill 0.2)
		(layers "F.Cu" "B.Cu")
		(net 1383)
	)
	(via
		(at 248.5 143.25)
		(size 0.45)
		(drill 0.2)
		(layers "F.Cu" "B.Cu")
		(net 1383)
	)
	(via
		(at 211.012273 132.999974)
		(size 0.45)
		(drill 0.2)
		(layers "F.Cu" "B.Cu")
		(net 1383)
	)
	(segment
		(start 211.012273 132.999974)
		(end 211.612299 133.6)
		(width 0.1)
		(layer "B.Cu")
		(net 1383)
	)
	(segment
		(start 216.4 134.2)
		(end 216.4 141)
		(width 0.1)
		(layer "B.Cu")
		(net 1383)
	)
	(segment
		(start 211.612299 133.6)
		(end 215.8 133.6)
		(width 0.1)
		(layer "B.Cu")
		(net 1383)
	)
	(segment
		(start 215.8 133.6)
		(end 216.4 134.2)
		(width 0.1)
		(layer "B.Cu")
		(net 1383)
	)
	(segment
		(start 248.1 144.3)
		(end 248.5 143.9)
		(width 0.1)
		(layer "In3.Cu")
		(net 1383)
	)
	(segment
		(start 226.248527 141.4)
		(end 240.354316 141.4)
		(width 0.1)
		(layer "In3.Cu")
		(net 1383)
	)
	(segment
		(start 240.604316 141.65)
		(end 243.5 141.65)
		(width 0.1)
		(layer "In3.Cu")
		(net 1383)
	)
	(segment
		(start 248.5 143.9)
		(end 248.5 143.25)
		(width 0.1)
		(layer "In3.Cu")
		(net 1383)
	)
	(segment
		(start 216.4 141)
		(end 217 141.6)
		(width 0.1)
		(layer "In3.Cu")
		(net 1383)
	)
	(segment
		(start 243.5 141.65)
		(end 246.15 144.3)
		(width 0.1)
		(layer "In3.Cu")
		(net 1383)
	)
	(segment
		(start 246.15 144.3)
		(end 248.1 144.3)
		(width 0.1)
		(layer "In3.Cu")
		(net 1383)
	)
	(segment
		(start 226.048528 141.6)
		(end 226.248527 141.4)
		(width 0.1)
		(layer "In3.Cu")
		(net 1383)
	)
	(segment
		(start 217 141.6)
		(end 226.048528 141.6)
		(width 0.1)
		(layer "In3.Cu")
		(net 1383)
	)
	(segment
		(start 240.354316 141.4)
		(end 240.604316 141.65)
		(width 0.1)
		(layer "In3.Cu")
		(net 1383)
	)
	(segment
		(start 217.216 133.716)
		(end 217.216 133.7745)
		(width 0.1)
		(layer "F.Cu")
		(net 1384)
	)
	(segment
		(start 215.8 132)
		(end 214 132)
		(width 0.182)
		(layer "F.Cu")
		(net 1384)
	)
	(segment
		(start 214 132)
		(end 213.5 131.5)
		(width 0.182)
		(layer "F.Cu")
		(net 1384)
	)
	(segment
		(start 217.216 133.416)
		(end 215.8 132)
		(width 0.182)
		(layer "F.Cu")
		(net 1384)
	)
	(segment
		(start 217.216 133.716)
		(end 217.216 133.416)
		(width 0.182)
		(layer "F.Cu")
		(net 1384)
	)
	(segment
		(start 248.1 144)
		(end 248.1 142.85)
		(width 0.1)
		(layer "F.Cu")
		(net 1384)
	)
	(via
		(at 248.1 142.85)
		(size 0.45)
		(drill 0.2)
		(layers "F.Cu" "B.Cu")
		(net 1384)
	)
	(via
		(at 217.216 133.7745)
		(size 0.45)
		(drill 0.2)
		(layers "F.Cu" "B.Cu")
		(net 1384)
	)
	(via
		(at 217.2 141)
		(size 0.45)
		(drill 0.2)
		(layers "F.Cu" "B.Cu")
		(net 1384)
	)
	(segment
		(start 217.216 140.984)
		(end 217.216 133.716)
		(width 0.182)
		(layer "B.Cu")
		(net 1384)
	)
	(segment
		(start 244.895 142.475)
		(end 245.65 142.475)
		(width 0.1)
		(layer "In3.Cu")
		(net 1384)
	)
	(segment
		(start 243.87 141.45)
		(end 244.895 142.475)
		(width 0.1)
		(layer "In3.Cu")
		(net 1384)
	)
	(segment
		(start 226.165684 141.2)
		(end 240.437158 141.2)
		(width 0.1)
		(layer "In3.Cu")
		(net 1384)
	)
	(segment
		(start 217.2 141)
		(end 217.6 141.4)
		(width 0.1)
		(layer "In3.Cu")
		(net 1384)
	)
	(segment
		(start 246.275 143.975)
		(end 247.925 143.975)
		(width 0.1)
		(layer "In3.Cu")
		(net 1384)
	)
	(segment
		(start 225.965685 141.4)
		(end 226.165684 141.2)
		(width 0.1)
		(layer "In3.Cu")
		(net 1384)
	)
	(segment
		(start 248.1 143.8)
		(end 248.1 142.85)
		(width 0.1)
		(layer "In3.Cu")
		(net 1384)
	)
	(segment
		(start 240.687158 141.45)
		(end 243.87 141.45)
		(width 0.1)
		(layer "In3.Cu")
		(net 1384)
	)
	(segment
		(start 245.65 142.475)
		(end 246.1 142.925)
		(width 0.1)
		(layer "In3.Cu")
		(net 1384)
	)
	(segment
		(start 247.925 143.975)
		(end 248.1 143.8)
		(width 0.1)
		(layer "In3.Cu")
		(net 1384)
	)
	(segment
		(start 240.437158 141.2)
		(end 240.687158 141.45)
		(width 0.1)
		(layer "In3.Cu")
		(net 1384)
	)
	(segment
		(start 246.1 142.925)
		(end 246.1 143.8)
		(width 0.1)
		(layer "In3.Cu")
		(net 1384)
	)
	(segment
		(start 217.6 141.4)
		(end 225.965685 141.4)
		(width 0.1)
		(layer "In3.Cu")
		(net 1384)
	)
	(segment
		(start 246.1 143.8)
		(end 246.275 143.975)
		(width 0.1)
		(layer "In3.Cu")
		(net 1384)
	)
	(segment
		(start 250.5 144)
		(end 250.5 143.45)
		(width 0.1)
		(layer "F.Cu")
		(net 1385)
	)
	(segment
		(start 204.5 130.5)
		(end 205 131)
		(width 0.256)
		(layer "F.Cu")
		(net 1385)
	)
	(segment
		(start 250.5 143.45)
		(end 250.475 143.425)
		(width 0.1)
		(layer "F.Cu")
		(net 1385)
	)
	(via
		(at 250.475 143.425)
		(size 0.45)
		(drill 0.2)
		(layers "F.Cu" "B.Cu")
		(net 1385)
	)
	(via
		(at 205 131)
		(size 0.45)
		(drill 0.2)
		(layers "F.Cu" "B.Cu")
		(net 1385)
	)
	(segment
		(start 209.282842 135.4)
		(end 204.7 135.4)
		(width 0.1)
		(layer "In3.Cu")
		(net 1385)
	)
	(segment
		(start 214.13 139.43)
		(end 214.127053 139.43)
		(width 0.1)
		(layer "In3.Cu")
		(net 1385)
	)
	(segment
		(start 211.6 136.5)
		(end 211.5 136.4)
		(width 0.1)
		(layer "In3.Cu")
		(net 1385)
	)
	(segment
		(start 249.65 144.5)
		(end 246.067158 144.5)
		(width 0.1)
		(layer "In3.Cu")
		(net 1385)
	)
	(segment
		(start 211.5 136.4)
		(end 209.8 136.4)
		(width 0.1)
		(layer "In3.Cu")
		(net 1385)
	)
	(segment
		(start 226.131371 141.8)
		(end 216.5 141.8)
		(width 0.1)
		(layer "In3.Cu")
		(net 1385)
	)
	(segment
		(start 214.127053 139.43)
		(end 214.122052 139.425)
		(width 0.1)
		(layer "In3.Cu")
		(net 1385)
	)
	(segment
		(start 250.475 143.425)
		(end 250.475 143.675)
		(width 0.1)
		(layer "In3.Cu")
		(net 1385)
	)
	(segment
		(start 246.067158 144.5)
		(end 243.417158 141.85)
		(width 0.1)
		(layer "In3.Cu")
		(net 1385)
	)
	(segment
		(start 240.271474 141.6)
		(end 226.33137 141.6)
		(width 0.1)
		(layer "In3.Cu")
		(net 1385)
	)
	(segment
		(start 204.7 135.4)
		(end 204.58 135.28)
		(width 0.1)
		(layer "In3.Cu")
		(net 1385)
	)
	(segment
		(start 204.58 131.42)
		(end 205 131)
		(width 0.1)
		(layer "In3.Cu")
		(net 1385)
	)
	(segment
		(start 216.5 141.8)
		(end 214.13 139.43)
		(width 0.1)
		(layer "In3.Cu")
		(net 1385)
	)
	(segment
		(start 214.122052 139.425)
		(end 211.894669 139.425)
		(width 0.1)
		(layer "In3.Cu")
		(net 1385)
	)
	(segment
		(start 211.894669 139.425)
		(end 211.6 139.130331)
		(width 0.1)
		(layer "In3.Cu")
		(net 1385)
	)
	(segment
		(start 211.6 139.130331)
		(end 211.6 136.5)
		(width 0.1)
		(layer "In3.Cu")
		(net 1385)
	)
	(segment
		(start 250.475 143.675)
		(end 249.65 144.5)
		(width 0.1)
		(layer "In3.Cu")
		(net 1385)
	)
	(segment
		(start 226.33137 141.6)
		(end 226.131371 141.8)
		(width 0.1)
		(layer "In3.Cu")
		(net 1385)
	)
	(segment
		(start 243.417158 141.85)
		(end 240.521474 141.85)
		(width 0.1)
		(layer "In3.Cu")
		(net 1385)
	)
	(segment
		(start 209.6 135.717157)
		(end 209.282842 135.4)
		(width 0.1)
		(layer "In3.Cu")
		(net 1385)
	)
	(segment
		(start 209.6 136.2)
		(end 209.6 135.717157)
		(width 0.1)
		(layer "In3.Cu")
		(net 1385)
	)
	(segment
		(start 204.58 135.28)
		(end 204.58 131.42)
		(width 0.1)
		(layer "In3.Cu")
		(net 1385)
	)
	(segment
		(start 209.8 136.4)
		(end 209.6 136.2)
		(width 0.1)
		(layer "In3.Cu")
		(net 1385)
	)
	(segment
		(start 240.521474 141.85)
		(end 240.271474 141.6)
		(width 0.1)
		(layer "In3.Cu")
		(net 1385)
	)
	(segment
		(start 250.1 144)
		(end 250.1 142.85)
		(width 0.1)
		(layer "F.Cu")
		(net 1386)
	)
	(segment
		(start 204.5 129.5)
		(end 205 129)
		(width 0.256)
		(layer "F.Cu")
		(net 1386)
	)
	(via
		(at 250.1 142.85)
		(size 0.45)
		(drill 0.2)
		(layers "F.Cu" "B.Cu")
		(net 1386)
	)
	(via
		(at 205 129)
		(size 0.45)
		(drill 0.2)
		(layers "F.Cu" "B.Cu")
		(net 1386)
	)
	(segment
		(start 245.984316 144.7)
		(end 249.75 144.7)
		(width 0.1)
		(layer "In3.Cu")
		(net 1386)
	)
	(segment
		(start 204.4 135.382842)
		(end 204.4 135.4)
		(width 0.1)
		(layer "In3.Cu")
		(net 1386)
	)
	(segment
		(start 226.214214 142)
		(end 226.414213 141.8)
		(width 0.1)
		(layer "In3.Cu")
		(net 1386)
	)
	(segment
		(start 211.3 136.6)
		(end 211.4 136.7)
		(width 0.1)
		(layer "In3.Cu")
		(net 1386)
	)
	(segment
		(start 240.188632 141.8)
		(end 240.438632 142.05)
		(width 0.1)
		(layer "In3.Cu")
		(net 1386)
	)
	(segment
		(start 211.4 139.213174)
		(end 211.811827 139.625)
		(width 0.1)
		(layer "In3.Cu")
		(net 1386)
	)
	(segment
		(start 204.38 131.337158)
		(end 204.38 135.362843)
		(width 0.1)
		(layer "In3.Cu")
		(net 1386)
	)
	(segment
		(start 240.438632 142.05)
		(end 243.334316 142.05)
		(width 0.1)
		(layer "In3.Cu")
		(net 1386)
	)
	(segment
		(start 204.4 129.6)
		(end 204.4 131.317157)
		(width 0.1)
		(layer "In3.Cu")
		(net 1386)
	)
	(segment
		(start 211.4 136.7)
		(end 211.4 139.213174)
		(width 0.1)
		(layer "In3.Cu")
		(net 1386)
	)
	(segment
		(start 209.6 136.6)
		(end 211.3 136.6)
		(width 0.1)
		(layer "In3.Cu")
		(net 1386)
	)
	(segment
		(start 214.03921 139.625)
		(end 216.41421 142)
		(width 0.1)
		(layer "In3.Cu")
		(net 1386)
	)
	(segment
		(start 216.41421 142)
		(end 226.214214 142)
		(width 0.1)
		(layer "In3.Cu")
		(net 1386)
	)
	(segment
		(start 226.414213 141.8)
		(end 240.188632 141.8)
		(width 0.1)
		(layer "In3.Cu")
		(net 1386)
	)
	(segment
		(start 204.6 135.6)
		(end 209.2 135.6)
		(width 0.1)
		(layer "In3.Cu")
		(net 1386)
	)
	(segment
		(start 250.9 143.275)
		(end 250.475 142.85)
		(width 0.1)
		(layer "In3.Cu")
		(net 1386)
	)
	(segment
		(start 211.811827 139.625)
		(end 214.03921 139.625)
		(width 0.1)
		(layer "In3.Cu")
		(net 1386)
	)
	(segment
		(start 209.4 136.4)
		(end 209.6 136.6)
		(width 0.1)
		(layer "In3.Cu")
		(net 1386)
	)
	(segment
		(start 249.75 144.7)
		(end 250.9 143.55)
		(width 0.1)
		(layer "In3.Cu")
		(net 1386)
	)
	(segment
		(start 250.475 142.85)
		(end 250.1 142.85)
		(width 0.1)
		(layer "In3.Cu")
		(net 1386)
	)
	(segment
		(start 204.38 135.362843)
		(end 204.4 135.382842)
		(width 0.1)
		(layer "In3.Cu")
		(net 1386)
	)
	(segment
		(start 204.4 135.4)
		(end 204.6 135.6)
		(width 0.1)
		(layer "In3.Cu")
		(net 1386)
	)
	(segment
		(start 205 129)
		(end 204.4 129.6)
		(width 0.1)
		(layer "In3.Cu")
		(net 1386)
	)
	(segment
		(start 250.9 143.55)
		(end 250.9 143.275)
		(width 0.1)
		(layer "In3.Cu")
		(net 1386)
	)
	(segment
		(start 204.4 131.317157)
		(end 204.38 131.337158)
		(width 0.1)
		(layer "In3.Cu")
		(net 1386)
	)
	(segment
		(start 243.334316 142.05)
		(end 245.984316 144.7)
		(width 0.1)
		(layer "In3.Cu")
		(net 1386)
	)
	(segment
		(start 209.2 135.6)
		(end 209.4 135.8)
		(width 0.1)
		(layer "In3.Cu")
		(net 1386)
	)
	(segment
		(start 209.4 135.8)
		(end 209.4 136.4)
		(width 0.1)
		(layer "In3.Cu")
		(net 1386)
	)
	(segment
		(start 231.7 139.625)
		(end 231.375 139.625)
		(width 0.1)
		(layer "F.Cu")
		(net 1387)
	)
	(segment
		(start 229.925 144.75)
		(end 233.425 141.25)
		(width 0.1)
		(layer "F.Cu")
		(net 1387)
	)
	(segment
		(start 227 144.55)
		(end 226.78 144.77)
		(width 0.1)
		(layer "F.Cu")
		(net 1387)
	)
	(segment
		(start 228.45 146.1)
		(end 228.45 145.03)
		(width 0.1)
		(layer "F.Cu")
		(net 1387)
	)
	(segment
		(start 253.7 144)
		(end 253.7 143.25)
		(width 0.1)
		(layer "F.Cu")
		(net 1387)
	)
	(segment
		(start 233.425 139.575)
		(end 233.325 139.475)
		(width 0.1)
		(layer "F.Cu")
		(net 1387)
	)
	(segment
		(start 233.425 141.25)
		(end 233.425 139.575)
		(width 0.1)
		(layer "F.Cu")
		(net 1387)
	)
	(segment
		(start 228.45 145.03)
		(end 228.73 144.75)
		(width 0.1)
		(layer "F.Cu")
		(net 1387)
	)
	(segment
		(start 226.78 144.77)
		(end 226.78 146.24)
		(width 0.1)
		(layer "F.Cu")
		(net 1387)
	)
	(segment
		(start 231.85 139.475)
		(end 231.7 139.625)
		(width 0.1)
		(layer "F.Cu")
		(net 1387)
	)
	(segment
		(start 228.73 144.75)
		(end 229.925 144.75)
		(width 0.1)
		(layer "F.Cu")
		(net 1387)
	)
	(segment
		(start 227 142.225)
		(end 227 144.55)
		(width 0.1)
		(layer "F.Cu")
		(net 1387)
	)
	(segment
		(start 226.78 146.24)
		(end 226.99 146.45)
		(width 0.1)
		(layer "F.Cu")
		(net 1387)
	)
	(segment
		(start 233.325 139.475)
		(end 231.85 139.475)
		(width 0.1)
		(layer "F.Cu")
		(net 1387)
	)
	(segment
		(start 228.1 146.45)
		(end 228.45 146.1)
		(width 0.1)
		(layer "F.Cu")
		(net 1387)
	)
	(segment
		(start 226.99 146.45)
		(end 228.1 146.45)
		(width 0.1)
		(layer "F.Cu")
		(net 1387)
	)
	(via
		(at 178.01 180.73)
		(size 0.45)
		(drill 0.2)
		(layers "F.Cu" "B.Cu")
		(net 1387)
	)
	(via
		(at 253.7 143.25)
		(size 0.45)
		(drill 0.2)
		(layers "F.Cu" "B.Cu")
		(net 1387)
	)
	(via
		(at 231.375 139.625)
		(size 0.45)
		(drill 0.2)
		(layers "F.Cu" "B.Cu")
		(net 1387)
	)
	(segment
		(start 176.9 176.2)
		(end 175.815 176.2)
		(width 0.1)
		(layer "B.Cu")
		(net 1387)
	)
	(segment
		(start 178.01 177.31)
		(end 176.9 176.2)
		(width 0.1)
		(layer "B.Cu")
		(net 1387)
	)
	(segment
		(start 178.01 180.73)
		(end 178.01 177.31)
		(width 0.1)
		(layer "B.Cu")
		(net 1387)
	)
	(segment
		(start 241.975 143.805)
		(end 241.975 137.295)
		(width 0.1)
		(layer "In7.Cu")
		(net 1387)
	)
	(segment
		(start 221.5 154.7)
		(end 222.8 154.7)
		(width 0.1)
		(layer "In7.Cu")
		(net 1387)
	)
	(segment
		(start 224.9 156.8)
		(end 224.9 173.66)
		(width 0.1)
		(layer "In7.Cu")
		(net 1387)
	)
	(segment
		(start 255.15 148.5)
		(end 252.619669 148.5)
		(width 0.1)
		(layer "In7.Cu")
		(net 1387)
	)
	(segment
		(start 224.9 173.66)
		(end 218.85 179.71)
		(width 0.1)
		(layer "In7.Cu")
		(net 1387)
	)
	(segment
		(start 235.2 150.8)
		(end 233.3 152.7)
		(width 0.1)
		(layer "In7.Cu")
		(net 1387)
	)
	(segment
		(start 243.88 145.72)
		(end 241.97 143.81)
		(width 0.1)
		(layer "In7.Cu")
		(net 1387)
	)
	(segment
		(start 236.65 147.45)
		(end 235.2 148.9)
		(width 0.1)
		(layer "In7.Cu")
		(net 1387)
	)
	(segment
		(start 197.29 179.71)
		(end 196.27 180.73)
		(width 0.1)
		(layer "In7.Cu")
		(net 1387)
	)
	(segment
		(start 220.9 154.1)
		(end 221.5 154.7)
		(width 0.1)
		(layer "In7.Cu")
		(net 1387)
	)
	(segment
		(start 254.125 143.475)
		(end 255.4 144.75)
		(width 0.1)
		(layer "In7.Cu")
		(net 1387)
	)
	(segment
		(start 236.405684 133.54)
		(end 235.58 134.365684)
		(width 0.1)
		(layer "In7.Cu")
		(net 1387)
	)
	(segment
		(start 231.375 139.625)
		(end 236.65 144.9)
		(width 0.1)
		(layer "In7.Cu")
		(net 1387)
	)
	(segment
		(start 255.4 148.25)
		(end 255.15 148.5)
		(width 0.1)
		(layer "In7.Cu")
		(net 1387)
	)
	(segment
		(start 253.7 143.25)
		(end 253.925 143.475)
		(width 0.1)
		(layer "In7.Cu")
		(net 1387)
	)
	(segment
		(start 246.3 145.22)
		(end 245.8 145.72)
		(width 0.1)
		(layer "In7.Cu")
		(net 1387)
	)
	(segment
		(start 196.27 180.73)
		(end 178.01 180.73)
		(width 0.1)
		(layer "In7.Cu")
		(net 1387)
	)
	(segment
		(start 252.619669 148.5)
		(end 249.339669 145.22)
		(width 0.1)
		(layer "In7.Cu")
		(net 1387)
	)
	(segment
		(start 227.1 150.5)
		(end 222.3 150.5)
		(width 0.1)
		(layer "In7.Cu")
		(net 1387)
	)
	(segment
		(start 222.3 150.5)
		(end 220.9 151.9)
		(width 0.1)
		(layer "In7.Cu")
		(net 1387)
	)
	(segment
		(start 234.175707 139.625)
		(end 231.375 139.625)
		(width 0.1)
		(layer "In7.Cu")
		(net 1387)
	)
	(segment
		(start 235.2 148.9)
		(end 235.2 150.8)
		(width 0.1)
		(layer "In7.Cu")
		(net 1387)
	)
	(segment
		(start 235.58 138.220707)
		(end 234.175707 139.625)
		(width 0.1)
		(layer "In7.Cu")
		(net 1387)
	)
	(segment
		(start 241.97 143.81)
		(end 241.975 143.805)
		(width 0.1)
		(layer "In7.Cu")
		(net 1387)
	)
	(segment
		(start 253.925 143.475)
		(end 254.125 143.475)
		(width 0.1)
		(layer "In7.Cu")
		(net 1387)
	)
	(segment
		(start 235.58 134.365684)
		(end 235.58 138.220707)
		(width 0.1)
		(layer "In7.Cu")
		(net 1387)
	)
	(segment
		(start 222.8 154.7)
		(end 224.9 156.8)
		(width 0.1)
		(layer "In7.Cu")
		(net 1387)
	)
	(segment
		(start 236.65 144.9)
		(end 236.65 147.45)
		(width 0.1)
		(layer "In7.Cu")
		(net 1387)
	)
	(segment
		(start 218.85 179.71)
		(end 197.29 179.71)
		(width 0.1)
		(layer "In7.Cu")
		(net 1387)
	)
	(segment
		(start 241.975 137.295)
		(end 238.22 133.54)
		(width 0.1)
		(layer "In7.Cu")
		(net 1387)
	)
	(segment
		(start 249.339669 145.22)
		(end 246.3 145.22)
		(width 0.1)
		(layer "In7.Cu")
		(net 1387)
	)
	(segment
		(start 230.7 150.4)
		(end 230.3 150)
		(width 0.1)
		(layer "In7.Cu")
		(net 1387)
	)
	(segment
		(start 232 152.7)
		(end 230.7 151.4)
		(width 0.1)
		(layer "In7.Cu")
		(net 1387)
	)
	(segment
		(start 238.22 133.54)
		(end 236.405684 133.54)
		(width 0.1)
		(layer "In7.Cu")
		(net 1387)
	)
	(segment
		(start 233.3 152.7)
		(end 232 152.7)
		(width 0.1)
		(layer "In7.Cu")
		(net 1387)
	)
	(segment
		(start 230.3 150)
		(end 227.6 150)
		(width 0.1)
		(layer "In7.Cu")
		(net 1387)
	)
	(segment
		(start 220.9 151.9)
		(end 220.9 154.1)
		(width 0.1)
		(layer "In7.Cu")
		(net 1387)
	)
	(segment
		(start 230.7 151.4)
		(end 230.7 150.4)
		(width 0.1)
		(layer "In7.Cu")
		(net 1387)
	)
	(segment
		(start 245.8 145.72)
		(end 243.88 145.72)
		(width 0.1)
		(layer "In7.Cu")
		(net 1387)
	)
	(segment
		(start 227.6 150)
		(end 227.1 150.5)
		(width 0.1)
		(layer "In7.Cu")
		(net 1387)
	)
	(segment
		(start 255.4 144.75)
		(end 255.4 148.25)
		(width 0.1)
		(layer "In7.Cu")
		(net 1387)
	)
	(segment
		(start 252.5 144)
		(end 252.5 143.25)
		(width 0.1)
		(layer "F.Cu")
		(net 1388)
	)
	(segment
		(start 209 137)
		(end 208.5 136.5)
		(width 0.256)
		(layer "F.Cu")
		(net 1388)
	)
	(via
		(at 252.5 143.25)
		(size 0.45)
		(drill 0.2)
		(layers "F.Cu" "B.Cu")
		(net 1388)
	)
	(via
		(at 244.45 143.9995)
		(size 0.45)
		(drill 0.2)
		(layers "F.Cu" "B.Cu")
		(net 1388)
	)
	(via
		(at 209 137)
		(size 0.45)
		(drill 0.2)
		(layers "F.Cu" "B.Cu")
		(net 1388)
	)
	(segment
		(start 252.5 143.8)
		(end 252.5 143.25)
		(width 0.1)
		(layer "B.Cu")
		(net 1388)
	)
	(segment
		(start 244.45 143.9995)
		(end 252.3005 143.9995)
		(width 0.1)
		(layer "B.Cu")
		(net 1388)
	)
	(segment
		(start 252.3005 143.9995)
		(end 252.5 143.8)
		(width 0.1)
		(layer "B.Cu")
		(net 1388)
	)
	(segment
		(start 209.4 137.4)
		(end 209.4 138.117158)
		(width 0.1)
		(layer "In3.Cu")
		(net 1388)
	)
	(segment
		(start 210.575 141.192158)
		(end 210.782842 141.4)
		(width 0.1)
		(layer "In3.Cu")
		(net 1388)
	)
	(segment
		(start 239.965106 142.425)
		(end 240.190106 142.65)
		(width 0.1)
		(layer "In3.Cu")
		(net 1388)
	)
	(segment
		(start 209 137)
		(end 209.4 137.4)
		(width 0.1)
		(layer "In3.Cu")
		(net 1388)
	)
	(segment
		(start 210.782842 141.4)
		(end 214.965684 141.4)
		(width 0.1)
		(layer "In3.Cu")
		(net 1388)
	)
	(segment
		(start 226.637742 142.425)
		(end 239.965106 142.425)
		(width 0.1)
		(layer "In3.Cu")
		(net 1388)
	)
	(segment
		(start 243.08579 142.65)
		(end 243.375 142.93921)
		(width 0.1)
		(layer "In3.Cu")
		(net 1388)
	)
	(segment
		(start 243.886327 143.9995)
		(end 244.45 143.9995)
		(width 0.1)
		(layer "In3.Cu")
		(net 1388)
	)
	(segment
		(start 216.165684 142.6)
		(end 226.462743 142.6)
		(width 0.1)
		(layer "In3.Cu")
		(net 1388)
	)
	(segment
		(start 210.575 138.761826)
		(end 210.575 141.192158)
		(width 0.1)
		(layer "In3.Cu")
		(net 1388)
	)
	(segment
		(start 243.375 142.93921)
		(end 243.375 143.488173)
		(width 0.1)
		(layer "In3.Cu")
		(net 1388)
	)
	(segment
		(start 209.682842 138.4)
		(end 210.213174 138.4)
		(width 0.1)
		(layer "In3.Cu")
		(net 1388)
	)
	(segment
		(start 240.190106 142.65)
		(end 243.08579 142.65)
		(width 0.1)
		(layer "In3.Cu")
		(net 1388)
	)
	(segment
		(start 226.462743 142.6)
		(end 226.637742 142.425)
		(width 0.1)
		(layer "In3.Cu")
		(net 1388)
	)
	(segment
		(start 243.375 143.488173)
		(end 243.886327 143.9995)
		(width 0.1)
		(layer "In3.Cu")
		(net 1388)
	)
	(segment
		(start 214.965684 141.4)
		(end 216.165684 142.6)
		(width 0.1)
		(layer "In3.Cu")
		(net 1388)
	)
	(segment
		(start 209.4 138.117158)
		(end 209.682842 138.4)
		(width 0.1)
		(layer "In3.Cu")
		(net 1388)
	)
	(segment
		(start 210.213174 138.4)
		(end 210.575 138.761826)
		(width 0.1)
		(layer "In3.Cu")
		(net 1388)
	)
	(segment
		(start 193.599999 160.050001)
		(end 193.6 159.3)
		(width 0.177)
		(layer "F.Cu")
		(net 1389)
	)
	(segment
		(start 251.3 144)
		(end 251.3 142.85)
		(width 0.1)
		(layer "F.Cu")
		(net 1389)
	)
	(segment
		(start 251.3 142.85)
		(end 251.325 142.825)
		(width 0.1)
		(layer "F.Cu")
		(net 1389)
	)
	(via
		(at 193.6 159.3)
		(size 0.45)
		(drill 0.2)
		(layers "F.Cu" "B.Cu")
		(net 1389)
	)
	(via
		(at 251.325 142.825)
		(size 0.45)
		(drill 0.2)
		(layers "F.Cu" "B.Cu")
		(net 1389)
	)
	(segment
		(start 224.21 155.04)
		(end 217.87 155.04)
		(width 0.1)
		(layer "In3.Cu")
		(net 1389)
	)
	(segment
		(start 252.25 142.17)
		(end 252.64 141.78)
		(width 0.1)
		(layer "In3.Cu")
		(net 1389)
	)
	(segment
		(start 251.325 142.825)
		(end 251.325 142.575)
		(width 0.1)
		(layer "In3.Cu")
		(net 1389)
	)
	(segment
		(start 217.52 163.55)
		(end 217.52 158.88)
		(width 0.1)
		(layer "In3.Cu")
		(net 1389)
	)
	(segment
		(start 227.96 155.7)
		(end 229.22 154.44)
		(width 0.1)
		(layer "In3.Cu")
		(net 1389)
	)
	(segment
		(start 259.26 151.85)
		(end 253.43 151.85)
		(width 0.1)
		(layer "In3.Cu")
		(net 1389)
	)
	(segment
		(start 221.63 159.37)
		(end 225.74 159.37)
		(width 0.1)
		(layer "In3.Cu")
		(net 1389)
	)
	(segment
		(start 230.99 164.81)
		(end 230.27 164.09)
		(width 0.1)
		(layer "In3.Cu")
		(net 1389)
	)
	(segment
		(start 194.23 158.2)
		(end 193.6 158.83)
		(width 0.1)
		(layer "In3.Cu")
		(net 1389)
	)
	(segment
		(start 232.55 163.79)
		(end 231.53 164.81)
		(width 0.1)
		(layer "In3.Cu")
		(net 1389)
	)
	(segment
		(start 219.02 157.38)
		(end 219.64 157.38)
		(width 0.1)
		(layer "In3.Cu")
		(net 1389)
	)
	(segment
		(start 251.325 142.575)
		(end 251.73 142.17)
		(width 0.1)
		(layer "In3.Cu")
		(net 1389)
	)
	(segment
		(start 216.04 156.87)
		(end 200.78 156.87)
		(width 0.1)
		(layer "In3.Cu")
		(net 1389)
	)
	(segment
		(start 217.87 155.04)
		(end 216.04 156.87)
		(width 0.1)
		(layer "In3.Cu")
		(net 1389)
	)
	(segment
		(start 221.7 164.09)
		(end 221.58 163.97)
		(width 0.1)
		(layer "In3.Cu")
		(net 1389)
	)
	(segment
		(start 227.96 157.15)
		(end 227.96 155.7)
		(width 0.1)
		(layer "In3.Cu")
		(net 1389)
	)
	(segment
		(start 249.79 155.49)
		(end 239.95 155.49)
		(width 0.1)
		(layer "In3.Cu")
		(net 1389)
	)
	(segment
		(start 255.18 141.78)
		(end 256.31 142.91)
		(width 0.1)
		(layer "In3.Cu")
		(net 1389)
	)
	(segment
		(start 230.27 164.09)
		(end 221.7 164.09)
		(width 0.1)
		(layer "In3.Cu")
		(net 1389)
	)
	(segment
		(start 193.6 158.83)
		(end 193.6 159.3)
		(width 0.1)
		(layer "In3.Cu")
		(net 1389)
	)
	(segment
		(start 253.43 151.85)
		(end 249.79 155.49)
		(width 0.1)
		(layer "In3.Cu")
		(net 1389)
	)
	(segment
		(start 235.572274 159.867726)
		(end 234.542274 159.867726)
		(width 0.1)
		(layer "In3.Cu")
		(net 1389)
	)
	(segment
		(start 217.94 163.97)
		(end 217.52 163.55)
		(width 0.1)
		(layer "In3.Cu")
		(net 1389)
	)
	(segment
		(start 263.29 144.09)
		(end 263.29 147.82)
		(width 0.1)
		(layer "In3.Cu")
		(net 1389)
	)
	(segment
		(start 225.9 153.35)
		(end 224.21 155.04)
		(width 0.1)
		(layer "In3.Cu")
		(net 1389)
	)
	(segment
		(start 232.55 161.86)
		(end 232.55 163.79)
		(width 0.1)
		(layer "In3.Cu")
		(net 1389)
	)
	(segment
		(start 231.53 164.81)
		(end 230.99 164.81)
		(width 0.1)
		(layer "In3.Cu")
		(net 1389)
	)
	(segment
		(start 262.11 142.91)
		(end 263.29 144.09)
		(width 0.1)
		(layer "In3.Cu")
		(net 1389)
	)
	(segment
		(start 229.22 154.44)
		(end 229.22 153.72)
		(width 0.1)
		(layer "In3.Cu")
		(net 1389)
	)
	(segment
		(start 256.31 142.91)
		(end 262.11 142.91)
		(width 0.1)
		(layer "In3.Cu")
		(net 1389)
	)
	(segment
		(start 229.22 153.72)
		(end 228.85 153.35)
		(width 0.1)
		(layer "In3.Cu")
		(net 1389)
	)
	(segment
		(start 234.542274 159.867726)
		(end 232.55 161.86)
		(width 0.1)
		(layer "In3.Cu")
		(net 1389)
	)
	(segment
		(start 200.78 156.87)
		(end 199.45 158.2)
		(width 0.1)
		(layer "In3.Cu")
		(net 1389)
	)
	(segment
		(start 239.95 155.49)
		(end 235.572274 159.867726)
		(width 0.1)
		(layer "In3.Cu")
		(net 1389)
	)
	(segment
		(start 217.52 158.88)
		(end 219.02 157.38)
		(width 0.1)
		(layer "In3.Cu")
		(net 1389)
	)
	(segment
		(start 199.45 158.2)
		(end 194.23 158.2)
		(width 0.1)
		(layer "In3.Cu")
		(net 1389)
	)
	(segment
		(start 228.85 153.35)
		(end 225.9 153.35)
		(width 0.1)
		(layer "In3.Cu")
		(net 1389)
	)
	(segment
		(start 221.58 163.97)
		(end 217.94 163.97)
		(width 0.1)
		(layer "In3.Cu")
		(net 1389)
	)
	(segment
		(start 251.73 142.17)
		(end 252.25 142.17)
		(width 0.1)
		(layer "In3.Cu")
		(net 1389)
	)
	(segment
		(start 252.64 141.78)
		(end 255.18 141.78)
		(width 0.1)
		(layer "In3.Cu")
		(net 1389)
	)
	(segment
		(start 263.29 147.82)
		(end 259.26 151.85)
		(width 0.1)
		(layer "In3.Cu")
		(net 1389)
	)
	(segment
		(start 225.74 159.37)
		(end 227.96 157.15)
		(width 0.1)
		(layer "In3.Cu")
		(net 1389)
	)
	(segment
		(start 219.64 157.38)
		(end 221.63 159.37)
		(width 0.1)
		(layer "In3.Cu")
		(net 1389)
	)
	(segment
		(start 209.012326 141.999918)
		(end 208.999918 141.999918)
		(width 0.256)
		(layer "F.Cu")
		(net 1390)
	)
	(segment
		(start 208.999918 141.999918)
		(end 208.5 141.5)
		(width 0.256)
		(layer "F.Cu")
		(net 1390)
	)
	(segment
		(start 254.5 144)
		(end 254.5 143.25)
		(width 0.1)
		(layer "F.Cu")
		(net 1390)
	)
	(via
		(at 209.012326 141.999918)
		(size 0.45)
		(drill 0.2)
		(layers "F.Cu" "B.Cu")
		(net 1390)
	)
	(via
		(at 254.5 143.25)
		(size 0.45)
		(drill 0.2)
		(layers "F.Cu" "B.Cu")
		(net 1390)
	)
	(segment
		(start 209.012326 141.999918)
		(end 209.012326 142.412326)
		(width 0.1)
		(layer "In3.Cu")
		(net 1390)
	)
	(segment
		(start 209.4 143.3)
		(end 209.7 143.6)
		(width 0.1)
		(layer "In3.Cu")
		(net 1390)
	)
	(segment
		(start 251.3 145.6)
		(end 251.45 145.75)
		(width 0.1)
		(layer "In3.Cu")
		(net 1390)
	)
	(segment
		(start 251.45 147.5)
		(end 252.4 148.45)
		(width 0.1)
		(layer "In3.Cu")
		(net 1390)
	)
	(segment
		(start 209.012326 142.412326)
		(end 209.4 142.8)
		(width 0.1)
		(layer "In3.Cu")
		(net 1390)
	)
	(segment
		(start 237.979894 147.275)
		(end 245.542158 147.275)
		(width 0.1)
		(layer "In3.Cu")
		(net 1390)
	)
	(segment
		(start 251.45 145.75)
		(end 251.45 147.5)
		(width 0.1)
		(layer "In3.Cu")
		(net 1390)
	)
	(segment
		(start 247.075 145.825)
		(end 247.3 145.6)
		(width 0.1)
		(layer "In3.Cu")
		(net 1390)
	)
	(segment
		(start 247.3 145.6)
		(end 251.3 145.6)
		(width 0.1)
		(layer "In3.Cu")
		(net 1390)
	)
	(segment
		(start 245.542158 147.275)
		(end 246.167158 147.9)
		(width 0.1)
		(layer "In3.Cu")
		(net 1390)
	)
	(segment
		(start 209.4 142.8)
		(end 209.4 143.3)
		(width 0.1)
		(layer "In3.Cu")
		(net 1390)
	)
	(segment
		(start 246.663173 147.9)
		(end 247.075 147.488173)
		(width 0.1)
		(layer "In3.Cu")
		(net 1390)
	)
	(segment
		(start 227.46 144.09)
		(end 234.794894 144.09)
		(width 0.1)
		(layer "In3.Cu")
		(net 1390)
	)
	(segment
		(start 252.4 148.45)
		(end 254.3 148.45)
		(width 0.1)
		(layer "In3.Cu")
		(net 1390)
	)
	(segment
		(start 246.167158 147.9)
		(end 246.663173 147.9)
		(width 0.1)
		(layer "In3.Cu")
		(net 1390)
	)
	(segment
		(start 234.794894 144.09)
		(end 237.979894 147.275)
		(width 0.1)
		(layer "In3.Cu")
		(net 1390)
	)
	(segment
		(start 254.9 143.65)
		(end 254.5 143.25)
		(width 0.1)
		(layer "In3.Cu")
		(net 1390)
	)
	(segment
		(start 226.97 143.6)
		(end 227.46 144.09)
		(width 0.1)
		(layer "In3.Cu")
		(net 1390)
	)
	(segment
		(start 254.3 148.45)
		(end 254.9 147.85)
		(width 0.1)
		(layer "In3.Cu")
		(net 1390)
	)
	(segment
		(start 247.075 147.488173)
		(end 247.075 145.825)
		(width 0.1)
		(layer "In3.Cu")
		(net 1390)
	)
	(segment
		(start 209.7 143.6)
		(end 226.97 143.6)
		(width 0.1)
		(layer "In3.Cu")
		(net 1390)
	)
	(segment
		(start 254.9 147.85)
		(end 254.9 143.65)
		(width 0.1)
		(layer "In3.Cu")
		(net 1390)
	)
	(segment
		(start 254.1 144)
		(end 254.1 142.85)
		(width 0.1)
		(layer "F.Cu")
		(net 1391)
	)
	(segment
		(start 209.5 137.5)
		(end 210 138)
		(width 0.256)
		(layer "F.Cu")
		(net 1391)
	)
	(via
		(at 254.1 142.85)
		(size 0.45)
		(drill 0.2)
		(layers "F.Cu" "B.Cu")
		(net 1391)
	)
	(via
		(at 210 138)
		(size 0.45)
		(drill 0.2)
		(layers "F.Cu" "B.Cu")
		(net 1391)
	)
	(segment
		(start 216.248526 142.4)
		(end 226.3799 142.4)
		(width 0.1)
		(layer "In3.Cu")
		(net 1391)
	)
	(segment
		(start 210.6 138)
		(end 210.9 138.3)
		(width 0.1)
		(layer "In3.Cu")
		(net 1391)
	)
	(segment
		(start 214.448526 140.6)
		(end 216.248526 142.4)
		(width 0.1)
		(layer "In3.Cu")
		(net 1391)
	)
	(segment
		(start 226.3799 142.4)
		(end 226.554899 142.225)
		(width 0.1)
		(layer "In3.Cu")
		(net 1391)
	)
	(segment
		(start 210.9 138.3)
		(end 210.9 139.3)
		(width 0.1)
		(layer "In3.Cu")
		(net 1391)
	)
	(segment
		(start 226.554899 142.225)
		(end 240.047948 142.225)
		(width 0.1)
		(layer "In3.Cu")
		(net 1391)
	)
	(segment
		(start 240.272948 142.45)
		(end 243.168632 142.45)
		(width 0.1)
		(layer "In3.Cu")
		(net 1391)
	)
	(segment
		(start 243.168632 142.45)
		(end 243.575 142.856368)
		(width 0.1)
		(layer "In3.Cu")
		(net 1391)
	)
	(segment
		(start 210.9 139.3)
		(end 211.425 139.825)
		(width 0.1)
		(layer "In3.Cu")
		(net 1391)
	)
	(segment
		(start 244.625 143.625)
		(end 245.9 144.9)
		(width 0.1)
		(layer "In3.Cu")
		(net 1391)
	)
	(segment
		(start 243.794669 143.625)
		(end 244.625 143.625)
		(width 0.1)
		(layer "In3.Cu")
		(net 1391)
	)
	(segment
		(start 211.717157 140.6)
		(end 214.448526 140.6)
		(width 0.1)
		(layer "In3.Cu")
		(net 1391)
	)
	(segment
		(start 240.047948 142.225)
		(end 240.272948 142.45)
		(width 0.1)
		(layer "In3.Cu")
		(net 1391)
	)
	(segment
		(start 254.1 144.3)
		(end 254.1 142.85)
		(width 0.1)
		(layer "In3.Cu")
		(net 1391)
	)
	(segment
		(start 211.425 140.307843)
		(end 211.717157 140.6)
		(width 0.1)
		(layer "In3.Cu")
		(net 1391)
	)
	(segment
		(start 210 138)
		(end 210.6 138)
		(width 0.1)
		(layer "In3.Cu")
		(net 1391)
	)
	(segment
		(start 211.425 139.825)
		(end 211.425 140.307843)
		(width 0.1)
		(layer "In3.Cu")
		(net 1391)
	)
	(segment
		(start 245.9 144.9)
		(end 253.5 144.9)
		(width 0.1)
		(layer "In3.Cu")
		(net 1391)
	)
	(segment
		(start 243.575 142.856368)
		(end 243.575 143.405331)
		(width 0.1)
		(layer "In3.Cu")
		(net 1391)
	)
	(segment
		(start 243.575 143.405331)
		(end 243.794669 143.625)
		(width 0.1)
		(layer "In3.Cu")
		(net 1391)
	)
	(segment
		(start 253.5 144.9)
		(end 254.1 144.3)
		(width 0.1)
		(layer "In3.Cu")
		(net 1391)
	)
	(segment
		(start 253.3 144)
		(end 253.3 142.85)
		(width 0.1)
		(layer "F.Cu")
		(net 1392)
	)
	(segment
		(start 205.976828 138.976828)
		(end 206.011849 138.976828)
		(width 0.256)
		(layer "F.Cu")
		(net 1392)
	)
	(segment
		(start 205.5 138.5)
		(end 205.976828 138.976828)
		(width 0.256)
		(layer "F.Cu")
		(net 1392)
	)
	(via
		(at 248.9 148.38)
		(size 0.45)
		(drill 0.2)
		(layers "F.Cu" "B.Cu")
		(net 1392)
	)
	(via
		(at 253.3 142.85)
		(size 0.45)
		(drill 0.2)
		(layers "F.Cu" "B.Cu")
		(net 1392)
	)
	(via
		(at 206.011849 138.976828)
		(size 0.45)
		(drill 0.2)
		(layers "F.Cu" "B.Cu")
		(net 1392)
	)
	(segment
		(start 206.4 139.364979)
		(end 206.4 140.1)
		(width 0.1)
		(layer "In3.Cu")
		(net 1392)
	)
	(segment
		(start 207.6 140.617157)
		(end 207.6 145.2)
		(width 0.1)
		(layer "In3.Cu")
		(net 1392)
	)
	(segment
		(start 206.4 140.1)
		(end 206.7 140.4)
		(width 0.1)
		(layer "In3.Cu")
		(net 1392)
	)
	(segment
		(start 206.7 140.4)
		(end 207.382843 140.4)
		(width 0.1)
		(layer "In3.Cu")
		(net 1392)
	)
	(segment
		(start 207.6 145.2)
		(end 207.9 145.5)
		(width 0.1)
		(layer "In3.Cu")
		(net 1392)
	)
	(segment
		(start 216.2 144.4)
		(end 226.275 144.4)
		(width 0.1)
		(layer "In3.Cu")
		(net 1392)
	)
	(segment
		(start 247.41 148.16)
		(end 248.68 148.16)
		(width 0.1)
		(layer "In3.Cu")
		(net 1392)
	)
	(segment
		(start 245.64 149.09)
		(end 246.48 149.09)
		(width 0.1)
		(layer "In3.Cu")
		(net 1392)
	)
	(segment
		(start 215.1 145.5)
		(end 216.2 144.4)
		(width 0.1)
		(layer "In3.Cu")
		(net 1392)
	)
	(segment
		(start 227.385 145.51)
		(end 235.083526 145.51)
		(width 0.1)
		(layer "In3.Cu")
		(net 1392)
	)
	(segment
		(start 207.9 145.5)
		(end 215.1 145.5)
		(width 0.1)
		(layer "In3.Cu")
		(net 1392)
	)
	(segment
		(start 244.65 148.1)
		(end 245.64 149.09)
		(width 0.1)
		(layer "In3.Cu")
		(net 1392)
	)
	(segment
		(start 237.673526 148.1)
		(end 244.65 148.1)
		(width 0.1)
		(layer "In3.Cu")
		(net 1392)
	)
	(segment
		(start 248.68 148.16)
		(end 248.9 148.38)
		(width 0.1)
		(layer "In3.Cu")
		(net 1392)
	)
	(segment
		(start 207.382843 140.4)
		(end 207.6 140.617157)
		(width 0.1)
		(layer "In3.Cu")
		(net 1392)
	)
	(segment
		(start 206.011849 138.976828)
		(end 206.4 139.364979)
		(width 0.1)
		(layer "In3.Cu")
		(net 1392)
	)
	(segment
		(start 226.275 144.4)
		(end 227.385 145.51)
		(width 0.1)
		(layer "In3.Cu")
		(net 1392)
	)
	(segment
		(start 246.48 149.09)
		(end 247.41 148.16)
		(width 0.1)
		(layer "In3.Cu")
		(net 1392)
	)
	(segment
		(start 235.083526 145.51)
		(end 237.673526 148.1)
		(width 0.1)
		(layer "In3.Cu")
		(net 1392)
	)
	(segment
		(start 254.96 149.41)
		(end 256.38 147.99)
		(width 0.1)
		(layer "In5.Cu")
		(net 1392)
	)
	(segment
		(start 249.79 149.41)
		(end 254.96 149.41)
		(width 0.1)
		(layer "In5.Cu")
		(net 1392)
	)
	(segment
		(start 256.38 147.99)
		(end 256.38 144.01)
		(width 0.1)
		(layer "In5.Cu")
		(net 1392)
	)
	(segment
		(start 255.55 143.75)
		(end 254.25 142.45)
		(width 0.1)
		(layer "In5.Cu")
		(net 1392)
	)
	(segment
		(start 253.7 142.45)
		(end 253.3 142.85)
		(width 0.1)
		(layer "In5.Cu")
		(net 1392)
	)
	(segment
		(start 256.12 143.75)
		(end 255.55 143.75)
		(width 0.1)
		(layer "In5.Cu")
		(net 1392)
	)
	(segment
		(start 248.9 148.38)
		(end 248.9 148.52)
		(width 0.1)
		(layer "In5.Cu")
		(net 1392)
	)
	(segment
		(start 256.38 144.01)
		(end 256.12 143.75)
		(width 0.1)
		(layer "In5.Cu")
		(net 1392)
	)
	(segment
		(start 248.9 148.52)
		(end 249.79 149.41)
		(width 0.1)
		(layer "In5.Cu")
		(net 1392)
	)
	(segment
		(start 254.25 142.45)
		(end 253.7 142.45)
		(width 0.1)
		(layer "In5.Cu")
		(net 1392)
	)
	(segment
		(start 179.25 170.5)
		(end 180.2 170.5)
		(width 0.182)
		(layer "F.Cu")
		(net 1393)
	)
	(segment
		(start 180.2 170.5)
		(end 180.6 170.1)
		(width 0.182)
		(layer "F.Cu")
		(net 1393)
	)
	(segment
		(start 183.27 169.11)
		(end 182.7392 169.11)
		(width 0.182)
		(layer "F.Cu")
		(net 1393)
	)
	(segment
		(start 181.6508 170.1)
		(end 181.7 170.1492)
		(width 0.182)
		(layer "F.Cu")
		(net 1393)
	)
	(segment
		(start 180.6 170.1)
		(end 181.6508 170.1)
		(width 0.182)
		(layer "F.Cu")
		(net 1393)
	)
	(segment
		(start 182.7392 169.11)
		(end 181.7 170.1492)
		(width 0.182)
		(layer "F.Cu")
		(net 1393)
	)
	(via
		(at 183.27 169.11)
		(size 0.45)
		(drill 0.2)
		(layers "F.Cu" "B.Cu")
		(net 1393)
	)
	(via
		(at 180.77 182.74)
		(size 0.45)
		(drill 0.2)
		(layers "F.Cu" "B.Cu")
		(net 1393)
	)
	(segment
		(start 183.27 169.11)
		(end 183.71 169.11)
		(width 0.1)
		(layer "In3.Cu")
		(net 1393)
	)
	(segment
		(start 183.71 169.11)
		(end 184.175 169.575)
		(width 0.1)
		(layer "In3.Cu")
		(net 1393)
	)
	(segment
		(start 184.175 169.575)
		(end 184.175 172.505)
		(width 0.1)
		(layer "In3.Cu")
		(net 1393)
	)
	(segment
		(start 184.99 179.11)
		(end 181.36 182.74)
		(width 0.1)
		(layer "In3.Cu")
		(net 1393)
	)
	(segment
		(start 184.99 173.32)
		(end 184.99 179.11)
		(width 0.1)
		(layer "In3.Cu")
		(net 1393)
	)
	(segment
		(start 184.175 172.505)
		(end 184.99 173.32)
		(width 0.1)
		(layer "In3.Cu")
		(net 1393)
	)
	(segment
		(start 181.36 182.74)
		(end 180.77 182.74)
		(width 0.1)
		(layer "In3.Cu")
		(net 1393)
	)
	(segment
		(start 163.7383 170.1492)
		(end 164.5 170.1492)
		(width 0.182)
		(layer "F.Cu")
		(net 1394)
	)
	(segment
		(start 163.3875 170.5)
		(end 163.7383 170.1492)
		(width 0.182)
		(layer "F.Cu")
		(net 1394)
	)
	(segment
		(start 164.5 170.1492)
		(end 165.1492 170.1492)
		(width 0.182)
		(layer "F.Cu")
		(net 1394)
	)
	(segment
		(start 162.3 170.5)
		(end 163.3875 170.5)
		(width 0.182)
		(layer "F.Cu")
		(net 1394)
	)
	(segment
		(start 165.1492 170.1492)
		(end 165.2 170.2)
		(width 0.182)
		(layer "F.Cu")
		(net 1394)
	)
	(via
		(at 179.77 182.74)
		(size 0.45)
		(drill 0.2)
		(layers "F.Cu" "B.Cu")
		(net 1394)
	)
	(via
		(at 165.2 170.2)
		(size 0.45)
		(drill 0.2)
		(layers "F.Cu" "B.Cu")
		(net 1394)
	)
	(via
		(at 169 183.7)
		(size 0.45)
		(drill 0.2)
		(layers "F.Cu" "B.Cu")
		(net 1394)
	)
	(segment
		(start 179.77 183.74)
		(end 178.61 184.9)
		(width 0.1)
		(layer "B.Cu")
		(net 1394)
	)
	(segment
		(start 178.61 184.9)
		(end 170.2 184.9)
		(width 0.1)
		(layer "B.Cu")
		(net 1394)
	)
	(segment
		(start 179.77 182.74)
		(end 179.77 183.74)
		(width 0.1)
		(layer "B.Cu")
		(net 1394)
	)
	(segment
		(start 170.2 184.9)
		(end 169 183.7)
		(width 0.1)
		(layer "B.Cu")
		(net 1394)
	)
	(segment
		(start 165.2 170.2)
		(end 164.6 170.8)
		(width 0.1)
		(layer "In3.Cu")
		(net 1394)
	)
	(segment
		(start 168 183.7)
		(end 169 183.7)
		(width 0.1)
		(layer "In3.Cu")
		(net 1394)
	)
	(segment
		(start 164.6 180.3)
		(end 168 183.7)
		(width 0.1)
		(layer "In3.Cu")
		(net 1394)
	)
	(segment
		(start 164.6 170.8)
		(end 164.6 180.3)
		(width 0.1)
		(layer "In3.Cu")
		(net 1394)
	)
	(segment
		(start 232.592234 149.661168)
		(end 232.592234 149.307766)
		(width 0.182)
		(layer "F.Cu")
		(net 1397)
	)
	(segment
		(start 232.592234 149.307766)
		(end 232.9 149)
		(width 0.182)
		(layer "F.Cu")
		(net 1397)
	)
	(segment
		(start 198.5 134.5)
		(end 198 135)
		(width 0.256)
		(layer "F.Cu")
		(net 1397)
	)
	(via
		(at 198 135)
		(size 0.45)
		(drill 0.2)
		(layers "F.Cu" "B.Cu")
		(net 1397)
	)
	(via
		(at 232.592234 149.661168)
		(size 0.45)
		(drill 0.2)
		(layers "F.Cu" "B.Cu")
		(net 1397)
	)
	(segment
		(start 235.2 147.9)
		(end 234.353402 147.9)
		(width 0.1)
		(layer "In7.Cu")
		(net 1397)
	)
	(segment
		(start 201.089668 142.62)
		(end 213.38 142.62)
		(width 0.1)
		(layer "In7.Cu")
		(net 1397)
	)
	(segment
		(start 199.5 135.6)
		(end 199.5 141.030332)
		(width 0.1)
		(layer "In7.Cu")
		(net 1397)
	)
	(segment
		(start 199.5 141.030332)
		(end 201.089668 142.62)
		(width 0.1)
		(layer "In7.Cu")
		(net 1397)
	)
	(segment
		(start 234.353402 147.9)
		(end 232.592234 149.661168)
		(width 0.1)
		(layer "In7.Cu")
		(net 1397)
	)
	(segment
		(start 213.875 142.125)
		(end 232.925 142.125)
		(width 0.1)
		(layer "In7.Cu")
		(net 1397)
	)
	(segment
		(start 232.925 142.125)
		(end 235.9 145.1)
		(width 0.1)
		(layer "In7.Cu")
		(net 1397)
	)
	(segment
		(start 235.9 145.1)
		(end 235.9 147.2)
		(width 0.1)
		(layer "In7.Cu")
		(net 1397)
	)
	(segment
		(start 198 135)
		(end 198.9 135)
		(width 0.1)
		(layer "In7.Cu")
		(net 1397)
	)
	(segment
		(start 213.38 142.62)
		(end 213.875 142.125)
		(width 0.1)
		(layer "In7.Cu")
		(net 1397)
	)
	(segment
		(start 235.9 147.2)
		(end 235.2 147.9)
		(width 0.1)
		(layer "In7.Cu")
		(net 1397)
	)
	(segment
		(start 198.9 135)
		(end 199.5 135.6)
		(width 0.1)
		(layer "In7.Cu")
		(net 1397)
	)
	(segment
		(start 218.715 137.2)
		(end 217.94 137.2)
		(width 0.184)
		(layer "F.Cu")
		(net 1402)
	)
	(segment
		(start 217.94 137.2)
		(end 217.68 137.46)
		(width 0.184)
		(layer "F.Cu")
		(net 1402)
	)
	(segment
		(start 217.68 138.94)
		(end 217.64 138.98)
		(width 0.184)
		(layer "F.Cu")
		(net 1402)
	)
	(segment
		(start 211.5 136.5)
		(end 212 137)
		(width 0.256)
		(layer "F.Cu")
		(net 1402)
	)
	(segment
		(start 217.68 137.46)
		(end 217.68 138.94)
		(width 0.184)
		(layer "F.Cu")
		(net 1402)
	)
	(via
		(at 212 137)
		(size 0.45)
		(drill 0.2)
		(layers "F.Cu" "B.Cu")
		(net 1402)
	)
	(via
		(at 217.64 138.98)
		(size 0.45)
		(drill 0.2)
		(layers "F.Cu" "B.Cu")
		(net 1402)
	)
	(segment
		(start 216.07 137.41)
		(end 212.41 137.41)
		(width 0.1)
		(layer "In7.Cu")
		(net 1402)
	)
	(segment
		(start 217.64 138.98)
		(end 216.07 137.41)
		(width 0.1)
		(layer "In7.Cu")
		(net 1402)
	)
	(segment
		(start 212.41 137.41)
		(end 212 137)
		(width 0.1)
		(layer "In7.Cu")
		(net 1402)
	)
	(segment
		(start 218.715 142.4)
		(end 218.29 142.4)
		(width 0.184)
		(layer "F.Cu")
		(net 1403)
	)
	(segment
		(start 215.5 139.35)
		(end 214.85 140)
		(width 0.184)
		(layer "F.Cu")
		(net 1403)
	)
	(segment
		(start 213 140)
		(end 212.5 139.5)
		(width 0.184)
		(layer "F.Cu")
		(net 1403)
	)
	(segment
		(start 217.83 140.18)
		(end 217.223 139.573)
		(width 0.184)
		(layer "F.Cu")
		(net 1403)
	)
	(segment
		(start 215.775 138.5)
		(end 215.5 138.775)
		(width 0.184)
		(layer "F.Cu")
		(net 1403)
	)
	(segment
		(start 214.85 140)
		(end 213 140)
		(width 0.184)
		(layer "F.Cu")
		(net 1403)
	)
	(segment
		(start 217.223 138.793)
		(end 216.93 138.5)
		(width 0.184)
		(layer "F.Cu")
		(net 1403)
	)
	(segment
		(start 217.83 141.94)
		(end 217.83 140.18)
		(width 0.184)
		(layer "F.Cu")
		(net 1403)
	)
	(segment
		(start 216.93 138.5)
		(end 215.775 138.5)
		(width 0.184)
		(layer "F.Cu")
		(net 1403)
	)
	(segment
		(start 218.29 142.4)
		(end 217.83 141.94)
		(width 0.184)
		(layer "F.Cu")
		(net 1403)
	)
	(segment
		(start 215.5 138.775)
		(end 215.5 139.35)
		(width 0.184)
		(layer "F.Cu")
		(net 1403)
	)
	(segment
		(start 217.223 139.573)
		(end 217.223 138.793)
		(width 0.184)
		(layer "F.Cu")
		(net 1403)
	)
	(segment
		(start 252 120.65)
		(end 251.975 120.625)
		(width 0.1)
		(layer "F.Cu")
		(net 1413)
	)
	(segment
		(start 158.1875 173.9625)
		(end 158.1875 174.825)
		(width 0.182)
		(layer "F.Cu")
		(net 1413)
	)
	(segment
		(start 252 121.7)
		(end 252 120.65)
		(width 0.1)
		(layer "F.Cu")
		(net 1413)
	)
	(via
		(at 251.975 120.625)
		(size 0.45)
		(drill 0.2)
		(layers "F.Cu" "B.Cu")
		(net 1413)
	)
	(via
		(at 256.9 146.7)
		(size 0.45)
		(drill 0.2)
		(layers "F.Cu" "B.Cu")
		(net 1413)
	)
	(via
		(at 156.4625 176.675)
		(size 0.45)
		(drill 0.2)
		(layers "F.Cu" "B.Cu")
		(net 1413)
	)
	(via
		(at 251.3 147.925)
		(size 0.45)
		(drill 0.2)
		(layers "F.Cu" "B.Cu")
		(net 1413)
	)
	(via
		(at 255.5 153.3)
		(size 0.45)
		(drill 0.2)
		(layers "F.Cu" "B.Cu")
		(net 1413)
	)
	(via
		(at 158.1875 174.825)
		(size 0.45)
		(drill 0.2)
		(layers "F.Cu" "B.Cu")
		(net 1413)
	)
	(segment
		(start 251.3 147.925)
		(end 251.3 148.85)
		(width 0.1)
		(layer "B.Cu")
		(net 1413)
	)
	(segment
		(start 158.1875 174.95)
		(end 156.4625 176.675)
		(width 0.182)
		(layer "In2.Cu")
		(net 1413)
	)
	(segment
		(start 158.1875 174.825)
		(end 158.1875 174.95)
		(width 0.182)
		(layer "In2.Cu")
		(net 1413)
	)
	(segment
		(start 184.345 187.425)
		(end 167.925 187.425)
		(width 0.1)
		(layer "In3.Cu")
		(net 1413)
	)
	(segment
		(start 159.5 179.7125)
		(end 156.4625 176.675)
		(width 0.1)
		(layer "In3.Cu")
		(net 1413)
	)
	(segment
		(start 258.4 158.3)
		(end 259.5 159.4)
		(width 0.1)
		(layer "In3.Cu")
		(net 1413)
	)
	(segment
		(start 167.925 187.425)
		(end 166.1 185.6)
		(width 0.1)
		(layer "In3.Cu")
		(net 1413)
	)
	(segment
		(start 266.2 156.4)
		(end 266.2 167)
		(width 0.1)
		(layer "In3.Cu")
		(net 1413)
	)
	(segment
		(start 190.4 181.37)
		(end 184.345 187.425)
		(width 0.1)
		(layer "In3.Cu")
		(net 1413)
	)
	(segment
		(start 267.5 172.2)
		(end 265.4 174.3)
		(width 0.1)
		(layer "In3.Cu")
		(net 1413)
	)
	(segment
		(start 251.325 147.925)
		(end 252.2 148.8)
		(width 0.1)
		(layer "In3.Cu")
		(net 1413)
	)
	(segment
		(start 159.5 185.2)
		(end 159.5 179.7125)
		(width 0.1)
		(layer "In3.Cu")
		(net 1413)
	)
	(segment
		(start 265.4 174.3)
		(end 258.2 174.3)
		(width 0.1)
		(layer "In3.Cu")
		(net 1413)
	)
	(segment
		(start 254.8 148.8)
		(end 256.9 146.7)
		(width 0.1)
		(layer "In3.Cu")
		(net 1413)
	)
	(segment
		(start 263.9 155.9)
		(end 265.7 155.9)
		(width 0.1)
		(layer "In3.Cu")
		(net 1413)
	)
	(segment
		(start 194.9 169.9)
		(end 191.9 169.9)
		(width 0.1)
		(layer "In3.Cu")
		(net 1413)
	)
	(segment
		(start 159.9 185.6)
		(end 159.5 185.2)
		(width 0.1)
		(layer "In3.Cu")
		(net 1413)
	)
	(segment
		(start 261.3 159.4)
		(end 263.2 157.5)
		(width 0.1)
		(layer "In3.Cu")
		(net 1413)
	)
	(segment
		(start 166.1 185.6)
		(end 159.9 185.6)
		(width 0.1)
		(layer "In3.Cu")
		(net 1413)
	)
	(segment
		(start 267.5 168.3)
		(end 267.5 172.2)
		(width 0.1)
		(layer "In3.Cu")
		(net 1413)
	)
	(segment
		(start 258.4 154.7)
		(end 258.4 158.3)
		(width 0.1)
		(layer "In3.Cu")
		(net 1413)
	)
	(segment
		(start 197.7 167.1)
		(end 194.9 169.9)
		(width 0.1)
		(layer "In3.Cu")
		(net 1413)
	)
	(segment
		(start 259.5 159.4)
		(end 261.3 159.4)
		(width 0.1)
		(layer "In3.Cu")
		(net 1413)
	)
	(segment
		(start 258.2 174.3)
		(end 251 167.1)
		(width 0.1)
		(layer "In3.Cu")
		(net 1413)
	)
	(segment
		(start 266.2 167)
		(end 267.5 168.3)
		(width 0.1)
		(layer "In3.Cu")
		(net 1413)
	)
	(segment
		(start 252.2 148.8)
		(end 254.8 148.8)
		(width 0.1)
		(layer "In3.Cu")
		(net 1413)
	)
	(segment
		(start 251.3 147.925)
		(end 251.325 147.925)
		(width 0.1)
		(layer "In3.Cu")
		(net 1413)
	)
	(segment
		(start 265.7 155.9)
		(end 266.2 156.4)
		(width 0.1)
		(layer "In3.Cu")
		(net 1413)
	)
	(segment
		(start 255.5 153.3)
		(end 257 153.3)
		(width 0.1)
		(layer "In3.Cu")
		(net 1413)
	)
	(segment
		(start 263.2 157.5)
		(end 263.2 156.6)
		(width 0.1)
		(layer "In3.Cu")
		(net 1413)
	)
	(segment
		(start 251 167.1)
		(end 197.7 167.1)
		(width 0.1)
		(layer "In3.Cu")
		(net 1413)
	)
	(segment
		(start 257 153.3)
		(end 258.4 154.7)
		(width 0.1)
		(layer "In3.Cu")
		(net 1413)
	)
	(segment
		(start 190.4 171.4)
		(end 190.4 181.37)
		(width 0.1)
		(layer "In3.Cu")
		(net 1413)
	)
	(segment
		(start 263.2 156.6)
		(end 263.9 155.9)
		(width 0.1)
		(layer "In3.Cu")
		(net 1413)
	)
	(segment
		(start 191.9 169.9)
		(end 190.4 171.4)
		(width 0.1)
		(layer "In3.Cu")
		(net 1413)
	)
	(segment
		(start 251.3 147.925)
		(end 251.3 147.05)
		(width 0.1)
		(layer "In5.Cu")
		(net 1413)
	)
	(segment
		(start 255.4 126.65)
		(end 251.975 123.225)
		(width 0.1)
		(layer "In5.Cu")
		(net 1413)
	)
	(segment
		(start 255.4 132.9)
		(end 255.4 126.65)
		(width 0.1)
		(layer "In5.Cu")
		(net 1413)
	)
	(segment
		(start 252.8 135.5)
		(end 255.4 132.9)
		(width 0.1)
		(layer "In5.Cu")
		(net 1413)
	)
	(segment
		(start 253.125 145.225)
		(end 253.125 143.25)
		(width 0.1)
		(layer "In5.Cu")
		(net 1413)
	)
	(segment
		(start 251.975 123.225)
		(end 251.975 120.625)
		(width 0.1)
		(layer "In5.Cu")
		(net 1413)
	)
	(segment
		(start 253.125 143.25)
		(end 252.8 142.925)
		(width 0.1)
		(layer "In5.Cu")
		(net 1413)
	)
	(segment
		(start 252.8 142.925)
		(end 252.8 135.5)
		(width 0.1)
		(layer "In5.Cu")
		(net 1413)
	)
	(segment
		(start 251.3 147.05)
		(end 253.125 145.225)
		(width 0.1)
		(layer "In5.Cu")
		(net 1413)
	)
	(segment
		(start 256.9 147.2)
		(end 256.9 146.7)
		(width 0.1)
		(layer "In7.Cu")
		(net 1413)
	)
	(segment
		(start 255.5 148.6)
		(end 256.9 147.2)
		(width 0.1)
		(layer "In7.Cu")
		(net 1413)
	)
	(segment
		(start 255.5 153.3)
		(end 255.5 148.6)
		(width 0.1)
		(layer "In7.Cu")
		(net 1413)
	)
	(zone
		(net 750)
		(net_name "/DC-DC Converters/VDDR_VTT")
		(layer "F.Cu")
		(hatch edge 0.508)
		(priority 6)
		(connect_pads yes
			(clearance 0.1)
		)
		(min_thickness 0.1)
		(filled_areas_thickness no)
		(fill yes
			(thermal_gap 0.1)
			(thermal_bridge_width 0.2)
		)
		(polygon
			(pts
				(xy 160.35 151.41) (xy 161.6 151.41) (xy 161.6 153.8) (xy 156.2 153.8) (xy 156.2 152.6) (xy 160.35 152.6)
			)
		)
	)
	(zone
		(net 699)
		(net_name "GNDD")
		(layer "F.Cu")
		(hatch edge 0.508)
		(connect_pads yes
			(clearance 0.1)
		)
		(min_thickness 0.254)
		(filled_areas_thickness no)
		(fill yes
			(thermal_gap 0.508)
			(thermal_bridge_width 0.508)
		)
		(polygon
			(pts
				(xy 230 175) (xy 225 175) (xy 225 187.375) (xy 229.625 187.375) (xy 232.5 184.5) (xy 255.5 184.5)
				(xy 255.5 186.5) (xy 257 186.5) (xy 257 183) (xy 256 182) (xy 256 181.5) (xy 255.58 181) (xy 254.5 181)
				(xy 254.5 175.25) (xy 256.25 175.25) (xy 256.25 171) (xy 258.5 171) (xy 258.5 174.5) (xy 256.5 176.5)
				(xy 256.5 179) (xy 258.5 180) (xy 258.5 189.5) (xy 220.5 189.5) (xy 220.5 167.5) (xy 230 167.5)
			)
		)
	)
	(zone
		(net 2)
		(net_name "VCC_USR_A")
		(layer "F.Cu")
		(hatch edge 0.508)
		(priority 10)
		(connect_pads yes
			(clearance 0.1)
		)
		(min_thickness 0.254)
		(filled_areas_thickness no)
		(fill yes
			(thermal_gap 0.508)
			(thermal_bridge_width 0.508)
		)
		(polygon
			(pts
				(xy 211 100.2) (xy 214.6 100.2) (xy 214.6 97) (xy 217.4 97) (xy 217.4 101) (xy 216.6 101.8) (xy 209.2 101.8)
				(xy 209.2 96.8) (xy 211 96.8)
			)
		)
	)
	(zone
		(net 697)
		(net_name "/Power supply/VSS")
		(layer "F.Cu")
		(hatch edge 0.508)
		(priority 2)
		(connect_pads yes
			(clearance 0.1)
		)
		(min_thickness 0.254)
		(filled_areas_thickness no)
		(fill yes
			(thermal_gap 0.508)
			(thermal_bridge_width 0.508)
		)
		(polygon
			(pts
				(xy 254.4 180.8) (xy 250.35 180.8) (xy 250.35 178.8) (xy 254.4 178.8)
			)
		)
	)
	(zone
		(net 743)
		(net_name "/DC-DC Converters/1V7")
		(layer "F.Cu")
		(hatch edge 0.508)
		(priority 5)
		(connect_pads yes
			(clearance 0.1)
		)
		(min_thickness 0.254)
		(filled_areas_thickness no)
		(fill yes
			(thermal_gap 0.508)
			(thermal_bridge_width 0.508)
		)
		(polygon
			(pts
				(xy 153.7 170.8) (xy 153 170.8) (xy 153 172.5) (xy 150.5 172.5) (xy 150.5 169.7) (xy 153.7 169.7)
			)
		)
	)
	(zone
		(net 733)
		(net_name "/DC-DC Converters/MGTAVCC_local")
		(layer "F.Cu")
		(hatch edge 0.508)
		(priority 1)
		(connect_pads yes
			(clearance 0.1)
		)
		(min_thickness 0.254)
		(filled_areas_thickness no)
		(fill yes
			(thermal_gap 0.508)
			(thermal_bridge_width 0.508)
		)
		(polygon
			(pts
				(xy 159.15 163) (xy 158.05 163) (xy 158.05 166.4) (xy 157.85 166.7) (xy 157.85 168.4) (xy 156.55 168.4)
				(xy 156.55 166.8) (xy 153.35 165.1) (xy 153.35 164) (xy 152.85 164) (xy 152.85 161.6) (xy 159.15 161.6)
			)
		)
	)
	(zone
		(net 25)
		(net_name "+1V35")
		(layer "F.Cu")
		(hatch edge 0.508)
		(priority 3)
		(connect_pads
			(clearance 0.1)
		)
		(min_thickness 0.1)
		(filled_areas_thickness no)
		(fill yes
			(thermal_gap 0.1)
			(thermal_bridge_width 0.2)
		)
		(polygon
			(pts
				(xy 174.6 151.1) (xy 162.8 151.1) (xy 162.8 149.7) (xy 161.7 149.7) (xy 161.7 148.6) (xy 166.4 148.6)
				(xy 166.4 147.2) (xy 174.6 147.2)
			)
		)
	)
	(zone
		(net 700)
		(net_name "/Power supply/USB_PD_VBUS")
		(layer "F.Cu")
		(name "USB_DBG_PD.VBUS")
		(hatch edge 0.508)
		(priority 1)
		(connect_pads
			(clearance 0.25)
		)
		(min_thickness 0.1)
		(filled_areas_thickness no)
		(fill yes
			(thermal_gap 0.1)
			(thermal_bridge_width 0.5)
		)
		(polygon
			(pts
				(xy 225.2 158.4) (xy 221.75 158.4) (xy 221.75 156) (xy 225.2 156)
			)
		)
	)
	(zone
		(net 745)
		(net_name "/DC-DC Converters/1V0_BS")
		(layer "F.Cu")
		(hatch edge 0.508)
		(connect_pads yes
			(clearance 0.1)
		)
		(min_thickness 0.254)
		(filled_areas_thickness no)
		(fill yes
			(thermal_gap 0.508)
			(thermal_bridge_width 0.508)
		)
		(polygon
			(pts
				(xy 197.6 164.5) (xy 195.9 164.5) (xy 195.9 163.1) (xy 195.1 163.1) (xy 195.1 162.1) (xy 197.6 162.1)
			)
		)
	)
	(zone
		(net 650)
		(net_name "+1V0")
		(layer "F.Cu")
		(hatch edge 0.508)
		(connect_pads yes
			(clearance 0.1)
		)
		(min_thickness 0.254)
		(filled_areas_thickness no)
		(fill yes
			(thermal_gap 0.508)
			(thermal_bridge_width 0.508)
		)
		(polygon
			(pts
				(xy 197 151) (xy 198.5 151) (xy 198.5 147.5) (xy 201 147.5) (xy 201 151) (xy 203.5 151) (xy 203.5 147.5)
				(xy 206.5 147.5) (xy 206.5 155) (xy 203.5 155) (xy 203.5 153.8) (xy 200 153.8) (xy 200 153.2) (xy 196 153.2)
				(xy 196 151) (xy 193.5 151) (xy 193.5 147.5) (xy 197 147.5)
			)
		)
	)
	(zone
		(net 743)
		(net_name "/DC-DC Converters/1V7")
		(layer "F.Cu")
		(hatch edge 0.508)
		(priority 6)
		(connect_pads yes
			(clearance 0.1)
		)
		(min_thickness 0.1)
		(filled_areas_thickness no)
		(fill yes
			(thermal_gap 0.1)
			(thermal_bridge_width 0.2)
		)
		(polygon
			(pts
				(xy 156.4 138.8) (xy 156.4 142.2) (xy 154.8 142.2) (xy 154.8 138.8)
			)
		)
	)
	(zone
		(net 698)
		(net_name "/Power supply/VDD")
		(layer "F.Cu")
		(hatch edge 0.508)
		(priority 1)
		(connect_pads yes
			(clearance 0.5)
		)
		(min_thickness 0.254)
		(filled_areas_thickness no)
		(fill yes
			(thermal_gap 0.508)
			(thermal_bridge_width 0.508)
		)
		(polygon
			(pts
				(xy 248.75 181.25) (xy 255.75 181.25) (xy 255.75 184.25) (xy 232.5 184.25) (xy 229.75 187) (xy 226.5 187)
				(xy 226.5 181.75) (xy 229.5 178.75) (xy 247 178.75) (xy 247 174) (xy 248.75 174)
			)
		)
	)
	(zone
		(net 737)
		(net_name "/DC-DC Converters/1V2_local")
		(layer "F.Cu")
		(hatch edge 0.508)
		(priority 2)
		(connect_pads yes
			(clearance 0.1)
		)
		(min_thickness 0.254)
		(filled_areas_thickness no)
		(fill yes
			(thermal_gap 0.508)
			(thermal_bridge_width 0.508)
		)
		(polygon
			(pts
				(xy 163.8 172.6) (xy 166.9 172.6) (xy 166.9 176.2) (xy 162.5 176.2) (xy 162.5 175.5) (xy 161.6 174.6)
				(xy 161.6 172.1) (xy 163.3 172.1)
			)
		)
	)
	(zone
		(net 697)
		(net_name "/Power supply/VSS")
		(layer "F.Cu")
		(hatch edge 0.508)
		(priority 2)
		(connect_pads yes
			(clearance 0.1)
		)
		(min_thickness 0.254)
		(filled_areas_thickness no)
		(fill yes
			(thermal_gap 0.508)
			(thermal_bridge_width 0.508)
		)
		(polygon
			(pts
				(xy 248.8 173.5) (xy 247.05 173.5) (xy 247.05 171.5) (xy 248.8 171.5)
			)
		)
	)
	(zone
		(net 704)
		(net_name "/Power supply/USB_DBG_PD.VBUS")
		(layer "F.Cu")
		(name "USB_DBG_PD.VBUS")
		(hatch edge 0.508)
		(priority 10)
		(connect_pads yes
			(clearance 0.1)
		)
		(min_thickness 0.1)
		(filled_areas_thickness no)
		(fill yes
			(thermal_gap 0.1)
			(thermal_bridge_width 0.5)
		)
		(polygon
			(pts
				(xy 235.5 158.5) (xy 232.1 158.5) (xy 232.1 155.9) (xy 235.5 155.9)
			)
		)
	)
	(zone
		(net 697)
		(net_name "/Power supply/VSS")
		(layer "F.Cu")
		(hatch edge 0.508)
		(priority 2)
		(connect_pads yes
			(clearance 0.1)
		)
		(min_thickness 0.254)
		(filled_areas_thickness no)
		(fill yes
			(thermal_gap 0.508)
			(thermal_bridge_width 0.508)
		)
		(polygon
			(pts
				(xy 247 180.25) (xy 245.25 180.25) (xy 245.25 178.4) (xy 247 178.4)
			)
		)
	)
	(zone
		(net 6)
		(net_name "+1V0_MGTAVCC")
		(layer "F.Cu")
		(hatch edge 0.508)
		(priority 5)
		(connect_pads yes
			(clearance 0.1)
		)
		(min_thickness 0.254)
		(filled_areas_thickness no)
		(fill yes
			(thermal_gap 0.508)
			(thermal_bridge_width 0.508)
		)
		(polygon
			(pts
				(xy 157.2 158.5) (xy 157.2 161.7) (xy 152.6 161.7) (xy 152.6 158.5)
			)
		)
	)
	(zone
		(net 7)
		(net_name "+0V675_VTT")
		(layer "F.Cu")
		(hatch edge 0.508)
		(priority 3)
		(connect_pads yes
			(clearance 0.1)
		)
		(min_thickness 0.1)
		(filled_areas_thickness no)
		(fill yes
			(thermal_gap 0.1)
			(thermal_bridge_width 0.2)
		)
		(polygon
			(pts
				(xy 164.1 154) (xy 161.9 154) (xy 161.9 151.7) (xy 164.1 151.7)
			)
		)
	)
	(zone
		(net 26)
		(net_name "+1V8")
		(layer "F.Cu")
		(hatch edge 0.508)
		(priority 5)
		(connect_pads yes
			(clearance 0.1)
		)
		(min_thickness 0.254)
		(filled_areas_thickness no)
		(fill yes
			(thermal_gap 0.508)
			(thermal_bridge_width 0.508)
		)
		(polygon
			(pts
				(xy 164.9 158.3) (xy 164.9 161.3) (xy 160.5 161.3) (xy 160.5 158.3)
			)
		)
	)
	(zone
		(net 740)
		(net_name "/DC-DC Converters/1V35_local")
		(layer "F.Cu")
		(hatch edge 0.508)
		(priority 2)
		(connect_pads yes
			(clearance 0.1)
		)
		(min_thickness 0.254)
		(filled_areas_thickness no)
		(fill yes
			(thermal_gap 0.508)
			(thermal_bridge_width 0.508)
		)
		(polygon
			(pts
				(xy 171.4 172.6) (xy 168.3 172.6) (xy 168.3 174.9) (xy 169.45 174.9) (xy 169.45 176.2) (xy 172.7 176.2)
				(xy 172.7 175.5) (xy 173.6 174.6) (xy 173.6 172.1) (xy 171.9 172.1)
			)
		)
	)
	(zone
		(net 25)
		(net_name "+1V35")
		(layer "F.Cu")
		(hatch edge 0.508)
		(priority 3)
		(connect_pads
			(clearance 0.1)
		)
		(min_thickness 0.1)
		(filled_areas_thickness no)
		(fill yes
			(thermal_gap 0.1)
			(thermal_bridge_width 0.2)
		)
		(polygon
			(pts
				(xy 169.5 139.7) (xy 169.5 141) (xy 174.7 141) (xy 174.7 143.3) (xy 164.8 143.3) (xy 164.8 139.7)
				(xy 168.5 139.7) (xy 168.5 138.8) (xy 169.5 138.8)
			)
		)
	)
	(zone
		(net 1)
		(net_name "GND")
		(layer "F.Cu")
		(hatch edge 0.508)
		(connect_pads
			(clearance 0.1)
		)
		(min_thickness 0.254)
		(filled_areas_thickness no)
		(fill yes
			(thermal_gap 0.508)
			(thermal_bridge_width 0.508)
		)
		(polygon
			(pts
				(xy 193 104.25) (xy 189.5 107.75) (xy 186.275 107.75) (xy 184 105.475) (xy 184 86.25) (xy 193 86.25)
			)
		)
	)
	(zone
		(net 703)
		(net_name "+5V")
		(layer "F.Cu")
		(hatch edge 0.508)
		(priority 1)
		(connect_pads yes
			(clearance 0.1)
		)
		(min_thickness 0.254)
		(filled_areas_thickness no)
		(fill yes
			(thermal_gap 0.508)
			(thermal_bridge_width 0.508)
		)
		(polygon
			(pts
				(xy 183.9 172.5) (xy 182.25 172.5) (xy 182.25 171.25) (xy 182.75 170.5) (xy 182.75 169.5) (xy 183.9 169.5)
			)
		)
	)
	(zone
		(net 956)
		(net_name "/DC-DC Converters/POE_DC")
		(layer "F.Cu")
		(hatch edge 0.508)
		(priority 1)
		(connect_pads yes
			(clearance 0.1)
		)
		(min_thickness 0.254)
		(filled_areas_thickness no)
		(fill yes
			(thermal_gap 0.508)
			(thermal_bridge_width 0.508)
		)
		(polygon
			(pts
				(xy 197.75 179.75) (xy 201.75 179.75) (xy 201.75 187.25) (xy 197.5 187.25) (xy 197.5 183.75) (xy 194.75 183.75)
				(xy 192.5 181.5) (xy 189.75 181.5) (xy 189.75 176.75) (xy 197.75 176.75)
			)
		)
	)
	(zone
		(net 702)
		(net_name "VDC")
		(layer "F.Cu")
		(hatch edge 0.508)
		(priority 1)
		(connect_pads yes
			(clearance 0.1)
		)
		(min_thickness 0.254)
		(filled_areas_thickness no)
		(fill yes
			(thermal_gap 0.508)
			(thermal_bridge_width 0.508)
		)
		(polygon
			(pts
				(xy 195 163.1) (xy 193.4 163.1) (xy 193.4 164.5) (xy 192.1 164.5) (xy 192.1 167.2) (xy 190.3 167.2)
				(xy 190.3 170.3) (xy 188.8 170.3) (xy 188.8 190) (xy 184.45 190) (xy 184.45 183.1) (xy 159 183.1)
				(xy 159 173.3) (xy 160.9 173.3) (xy 160.9 176.2) (xy 167.5 176.2) (xy 167.5 179.3) (xy 176 179.3)
				(xy 176 173.3) (xy 178 173.3) (xy 178 176.3) (xy 184 176.3) (xy 184 166.5) (xy 184.8 166.5) (xy 184.8 164.7)
				(xy 186.8 164.7) (xy 186.8 161.7) (xy 195 161.7)
			)
		)
	)
	(zone
		(net 704)
		(net_name "/Power supply/USB_DBG_PD.VBUS")
		(layer "F.Cu")
		(name "USB_DBG_PD.VBUS")
		(hatch edge 0.508)
		(priority 10)
		(connect_pads yes
			(clearance 0.1)
		)
		(min_thickness 0.1)
		(filled_areas_thickness no)
		(fill yes
			(thermal_gap 0.1)
			(thermal_bridge_width 0.5)
		)
		(polygon
			(pts
				(xy 264.7 149.6) (xy 259 149.6) (xy 259 147.6) (xy 257.15 147.6) (xy 257.15 143.75) (xy 259.125 143.75)
				(xy 260.475 142.4) (xy 261.1 142.4) (xy 262.7 142.4) (xy 264.7 142.4)
			)
		)
	)
	(zone
		(net 697)
		(net_name "/Power supply/VSS")
		(layer "F.Cu")
		(hatch edge 0.508)
		(priority 2)
		(connect_pads yes
			(clearance 0.1)
		)
		(min_thickness 0.254)
		(filled_areas_thickness no)
		(fill yes
			(thermal_gap 0.508)
			(thermal_bridge_width 0.508)
		)
		(polygon
			(pts
				(xy 239 180.25) (xy 237.25 180.25) (xy 237.25 178.4) (xy 239 178.4)
			)
		)
	)
	(zone
		(net 1)
		(net_name "GND")
		(layer "F.Cu")
		(hatch edge 0.508)
		(priority 2)
		(connect_pads yes
			(clearance 0.1)
		)
		(min_thickness 0.254)
		(filled_areas_thickness no)
		(fill yes
			(thermal_gap 0.508)
			(thermal_bridge_width 0.508)
		)
		(polygon
			(pts
				(xy 195.75 161.75) (xy 186.75 161.75) (xy 186.75 158.75) (xy 190.75 158.75) (xy 190.75 157.75) (xy 194.25 154.25)
				(xy 194.25 151) (xy 195.75 151)
			)
		)
	)
	(zone
		(net 1)
		(net_name "GND")
		(layer "F.Cu")
		(name "GND")
		(hatch edge 0.508)
		(connect_pads yes
			(clearance 0.1)
		)
		(min_thickness 0.254)
		(filled_areas_thickness no)
		(fill yes
			(thermal_gap 0.508)
			(thermal_bridge_width 0.508)
		)
		(polygon
			(pts
				(xy 170.3 169.89) (xy 165.03 169.89) (xy 165.03 158.32) (xy 170.3 158.32)
			)
		)
	)
	(zone
		(net 25)
		(net_name "+1V35")
		(layer "F.Cu")
		(hatch edge 0.508)
		(priority 3)
		(connect_pads yes
			(clearance 0.1)
		)
		(min_thickness 0.254)
		(filled_areas_thickness no)
		(fill yes
			(thermal_gap 0.508)
			(thermal_bridge_width 0.508)
		)
		(polygon
			(pts
				(xy 170 172.5) (xy 168.3 172.5) (xy 168.3 175) (xy 169.4 175) (xy 169.4 176.2) (xy 166.9 176.2)
				(xy 166.9 172.5) (xy 167.5 171.9) (xy 167.5 169.9) (xy 170 169.9)
			)
		)
	)
	(zone
		(net 739)
		(net_name "/DC-DC Converters/5V_local")
		(layer "F.Cu")
		(hatch edge 0.508)
		(priority 2)
		(connect_pads yes
			(clearance 0.1)
		)
		(min_thickness 0.254)
		(filled_areas_thickness no)
		(fill yes
			(thermal_gap 0.508)
			(thermal_bridge_width 0.508)
		)
		(polygon
			(pts
				(xy 180.8 172.6) (xy 183.9 172.6) (xy 183.9 176.2) (xy 179.5 176.2) (xy 179.5 175.5) (xy 178.6 174.6)
				(xy 178.6 172.1) (xy 180.3 172.1)
			)
		)
	)
	(zone
		(net 751)
		(net_name "/DC-DC Converters/1V0_REG")
		(layer "F.Cu")
		(hatch edge 0.508)
		(priority 6)
		(connect_pads yes
			(clearance 0.1)
		)
		(min_thickness 0.254)
		(filled_areas_thickness no)
		(fill yes
			(thermal_gap 0.508)
			(thermal_bridge_width 0.508)
		)
		(polygon
			(pts
				(xy 202.9 158.1) (xy 198 158.1) (xy 197.2 158.9) (xy 195.8 158.9) (xy 195.8 153.4) (xy 199.9 153.4)
				(xy 199.9 153.9) (xy 202.9 153.9)
			)
		)
	)
	(zone
		(net 703)
		(net_name "+5V")
		(layer "F.Cu")
		(hatch edge 0.508)
		(priority 2)
		(connect_pads yes
			(clearance 0.1)
		)
		(min_thickness 0.254)
		(filled_areas_thickness no)
		(fill yes
			(thermal_gap 0.508)
			(thermal_bridge_width 0.508)
		)
		(polygon
			(pts
				(xy 244.8 118.2) (xy 244.4 118.2) (xy 244.4 119.6) (xy 242 119.6) (xy 242 118.4) (xy 243 118.4)
				(xy 243 116.8) (xy 244.8 116.8)
			)
		)
	)
	(zone
		(net 727)
		(net_name "+1V2")
		(layer "F.Cu")
		(hatch edge 0.508)
		(priority 3)
		(connect_pads yes
			(clearance 0.1)
		)
		(min_thickness 0.254)
		(filled_areas_thickness no)
		(fill yes
			(thermal_gap 0.508)
			(thermal_bridge_width 0.508)
		)
		(polygon
			(pts
				(xy 218.5 97) (xy 214.5 97) (xy 214.5 84) (xy 218.5 84)
			)
		)
	)
	(zone
		(net 703)
		(net_name "+5V")
		(layer "F.Cu")
		(hatch edge 0.508)
		(priority 2)
		(connect_pads
			(clearance 0.1)
		)
		(min_thickness 0.254)
		(filled_areas_thickness no)
		(fill yes
			(thermal_gap 0.508)
			(thermal_bridge_width 0.508)
		)
		(polygon
			(pts
				(xy 255 123.625) (xy 252.5 123.625) (xy 252.5 119.5) (xy 255 119.5)
			)
		)
	)
	(zone
		(net 24)
		(net_name "+3V3")
		(layer "F.Cu")
		(hatch edge 0.508)
		(priority 1)
		(connect_pads yes
			(clearance 0.1)
		)
		(min_thickness 0.254)
		(filled_areas_thickness no)
		(fill yes
			(thermal_gap 0.508)
			(thermal_bridge_width 0.508)
		)
		(polygon
			(pts
				(xy 211 96.75) (xy 207.75 96.75) (xy 207.75 90.5) (xy 207.25 90.5) (xy 204 85.25) (xy 204 83) (xy 211 83)
			)
		)
	)
	(zone
		(net 26)
		(net_name "+1V8")
		(layer "F.Cu")
		(hatch edge 0.508)
		(priority 2)
		(connect_pads yes
			(clearance 0.1)
		)
		(min_thickness 0.254)
		(filled_areas_thickness no)
		(fill yes
			(thermal_gap 0.508)
			(thermal_bridge_width 0.508)
		)
		(polygon
			(pts
				(xy 212 88.25) (xy 214.5 88.25) (xy 214.5 100.25) (xy 211 100.25) (xy 211 84.9) (xy 212 84.9)
			)
		)
	)
	(zone
		(net 5)
		(net_name "/Power supply/PD_VBUS")
		(layer "F.Cu")
		(name "PD_VBUS")
		(hatch edge 0.508)
		(connect_pads yes
			(clearance 0.25)
		)
		(min_thickness 0.1)
		(filled_areas_thickness no)
		(fill yes
			(thermal_gap 0.1)
			(thermal_bridge_width 0.5)
		)
		(polygon
			(pts
				(xy 230.35 158.5) (xy 226.65 158.5) (xy 226.65 155.95) (xy 230.35 155.95)
			)
		)
	)
	(zone
		(net 24)
		(net_name "+3V3")
		(layer "F.Cu")
		(hatch edge 0.508)
		(priority 2)
		(connect_pads yes
			(clearance 0.1)
		)
		(min_thickness 0.254)
		(filled_areas_thickness no)
		(fill yes
			(thermal_gap 0.508)
			(thermal_bridge_width 0.508)
		)
		(polygon
			(pts
				(xy 178.7 161.5) (xy 177.2 161.5) (xy 177.2 163) (xy 175.1 163) (xy 175.1 161.5) (xy 173.6 161.5)
				(xy 173.6 159.4) (xy 178.7 159.4)
			)
		)
	)
	(zone
		(net 727)
		(net_name "+1V2")
		(layer "F.Cu")
		(hatch edge 0.508)
		(priority 5)
		(connect_pads yes
			(clearance 0.1)
		)
		(min_thickness 0.254)
		(filled_areas_thickness no)
		(fill yes
			(thermal_gap 0.508)
			(thermal_bridge_width 0.508)
		)
		(polygon
			(pts
				(xy 167.4 171.9) (xy 166.8 172.5) (xy 165.3 172.5) (xy 165.3 171.4) (xy 165.5 171.4) (xy 165.5 169.9)
				(xy 167.4 169.9)
			)
		)
	)
	(zone
		(net 4)
		(net_name "/Power supply/DC_IN")
		(layer "F.Cu")
		(hatch edge 0.508)
		(priority 1)
		(connect_pads yes
			(clearance 0.1)
		)
		(min_thickness 0.254)
		(filled_areas_thickness no)
		(fill yes
			(thermal_gap 0.508)
			(thermal_bridge_width 0.508)
		)
		(polygon
			(pts
				(xy 194 189.5) (xy 190 189.5) (xy 190 184.25) (xy 192.5 184.25) (xy 192.5 186) (xy 194 186)
			)
		)
	)
	(zone
		(net 734)
		(net_name "/DC-DC Converters/1V8_local")
		(layer "F.Cu")
		(hatch edge 0.508)
		(priority 1)
		(connect_pads yes
			(clearance 0.1)
		)
		(min_thickness 0.254)
		(filled_areas_thickness no)
		(fill yes
			(thermal_gap 0.508)
			(thermal_bridge_width 0.508)
		)
		(polygon
			(pts
				(xy 159.3 163) (xy 160.3 163) (xy 160.3 166.4) (xy 160.5 166.7) (xy 160.5 168.4) (xy 161.8 168.4)
				(xy 161.8 166.8) (xy 165 165.1) (xy 165 161.6) (xy 159.3 161.6)
			)
		)
	)
	(zone
		(net 1)
		(net_name "GND")
		(layer "F.Cu")
		(hatch edge 0.508)
		(priority 3)
		(connect_pads yes
			(clearance 0.1)
		)
		(min_thickness 0.1)
		(filled_areas_thickness no)
		(fill yes
			(thermal_gap 0.1)
			(thermal_bridge_width 0.2)
		)
		(polygon
			(pts
				(xy 153.2 154.8) (xy 153.2 154.5) (xy 153.5 154.5) (xy 154.2 153.8) (xy 154.2 152) (xy 156.1 152)
				(xy 156.1 153.8) (xy 156.3 153.8) (xy 161.4 153.8) (xy 161.4 155.7) (xy 156.2 155.7) (xy 156.2 158.5)
				(xy 154.2 158.5) (xy 154.2 154.5) (xy 153.5 154.5)
			)
		)
	)
	(zone
		(net 738)
		(net_name "/DC-DC Converters/1V7_local")
		(layer "F.Cu")
		(hatch edge 0.508)
		(priority 2)
		(connect_pads yes
			(clearance 0.1)
		)
		(min_thickness 0.254)
		(filled_areas_thickness no)
		(fill yes
			(thermal_gap 0.508)
			(thermal_bridge_width 0.508)
		)
		(polygon
			(pts
				(xy 154.5 172.6) (xy 151.4 172.6) (xy 151.4 176.2) (xy 155.8 176.2) (xy 155.8 175.5) (xy 156.7 174.6)
				(xy 156.7 172.1) (xy 155 172.1)
			)
		)
	)
	(zone
		(net 735)
		(net_name "/DC-DC Converters/3V3_local")
		(layer "F.Cu")
		(hatch edge 0.508)
		(priority 1)
		(connect_pads yes
			(clearance 0.1)
		)
		(min_thickness 0.254)
		(filled_areas_thickness no)
		(fill yes
			(thermal_gap 0.508)
			(thermal_bridge_width 0.508)
		)
		(polygon
			(pts
				(xy 175 166.4) (xy 174.8 166.7) (xy 174.8 168.4) (xy 173.5 168.4) (xy 173.5 166.8) (xy 170.3 165.1)
				(xy 170.3 159.4) (xy 175 159.4)
			)
		)
	)
	(zone
		(net 746)
		(net_name "/DC-DC Converters/1V0_SW")
		(layer "F.Cu")
		(hatch edge 0.508)
		(priority 4)
		(connect_pads yes
			(clearance 0.1)
		)
		(min_thickness 0.254)
		(filled_areas_thickness no)
		(fill yes
			(thermal_gap 0.508)
			(thermal_bridge_width 0.508)
		)
		(polygon
			(pts
				(xy 202.9 164.5) (xy 197.6 164.5) (xy 197.6 162.1) (xy 194.5 162.1) (xy 194.5 161.6) (xy 194.9 161.6)
				(xy 194.9 160.6) (xy 195.8 160.6) (xy 195.801513 158.900012) (xy 197.2 158.909931) (xy 198 158.1)
				(xy 202.9 158.1)
			)
		)
	)
	(zone
		(net 1)
		(net_name "GND")
		(layer "F.Cu")
		(hatch edge 0.508)
		(connect_pads yes
			(clearance 0.1)
		)
		(min_thickness 0.254)
		(filled_areas_thickness no)
		(fill yes
			(thermal_gap 0.508)
			(thermal_bridge_width 0.508)
		)
		(polygon
			(pts
				(xy 160.25 165) (xy 164.65 165) (xy 164.65 171.3) (xy 165.25 171.3) (xy 165.25 172.6) (xy 163.45 172.6)
				(xy 163.45 175) (xy 158.95 175) (xy 158.95 179.2) (xy 154.75 179.2) (xy 154.75 176.2) (xy 155.45 176.2)
				(xy 155.45 172.6) (xy 153.15 172.6) (xy 153.15 170.8) (xy 153.75 170.8) (xy 153.75 165.4) (xy 158.15 165.4)
				(xy 158.15 163.1) (xy 160.25 163.1)
			)
		)
	)
	(zone
		(net 1)
		(net_name "GND")
		(layer "F.Cu")
		(hatch edge 0.508)
		(connect_pads yes
			(clearance 0.1)
		)
		(min_thickness 0.254)
		(filled_areas_thickness no)
		(fill yes
			(thermal_gap 0.508)
			(thermal_bridge_width 0.508)
		)
		(polygon
			(pts
				(xy 177.2 165.2) (xy 181.6 165.2) (xy 181.6 171.3) (xy 182.2 171.3) (xy 182.2 172.6) (xy 180.4 172.6)
				(xy 180.4 175) (xy 175.9 175) (xy 175.9 179.2) (xy 167.6 179.2) (xy 167.6 176.2) (xy 172.4 176.2)
				(xy 172.4 172.6) (xy 170.1 172.6) (xy 170.1 170.8) (xy 170.7 170.8) (xy 170.7 165.2) (xy 175.1 165.2)
				(xy 175.1 163.1) (xy 177.2 163.1)
			)
		)
	)
	(zone
		(net 736)
		(net_name "/DC-DC Converters/3V3_local_2")
		(layer "F.Cu")
		(hatch edge 0.508)
		(priority 1)
		(connect_pads yes
			(clearance 0.1)
		)
		(min_thickness 0.254)
		(filled_areas_thickness no)
		(fill yes
			(thermal_gap 0.508)
			(thermal_bridge_width 0.508)
		)
		(polygon
			(pts
				(xy 177.3 166.4) (xy 177.5 166.7) (xy 177.5 168.4) (xy 178.8 168.4) (xy 178.8 166.8) (xy 182 165.1)
				(xy 182 159.4) (xy 177.3 159.4)
			)
		)
	)
	(zone
		(net 748)
		(net_name "/DC-DC Converters/MGTAVTT_OUT")
		(layer "F.Cu")
		(hatch edge 0.508)
		(priority 6)
		(connect_pads yes
			(clearance 0.1)
		)
		(min_thickness 0.1)
		(filled_areas_thickness no)
		(fill yes
			(thermal_gap 0.1)
			(thermal_bridge_width 0.2)
		)
		(polygon
			(pts
				(xy 153 140.2) (xy 153.4 140.2) (xy 153.4 141.8) (xy 152 141.8) (xy 152 140.8) (xy 150.6 140.8)
				(xy 150.6 138.8) (xy 153 138.8)
			)
		)
	)
	(zone
		(net 0)
		(net_name "")
		(layers "F.Cu" "B.Cu" "In1.Cu" "In2.Cu" "In3.Cu" "In4.Cu" "In5.Cu" "In6.Cu"
			"In7.Cu" "In8.Cu"
		)
		(name "USB_DBG_PD.VBUS")
		(hatch edge 0.508)
		(connect_pads yes
			(clearance 0)
		)
		(min_thickness 0.1)
		(filled_areas_thickness no)
		(keepout
			(tracks allowed)
			(vias allowed)
			(pads allowed)
			(copperpour not_allowed)
			(footprints allowed)
		)
		(placement
			(enabled no)
			(sheetname "")
		)
		(fill
			(thermal_gap 0.1)
			(thermal_bridge_width 0.5)
		)
		(polygon
			(pts
				(xy 162.4 176.8) (xy 161.85 176.8) (xy 161.85 176.2) (xy 162.4 176.2)
			)
		)
	)
	(zone
		(net 0)
		(net_name "")
		(layers "F.Cu" "B.Cu" "In1.Cu" "In2.Cu" "In3.Cu" "In4.Cu" "In5.Cu" "In6.Cu"
			"In7.Cu" "In8.Cu"
		)
		(name "USB_DBG_PD.VBUS")
		(hatch edge 0.508)
		(connect_pads yes
			(clearance 0)
		)
		(min_thickness 0.1)
		(filled_areas_thickness no)
		(keepout
			(tracks allowed)
			(vias allowed)
			(pads allowed)
			(copperpour not_allowed)
			(footprints allowed)
		)
		(placement
			(enabled no)
			(sheetname "")
		)
		(fill
			(thermal_gap 0.1)
			(thermal_bridge_width 0.5)
		)
		(polygon
			(pts
				(xy 154.475 168.1) (xy 153.925 168.1) (xy 153.925 167.5) (xy 154.475 167.5)
			)
		)
	)
	(zone
		(net 0)
		(net_name "")
		(layers "F.Cu" "B.Cu" "In1.Cu" "In2.Cu" "In3.Cu" "In4.Cu" "In5.Cu" "In6.Cu"
			"In7.Cu" "In8.Cu"
		)
		(name "USB_DBG_PD.VBUS")
		(hatch edge 0.508)
		(connect_pads yes
			(clearance 0)
		)
		(min_thickness 0.1)
		(filled_areas_thickness no)
		(keepout
			(tracks allowed)
			(vias allowed)
			(pads allowed)
			(copperpour not_allowed)
			(footprints allowed)
		)
		(placement
			(enabled no)
			(sheetname "")
		)
		(fill
			(thermal_gap 0.1)
			(thermal_bridge_width 0.5)
		)
		(polygon
			(pts
				(xy 242.875 166.875) (xy 242.325 166.875) (xy 242.325 166.275) (xy 242.875 166.275)
			)
		)
	)
	(zone
		(net 700)
		(net_name "/Power supply/USB_PD_VBUS")
		(layers "F.Cu" "In2.Cu")
		(name "USB_DBG_PD.VBUS")
		(hatch edge 0.508)
		(priority 1)
		(connect_pads
			(clearance 0.25)
		)
		(min_thickness 0.1)
		(filled_areas_thickness no)
		(fill yes
			(thermal_gap 0.1)
			(thermal_bridge_width 0.5)
		)
		(polygon
			(pts
				(xy 194 173.55) (xy 191.25 173.55) (xy 191.25 171.15) (xy 194 171.15)
			)
		)
	)
	(zone
		(net 1192)
		(net_name "Net-(F1-Pad1)")
		(layer "B.Cu")
		(hatch edge 0.508)
		(priority 2)
		(connect_pads yes
			(clearance 0.1)
		)
		(min_thickness 0.254)
		(filled_areas_thickness no)
		(fill yes
			(thermal_gap 0.508)
			(thermal_bridge_width 0.508)
		)
		(polygon
			(pts
				(xy 259.75 183) (xy 256.5 183) (xy 256.5 176.5) (xy 258.25 174.75) (xy 259.75 174.75)
			)
		)
	)
	(zone
		(net 702)
		(net_name "VDC")
		(layer "B.Cu")
		(hatch edge 0.508)
		(priority 6)
		(connect_pads yes
			(clearance 0.1)
		)
		(min_thickness 0.1)
		(filled_areas_thickness no)
		(fill yes
			(thermal_gap 0.1)
			(thermal_bridge_width 0.2)
		)
		(polygon
			(pts
				(xy 154.8 137.8) (xy 152 137.8) (xy 152 132.2) (xy 154.8 132.2)
			)
		)
	)
	(zone
		(net 1)
		(net_name "GND")
		(layer "B.Cu")
		(hatch edge 0.508)
		(connect_pads yes
			(clearance 0.1)
		)
		(min_thickness 0.254)
		(filled_areas_thickness no)
		(fill yes
			(thermal_gap 0.508)
			(thermal_bridge_width 0.508)
		)
		(polygon
			(pts
				(xy 167.94 175.5) (xy 153.12 175.5) (xy 153.12 162.5) (xy 167.94 162.5)
			)
		)
	)
	(zone
		(net 1)
		(net_name "GND")
		(layer "B.Cu")
		(hatch edge 0.508)
		(connect_pads yes
			(clearance 0.1)
		)
		(min_thickness 0.254)
		(filled_areas_thickness no)
		(fill yes
			(thermal_gap 0.508)
			(thermal_bridge_width 0.508)
		)
		(polygon
			(pts
				(xy 220.92 169.56) (xy 220.92 178.31) (xy 207.92 178.31) (xy 207.92 169.56)
			)
		)
	)
	(zone
		(net 1)
		(net_name "GND")
		(layer "B.Cu")
		(hatch edge 0.508)
		(priority 4)
		(connect_pads yes
			(clearance 0.1)
		)
		(min_thickness 0.1)
		(filled_areas_thickness no)
		(fill yes
			(thermal_gap 0.1)
			(thermal_bridge_width 0.2)
		)
		(polygon
			(pts
				(xy 162.37 144.4) (xy 157.17 144.4) (xy 157.17 142.7) (xy 162.37 142.7)
			)
		)
	)
	(zone
		(net 7)
		(net_name "+0V675_VTT")
		(layer "B.Cu")
		(hatch edge 0.508)
		(priority 3)
		(connect_pads yes
			(clearance 0.1)
		)
		(min_thickness 0.1)
		(filled_areas_thickness no)
		(fill yes
			(thermal_gap 0.1)
			(thermal_bridge_width 0.2)
		)
		(polygon
			(pts
				(xy 157.1 144.5) (xy 163 144.5) (xy 163.5 145) (xy 163.5 146) (xy 163 146.5) (xy 157.1 146.5) (xy 157.1 149.4)
				(xy 159.6 151.9) (xy 164.1 151.9) (xy 164.1 153.9) (xy 157.6 153.9) (xy 154.1 150.4) (xy 154.1 144.4)
				(xy 157.1 144.4)
			)
		)
	)
	(zone
		(net 1)
		(net_name "GND")
		(layer "B.Cu")
		(hatch edge 0.508)
		(connect_pads yes
			(clearance 0.1)
		)
		(min_thickness 0.254)
		(filled_areas_thickness no)
		(fill yes
			(thermal_gap 0.508)
			(thermal_bridge_width 0.508)
		)
		(polygon
			(pts
				(xy 184.12 175.5) (xy 170.18 175.5) (xy 170.18 162.5) (xy 184.12 162.5)
			)
		)
	)
	(zone
		(net 702)
		(net_name "VDC")
		(layer "B.Cu")
		(hatch edge 0.508)
		(priority 1)
		(connect_pads yes
			(clearance 0.1)
		)
		(min_thickness 0.254)
		(filled_areas_thickness no)
		(fill yes
			(thermal_gap 0.508)
			(thermal_bridge_width 0.508)
		)
		(polygon
			(pts
				(xy 192.75 162) (xy 195.25 162) (xy 195.25 163.25) (xy 193.25 163.25) (xy 193.25 164.5) (xy 192.25 164.5)
				(xy 190.25 162.75) (xy 190.25 161.75) (xy 192.75 161.75)
			)
		)
	)
	(zone
		(net 743)
		(net_name "/DC-DC Converters/1V7")
		(layer "B.Cu")
		(hatch edge 0.508)
		(priority 6)
		(connect_pads yes
			(clearance 0.1)
		)
		(min_thickness 0.1)
		(filled_areas_thickness no)
		(fill yes
			(thermal_gap 0.1)
			(thermal_bridge_width 0.2)
		)
		(polygon
			(pts
				(xy 156.6 142.2) (xy 153 142.2) (xy 153 171.2) (xy 150.4 171.2) (xy 150.4 138.4) (xy 156.6 138.4)
			)
		)
	)
	(zone
		(net 7)
		(net_name "+0V675_VTT")
		(layer "B.Cu")
		(name "+0V675_VTT")
		(hatch edge 0.508)
		(connect_pads yes
			(clearance 0.25)
		)
		(min_thickness 0.1)
		(filled_areas_thickness no)
		(fill yes
			(thermal_gap 0.508)
			(thermal_bridge_width 0.508)
		)
		(polygon
			(pts
				(xy 168.499999 146.049999) (xy 163.499999 146.049999) (xy 163.499999 145.149999) (xy 168.499999 145.149999)
			)
		)
	)
	(zone
		(net 4)
		(net_name "/Power supply/DC_IN")
		(layer "B.Cu")
		(hatch edge 0.508)
		(priority 1)
		(connect_pads yes
			(clearance 0.1)
		)
		(min_thickness 0.254)
		(filled_areas_thickness no)
		(fill yes
			(thermal_gap 0.508)
			(thermal_bridge_width 0.508)
		)
		(polygon
			(pts
				(xy 262 187) (xy 235 187) (xy 232 183.5) (xy 208 183.5) (xy 202 190) (xy 192 190) (xy 192 186) (xy 201 186)
				(xy 206 181) (xy 253.83 181) (xy 253.83 183) (xy 259.75 183) (xy 259.75 181) (xy 262 181)
			)
		)
	)
	(zone
		(net 59)
		(net_name "12P0V")
		(layer "B.Cu")
		(name "USB_DBG_PD.VBUS")
		(hatch edge 0.508)
		(priority 2)
		(connect_pads yes
			(clearance 0.25)
		)
		(min_thickness 0.1)
		(filled_areas_thickness no)
		(fill yes
			(thermal_gap 0.1)
			(thermal_bridge_width 0.5)
		)
		(polygon
			(pts
				(xy 168.2 133.7) (xy 164.15 133.7) (xy 162.85 135) (xy 156.8 135) (xy 156.8 131.9) (xy 151.9 131.9)
				(xy 151.9 125.4) (xy 159.4 125.4) (xy 159.4 132) (xy 164.2 132) (xy 164.2 131) (xy 163.4 131) (xy 163.4 123.2)
				(xy 168.2 123.2)
			)
		)
	)
	(zone
		(net 1)
		(net_name "GND")
		(layer "B.Cu")
		(hatch edge 0.508)
		(connect_pads yes
			(clearance 0.1)
		)
		(min_thickness 0.254)
		(filled_areas_thickness no)
		(fill yes
			(thermal_gap 0.508)
			(thermal_bridge_width 0.508)
		)
		(polygon
			(pts
				(xy 198.25 165.25) (xy 186.5 165.25) (xy 186.5 158.16) (xy 190.72 158.16) (xy 193.01 155.87) (xy 198.25 155.87)
			)
		)
	)
	(zone
		(net 697)
		(net_name "/Power supply/VSS")
		(layer "B.Cu")
		(hatch edge 0.508)
		(priority 2)
		(connect_pads yes
			(clearance 0.1)
		)
		(min_thickness 0.254)
		(filled_areas_thickness no)
		(fill yes
			(thermal_gap 0.508)
			(thermal_bridge_width 0.508)
		)
		(polygon
			(pts
				(xy 256.24 181) (xy 237 181) (xy 237 179) (xy 246 179) (xy 246 171) (xy 250 171) (xy 250 173) (xy 253.69 173)
				(xy 253.69 176.42) (xy 250 176.42) (xy 250 179) (xy 256.24 179)
			)
		)
	)
	(zone
		(net 25)
		(net_name "+1V35")
		(layer "B.Cu")
		(hatch edge 0.508)
		(priority 4)
		(connect_pads yes
			(clearance 0.1)
		)
		(min_thickness 0.1)
		(filled_areas_thickness no)
		(fill yes
			(thermal_gap 0.1)
			(thermal_bridge_width 0.2)
		)
		(polygon
			(pts
				(xy 162.4 149.4) (xy 157.2 149.4) (xy 157.2 146.6) (xy 162.4 146.6)
			)
		)
	)
	(zone
		(net 24)
		(net_name "+3V3")
		(layer "B.Cu")
		(name "USB_DBG_PD.VBUS")
		(hatch edge 0.508)
		(priority 1)
		(connect_pads
			(clearance 0.2)
		)
		(min_thickness 0.1)
		(filled_areas_thickness no)
		(fill yes
			(thermal_gap 0.1)
			(thermal_bridge_width 0.5)
		)
		(polygon
			(pts
				(xy 166 81.2) (xy 156.6 81.5) (xy 156.6 89.7) (xy 166 89.9) (xy 166 114) (xy 168 116) (xy 168 132)
				(xy 152 132) (xy 152 78) (xy 166 78)
			)
		)
	)
	(zone
		(net 650)
		(net_name "+1V0")
		(layers "B.Cu" "In1.Cu")
		(hatch edge 0.508)
		(priority 1)
		(connect_pads yes
			(clearance 0.1)
		)
		(min_thickness 0.12)
		(filled_areas_thickness no)
		(fill yes
			(thermal_gap 0.2)
			(thermal_bridge_width 0.12)
		)
		(polygon
			(pts
				(xy 207.25 127.75) (xy 207.25 155) (xy 193.05 155) (xy 193.05 148.25) (xy 194.01 147.3) (xy 194 143)
				(xy 193 142) (xy 193 125.52) (xy 199.5 125.52) (xy 199.5 123.5) (xy 203 123.5)
			)
		)
	)
	(zone
		(net 1)
		(net_name "GND")
		(layers "In1.Cu" "In4.Cu" "In6.Cu" "In8.Cu")
		(name "GND")
		(hatch edge 0.508)
		(priority 5)
		(connect_pads yes
			(clearance 0.5)
		)
		(min_thickness 0.254)
		(filled_areas_thickness no)
		(fill yes
			(thermal_gap 0.508)
			(thermal_bridge_width 0.508)
		)
		(polygon
			(pts
				(xy 232.3 151.5) (xy 270 151.5) (xy 270 190) (xy 220.5 190) (xy 220.5 167.5) (xy 232.3 167.5)
			)
		)
	)
	(zone
		(net 1)
		(net_name "GND")
		(layers "In1.Cu" "In4.Cu" "In6.Cu" "In8.Cu")
		(hatch edge 0.508)
		(connect_pads yes
			(clearance 0.1)
		)
		(min_thickness 0.1)
		(filled_areas_thickness no)
		(fill yes
			(thermal_gap 0.508)
			(thermal_bridge_width 0.508)
		)
		(polygon
			(pts
				(xy 270 190) (xy 150 190) (xy 150 70) (xy 270 70)
			)
		)
	)
	(zone
		(net 727)
		(net_name "+1V2")
		(layer "In2.Cu")
		(hatch edge 0.508)
		(priority 6)
		(connect_pads yes
			(clearance 0.1)
		)
		(min_thickness 0.254)
		(filled_areas_thickness no)
		(fill yes
			(thermal_gap 0.508)
			(thermal_bridge_width 0.508)
		)
		(polygon
			(pts
				(xy 209 91.5) (xy 210.9 91.5) (xy 210.9 91) (xy 218.7 91) (xy 218.7 93.25) (xy 206 93.25) (xy 206 100)
				(xy 201.7 99.999692) (xy 201.7 98) (xy 199.7 97.999881) (xy 199.7 99.999646) (xy 196.45 99.999535)
				(xy 196.45 89.7) (xy 193 89.7) (xy 193 99.999463) (xy 178.10904 100.01902) (xy 177.917344 128.992838)
				(xy 152.751033 129) (xy 152.75 163.35) (xy 167.65 163.35) (xy 167.65 172.5) (xy 165.25 172.5) (xy 165.25 165.5)
				(xy 150.05 165.5) (xy 150 125) (xy 173 125) (xy 172.989334 86.068445) (xy 199.300039 86.02252) (xy 199.3 88.2)
				(xy 209 88.2)
			)
		)
	)
	(zone
		(net 2)
		(net_name "VCC_USR_A")
		(layer "In2.Cu")
		(hatch edge 0.508)
		(priority 4)
		(connect_pads yes
			(clearance 0.1)
		)
		(min_thickness 0.12)
		(filled_areas_thickness no)
		(fill yes
			(thermal_gap 0.2)
			(thermal_bridge_width 0.12)
		)
		(polygon
			(pts
				(xy 217.25 108) (xy 221 108) (xy 221 127.5) (xy 217.5 127.5) (xy 217.5 122.5) (xy 218 122.5) (xy 218 112)
				(xy 210.45 112) (xy 210.45 101.1) (xy 209.2 101.1) (xy 209.15 95.25) (xy 212 95.25) (xy 212.1 94.85)
				(xy 213.4 94.85) (xy 213.6 95.25) (xy 217.25 95.25)
			)
		)
	)
	(zone
		(net 8)
		(net_name "+1V2_MGTAVTT")
		(layer "In2.Cu")
		(hatch edge 0.508)
		(priority 1)
		(connect_pads yes
			(clearance 0.1)
		)
		(min_thickness 0.254)
		(filled_areas_thickness no)
		(fill yes
			(thermal_gap 0.508)
			(thermal_bridge_width 0.508)
		)
		(polygon
			(pts
				(xy 189.8 128.8) (xy 190.5 129.5) (xy 190.5 132.575) (xy 191.25 133.275) (xy 191.625 133.275) (xy 191.75 133.4)
				(xy 191.75 133.575) (xy 191.6 133.725) (xy 191.275 133.725) (xy 190.5 134.5) (xy 190.5 135.35) (xy 189.85 136)
				(xy 189.5 136) (xy 189.1 136.4) (xy 182.6 136.4) (xy 182.6 111.85) (xy 189.8 111.85)
			)
		)
	)
	(zone
		(net 700)
		(net_name "/Power supply/USB_PD_VBUS")
		(layer "In2.Cu")
		(name "USB_DBG_PD.VBUS")
		(hatch edge 0.508)
		(priority 1)
		(connect_pads
			(clearance 0.25)
		)
		(min_thickness 0.1)
		(filled_areas_thickness no)
		(fill yes
			(thermal_gap 0.1)
			(thermal_bridge_width 0.5)
		)
		(polygon
			(pts
				(xy 224 158.4) (xy 221.75 158.4) (xy 221.75 156) (xy 224 156)
			)
		)
	)
	(zone
		(net 703)
		(net_name "+5V")
		(layer "In2.Cu")
		(hatch edge 0.508)
		(priority 10)
		(connect_pads yes
			(clearance 0.1)
		)
		(min_thickness 0.12)
		(filled_areas_thickness no)
		(fill yes
			(thermal_gap 0.2)
			(thermal_bridge_width 0.12)
		)
		(polygon
			(pts
				(xy 264 138) (xy 255.85 138) (xy 255.85 146) (xy 222 146) (xy 214.8 155) (xy 209.4 155) (xy 209.4 161.6)
				(xy 190.8 161.6) (xy 184 169.2) (xy 184 171) (xy 182.4 171) (xy 182.4 161.6) (xy 188.4 161.6) (xy 188.6 160)
				(xy 197.434398 159.94548) (xy 208 160) (xy 208 153.6) (xy 213.8 153.6) (xy 221.2 143.8) (xy 241.8 143.8)
				(xy 243.4 138.8) (xy 253.4 138.8) (xy 253.4 136.2) (xy 261.8 136.2) (xy 261.8 121) (xy 243 121)
				(xy 243 108.2) (xy 250 108.2) (xy 250 95.4) (xy 255.2 95.4) (xy 255.2 110.2) (xy 264 110.2)
			)
		)
	)
	(zone
		(net 721)
		(net_name "/HDMI + Ethernet/ETH_3V3")
		(layer "In2.Cu")
		(hatch edge 0.508)
		(priority 2)
		(connect_pads
			(clearance 0.3)
		)
		(min_thickness 0.254)
		(filled_areas_thickness no)
		(fill yes
			(thermal_gap 0.508)
			(thermal_bridge_width 0.508)
		)
		(polygon
			(pts
				(xy 262.5 169.75) (xy 248 169.75) (xy 248 175.5) (xy 239 175.5) (xy 239 155) (xy 262.5 155)
			)
		)
	)
	(zone
		(net 24)
		(net_name "+3V3")
		(layer "In2.Cu")
		(hatch edge 0.508)
		(connect_pads yes
			(clearance 0.1)
		)
		(min_thickness 0.254)
		(filled_areas_thickness no)
		(fill yes
			(thermal_gap 0.508)
			(thermal_bridge_width 0.508)
		)
		(polygon
			(pts
				(xy 275 192.5) (xy 145 192.5) (xy 145 67.5) (xy 275 67.5)
			)
		)
	)
	(zone
		(net 24)
		(net_name "+3V3")
		(layer "In2.Cu")
		(name "+3V3")
		(hatch edge 0.508)
		(priority 1)
		(connect_pads yes
			(clearance 0.5)
		)
		(min_thickness 0.254)
		(filled_areas_thickness no)
		(fill yes
			(thermal_gap 0.508)
			(thermal_bridge_width 0.508)
		)
		(polygon
			(pts
				(xy 231.325 152.975) (xy 270 152.975) (xy 270 190) (xy 220.5 190) (xy 220.5 167.5) (xy 231.325 167.5)
			)
		)
	)
	(zone
		(net 8)
		(net_name "+1V2_MGTAVTT")
		(layer "In2.Cu")
		(hatch edge 0.508)
		(priority 10)
		(connect_pads
			(clearance 0.1)
		)
		(min_thickness 0.254)
		(filled_areas_thickness no)
		(fill yes
			(thermal_gap 0.508)
			(thermal_bridge_width 0.508)
		)
		(polygon
			(pts
				(xy 183 134.5) (xy 157 134.5) (xy 157 145) (xy 155 145) (xy 155 132) (xy 183 132)
			)
		)
	)
	(zone
		(net 25)
		(net_name "+1V35")
		(layer "In2.Cu")
		(hatch edge 0.508)
		(priority 6)
		(connect_pads yes
			(clearance 0.1)
		)
		(min_thickness 0.254)
		(filled_areas_thickness no)
		(fill yes
			(thermal_gap 0.508)
			(thermal_bridge_width 0.508)
		)
		(polygon
			(pts
				(xy 182.75 147.5) (xy 175.6 147.5) (xy 175.6 145.25) (xy 163.25 145.25) (xy 163.25 145.75) (xy 174.95 145.75)
				(xy 174.95 149) (xy 175 149) (xy 175 150) (xy 169.8 150) (xy 169.6 150.8) (xy 168.8 150.8) (xy 168.6 150)
				(xy 160.5 150) (xy 160.5 160.5) (xy 170.5 160.5) (xy 170.5 172.5) (xy 167.85 172.5) (xy 167.85 163.1)
				(xy 157.25 163.1) (xy 157.25 134.45) (xy 182.75 134.45)
			)
		)
	)
	(zone
		(net 24)
		(net_name "+3V3")
		(layer "In2.Cu")
		(hatch edge 0.508)
		(priority 2)
		(connect_pads yes
			(clearance 0.1)
		)
		(min_thickness 0.254)
		(filled_areas_thickness no)
		(fill yes
			(thermal_gap 0.508)
			(thermal_bridge_width 0.508)
		)
		(polygon
			(pts
				(xy 207.4 122.3) (xy 203.95 125.75) (xy 203.95 128) (xy 204.5 128.55) (xy 205.05 128.55) (xy 206.05 127.55)
				(xy 218 127.55) (xy 218 147.5) (xy 204.22174 147.5) (xy 204.25 135.7) (xy 200.05 135.7) (xy 200.05 128.55)
				(xy 199.2 127.7) (xy 194.2 127.7) (xy 194.2 130.4) (xy 193.8 130.8) (xy 193.3 130.8) (xy 192.8 130.25)
				(xy 191.4 130.25) (xy 191.25 130.4) (xy 191.25 130.7) (xy 191.6 131.05) (xy 191.6 131.9) (xy 191.2 132.3)
				(xy 191.2 132.65) (xy 191.4 132.85) (xy 192.625 132.85) (xy 192.85 133.075) (xy 192.85 137.2) (xy 191.6 137.2)
				(xy 189.9 137.2) (xy 189.3 136.6) (xy 189.3 136.3) (xy 189.5 136.1) (xy 189.9 136.1) (xy 190.6 135.4)
				(xy 190.6 134.45) (xy 191.275 133.775) (xy 191.625 133.775) (xy 191.8 133.6) (xy 191.8 133.375)
				(xy 191.65 133.225) (xy 191.25 133.225) (xy 190.6 132.575) (xy 190.6 129.6) (xy 192.55 129.6) (xy 192.55 127)
				(xy 192.55 123.4) (xy 192.55 113.6) (xy 192.5 113.5) (xy 192.5 112.6) (xy 193.3 112.6) (xy 193.3 111.85)
				(xy 207.4 111.85)
			)
		)
	)
	(zone
		(net 11)
		(net_name "+0V675_VREF")
		(layer "In2.Cu")
		(hatch edge 0.508)
		(priority 20)
		(connect_pads yes
			(clearance 0.1)
		)
		(min_thickness 0.1)
		(filled_areas_thickness no)
		(fill yes
			(thermal_gap 0.1)
			(thermal_bridge_width 0.2)
		)
		(polygon
			(pts
				(xy 193.8 148) (xy 175.75 148) (xy 175.75 147.5) (xy 192.3 147.5) (xy 192.3 142.75) (xy 191.3 141.75)
				(xy 191.3 139.7) (xy 190.75 139.15) (xy 190.75 138.76) (xy 193.8 138.76)
			)
		)
	)
	(zone
		(net 26)
		(net_name "+1V8")
		(layer "In2.Cu")
		(hatch edge 0.508)
		(priority 5)
		(connect_pads yes
			(clearance 0.1)
		)
		(min_thickness 0.254)
		(filled_areas_thickness no)
		(fill yes
			(thermal_gap 0.508)
			(thermal_bridge_width 0.508)
		)
		(polygon
			(pts
				(xy 201.75 152) (xy 184 152) (xy 173.6 153.65) (xy 173.6 171) (xy 183.9 171) (xy 183.9 169.2) (xy 188.9 169.2)
				(xy 195.5 164.1) (xy 195.5 161.5) (xy 209.5 161.5) (xy 209.5 155) (xy 214.8 155) (xy 222 146) (xy 255.860127 146.038872)
				(xy 255.851471 138.038064) (xy 263.991344 138.000038) (xy 264.021393 110.099894) (xy 255.3 110.1)
				(xy 255 77.5) (xy 204 77.5) (xy 204 84.9) (xy 212.1 84.9) (xy 212.1 88.4) (xy 199.4 88.4) (xy 199.4 74.18)
				(xy 204.5 74.18) (xy 204.5 70.581817) (xy 269.999936 70.173058) (xy 269.900717 105.796229) (xy 269.9 105.699899)
				(xy 269.903761 142.00001) (xy 258.903862 142.000087) (xy 258.906266 150.780558) (xy 225.006266 150.879561)
				(xy 217.9 157.7) (xy 216.5 157.7) (xy 216.5 165.7) (xy 199.1 165.7) (xy 195.7 169.1) (xy 195.7 170.2)
				(xy 194.9 171) (xy 191 171) (xy 191 176.21) (xy 170.6 176.21) (xy 170.6 160.91) (xy 170.4 160.5)
				(xy 160.6 160.5) (xy 160.6 150.13) (xy 175.35 150.15) (xy 175.35 148) (xy 193.85 148) (xy 193.85 147)
				(xy 201.75 147)
			)
		)
	)
	(zone
		(net 6)
		(net_name "+1V0_MGTAVCC")
		(layer "In2.Cu")
		(hatch edge 0.508)
		(priority 2)
		(connect_pads
			(clearance 0.1)
		)
		(min_thickness 0.254)
		(filled_areas_thickness no)
		(fill yes
			(thermal_gap 0.508)
			(thermal_bridge_width 0.508)
		)
		(polygon
			(pts
				(xy 193 112.5) (xy 190 112.5) (xy 190 112) (xy 183 112) (xy 183 132) (xy 155 132) (xy 155 145) (xy 157 145)
				(xy 157 163) (xy 153 163) (xy 153 129) (xy 178 129) (xy 178 106.5) (xy 193 106.5)
			)
		)
	)
	(zone
		(net 3)
		(net_name "VCC_USR_B")
		(layer "In2.Cu")
		(hatch edge 0.508)
		(priority 3)
		(connect_pads yes
			(clearance 0.1)
		)
		(min_thickness 0.12)
		(filled_areas_thickness no)
		(fill yes
			(thermal_gap 0.2)
			(thermal_bridge_width 0.12)
		)
		(polygon
			(pts
				(xy 221.6 91.2) (xy 229.425 91.2) (xy 229.425 93.5) (xy 221.6 93.5) (xy 221.6 95.25) (xy 209.15 95.25)
				(xy 209.15 101.1) (xy 210.45 101.1) (xy 210.45 112.25) (xy 207.5 112.25) (xy 206.0007 100.000384)
				(xy 205.996006 93.255417) (xy 218.745306 93.205033) (xy 218.75 91) (xy 210.9 91) (xy 210.9 91.5)
				(xy 209.05 91.5) (xy 209.05 88.4) (xy 212.1 88.4) (xy 212.1 86) (xy 221.6 86)
			)
		)
	)
	(zone
		(net 3)
		(net_name "VCC_USR_B")
		(layer "In2.Cu")
		(hatch edge 0.508)
		(priority 3)
		(connect_pads yes
			(clearance 0.1)
		)
		(min_thickness 0.254)
		(filled_areas_thickness no)
		(fill yes
			(thermal_gap 0.508)
			(thermal_bridge_width 0.508)
		)
		(polygon
			(pts
				(xy 218 122.4) (xy 207.5 122.4) (xy 207.5 111.85) (xy 218 111.85)
			)
		)
	)
	(zone
		(net 24)
		(net_name "+3V3")
		(layer "In2.Cu")
		(hatch edge 0.508)
		(priority 2)
		(connect_pads yes
			(clearance 0.1)
		)
		(min_thickness 0.254)
		(filled_areas_thickness no)
		(fill yes
			(thermal_gap 0.508)
			(thermal_bridge_width 0.508)
		)
		(polygon
			(pts
				(xy 218 155.5) (xy 208.75 155.5) (xy 202.75 161.5) (xy 173.5 161.5) (xy 173.6 153.65) (xy 184 152)
				(xy 201.85 152) (xy 201.85 147) (xy 218 147)
			)
		)
	)
	(zone
		(net 2)
		(net_name "VCC_USR_A")
		(layer "In2.Cu")
		(hatch edge 0.508)
		(priority 4)
		(connect_pads yes
			(clearance 0.1)
		)
		(min_thickness 0.254)
		(filled_areas_thickness no)
		(fill yes
			(thermal_gap 0.508)
			(thermal_bridge_width 0.508)
		)
		(polygon
			(pts
				(xy 218 127.5) (xy 206 127.5) (xy 205 128.5) (xy 204.7 128.5) (xy 204 127.8) (xy 204 125.9) (xy 207.4 122.5)
				(xy 218 122.5)
			)
		)
	)
	(zone
		(net 25)
		(net_name "+1V35")
		(layer "In2.Cu")
		(hatch edge 0.508)
		(priority 6)
		(connect_pads yes
			(clearance 0.1)
		)
		(min_thickness 0.254)
		(filled_areas_thickness no)
		(fill yes
			(thermal_gap 0.508)
			(thermal_bridge_width 0.508)
		)
		(polygon
			(pts
				(xy 192.848117 138.666215) (xy 190.701048 138.709989) (xy 190.7 139.2) (xy 191.25 139.75) (xy 191.25 141.8)
				(xy 192.2 142.75) (xy 192.2 147.45) (xy 182.55 147.45) (xy 182.55 136.6) (xy 189.1 136.6) (xy 189.8 137.3)
				(xy 192.867069 137.286226)
			)
		)
	)
	(zone
		(net 704)
		(net_name "/Power supply/USB_DBG_PD.VBUS")
		(layer "In2.Cu")
		(name "USB_DBG_PD.VBUS")
		(hatch edge 0.508)
		(priority 10)
		(connect_pads yes
			(clearance 0.3)
		)
		(min_thickness 0.1)
		(filled_areas_thickness no)
		(fill yes
			(thermal_gap 0.1)
			(thermal_bridge_width 0.5)
		)
		(polygon
			(pts
				(xy 264.5 149.1) (xy 262.5 149.1) (xy 262.5 156.9) (xy 239 156.9) (xy 236.625 157.3) (xy 235.425 158.5)
				(xy 232.9 158.5) (xy 232.9 156) (xy 234.3 154.7) (xy 236.27 154.7) (xy 238.91 152.75) (xy 241.49 150.8)
				(xy 259.1 150.8) (xy 259.1 143.2) (xy 264.5 143.2)
			)
		)
	)
	(zone
		(net 6)
		(net_name "+1V0_MGTAVCC")
		(layer "In2.Cu")
		(hatch edge 0.508)
		(priority 6)
		(connect_pads yes
			(clearance 0.1)
		)
		(min_thickness 0.254)
		(filled_areas_thickness no)
		(fill yes
			(thermal_gap 0.508)
			(thermal_bridge_width 0.508)
		)
		(polygon
			(pts
				(xy 192.4 113.5) (xy 192.5 113.6) (xy 192.5 123.5) (xy 192.5 123.8) (xy 192.5 125.05) (xy 192.5 126.8)
				(xy 192.5 126.9) (xy 192.5 129.5) (xy 190.5 129.5) (xy 189.9 128.9) (xy 189.9 111.85) (xy 192.4 111.85)
			)
		)
	)
	(zone
		(net 26)
		(net_name "+1V8")
		(layer "In2.Cu")
		(hatch edge 0.508)
		(priority 5)
		(connect_pads yes
			(clearance 0.1)
		)
		(min_thickness 0.254)
		(filled_areas_thickness no)
		(fill yes
			(thermal_gap 0.508)
			(thermal_bridge_width 0.508)
		)
		(polygon
			(pts
				(xy 204.2 135.75) (xy 204.2 147.45) (xy 193.85 147.45) (xy 193.85 138.66) (xy 192.9 138.66) (xy 192.9 134.2)
				(xy 192.9 133) (xy 192.675001 132.774525) (xy 191.45 132.775) (xy 191.25 132.6) (xy 191.25 132.35)
				(xy 191.65 131.95) (xy 191.65 131.2) (xy 191.25 130.8) (xy 191.25 130.35) (xy 192.75 130.35) (xy 193.25 130.9)
				(xy 193.85 130.9) (xy 194.3 130.45) (xy 194.3 127.75) (xy 199.15 127.75) (xy 200 128.6) (xy 200 135.75)
			)
		)
	)
	(zone
		(net 702)
		(net_name "VDC")
		(layers "In2.Cu" "In7.Cu")
		(hatch edge 0.508)
		(priority 1)
		(connect_pads yes
			(clearance 0.1)
		)
		(min_thickness 0.254)
		(filled_areas_thickness no)
		(fill yes
			(thermal_gap 0.508)
			(thermal_bridge_width 0.508)
		)
		(polygon
			(pts
				(xy 195.5 164.1) (xy 188.8 170.2) (xy 184 170.2) (xy 184 167.5) (xy 185.6 167.5) (xy 191 161.6)
				(xy 195.5 161.5)
			)
		)
	)
	(zone
		(net 24)
		(net_name "+3V3")
		(layer "In3.Cu")
		(hatch edge 0.508)
		(priority 1)
		(connect_pads yes
			(clearance 0.1)
		)
		(min_thickness 0.12)
		(filled_areas_thickness no)
		(fill yes
			(thermal_gap 0.2)
			(thermal_bridge_width 0.12)
		)
		(polygon
			(pts
				(xy 178 161.5) (xy 181.12 166) (xy 181.12 176.5) (xy 182 176.5) (xy 182 178.5) (xy 175.5 178.5)
				(xy 175.5 169.11) (xy 174.5 169.11) (xy 174.5 159.5) (xy 178 159.5)
			)
		)
	)
	(zone
		(net 702)
		(net_name "VDC")
		(layer "In5.Cu")
		(hatch edge 0.508)
		(priority 6)
		(connect_pads yes
			(clearance 0.1)
		)
		(min_thickness 0.1)
		(filled_areas_thickness no)
		(fill yes
			(thermal_gap 0.1)
			(thermal_bridge_width 0.2)
		)
		(polygon
			(pts
				(xy 154.8 179.6) (xy 163.2 179.6) (xy 163.2 183.2) (xy 152 183.2) (xy 152 132.2) (xy 154.8 132.2)
			)
		)
	)
	(zone
		(net 723)
		(net_name "/HDMI + Ethernet/ETH_CONN_SH")
		(layer "In5.Cu")
		(hatch edge 0.508)
		(priority 1)
		(connect_pads yes
			(clearance 0.5)
		)
		(min_thickness 0.254)
		(filled_areas_thickness no)
		(fill yes
			(thermal_gap 0.508)
			(thermal_bridge_width 0.508)
		)
		(polygon
			(pts
				(xy 268 171.5) (xy 234 171.5) (xy 234 151.5) (xy 268 151.5)
			)
		)
	)
	(zone
		(net 1)
		(net_name "GND")
		(layers "In5.Cu" "In7.Cu")
		(name "GND")
		(hatch edge 0.508)
		(connect_pads
			(clearance 0.1)
		)
		(min_thickness 0.254)
		(filled_areas_thickness no)
		(fill yes
			(thermal_gap 0.508)
			(thermal_bridge_width 0.508)
		)
		(polygon
			(pts
				(xy 181.59 179.38) (xy 155.22 179.38) (xy 155.22 159.43) (xy 181.59 159.43)
			)
		)
	)
	(zone
		(net 24)
		(net_name "+3V3")
		(layer "In7.Cu")
		(hatch edge 0.508)
		(priority 2)
		(connect_pads
			(clearance 0.1)
		)
		(min_thickness 0.254)
		(filled_areas_thickness no)
		(fill yes
			(thermal_gap 0.508)
			(thermal_bridge_width 0.508)
		)
		(polygon
			(pts
				(xy 199.5 85.4) (xy 197 88) (xy 197 91.2) (xy 193.5 91.2) (xy 193.5 81.5) (xy 199.5 81.5)
			)
		)
	)
)
